G04 ================== begin FILE IDENTIFICATION RECORD ==================*
G04 Layout Name:  13130-1b.brd*
G04 Film Name:    TSMD*
G04 File Format:  Gerber RS274X*
G04 File Origin:  Cadence Allegro 16.5-S037*
G04 Origin Date:  Thu Nov 13 17:26:31 2014*
G04 *
G04 Layer:  VIA CLASS/PASTEMASK_TOP*
G04 Layer:  PIN/PASTEMASK_TOP*
G04 Layer:  PACKAGE GEOMETRY/PASTEMASK_TOP*
G04 Layer:  DRAWING FORMAT/LAYER_PCB_STORY*
G04 Layer:  DRAWING FORMAT/LAYER_PAST_T*
G04 Layer:  BOARD GEOMETRY/PANEL_OUTLINE*
G04 *
G04 Offset:    (0.00 0.00)*
G04 Mirror:    No*
G04 Mode:      Positive*
G04 Rotation:  0*
G04 FullContactRelief:  No*
G04 UndefLineWidth:     6.00*
G04 ================== end FILE IDENTIFICATION RECORD ====================*
%FSLAX35Y35*MOIN*%
%IR0*IPPOS*OFA0.00000B0.00000*MIA0B0*SFA1.00000B1.00000*%
%AMMACRO27*
4,1,3,-.0125,.025,
.0125,0.0,
-.0125,-.025,
-.0125,.025,
0.0*
%
%ADD27MACRO27*%
%ADD97R,.062X.114*%
%AMMACRO32*
4,1,3,.0125,0.0,
-.0125,-.025,
-.0125,.025,
.0125,0.0,
0.0*
%
%ADD32MACRO32*%
%ADD112R,.114X.062*%
%ADD41R,.03X.008*%
%ADD40R,.008X.03*%
%ADD82C,.012*%
%AMMACRO15*
4,1,40,-.009,-.01,
.009,-.01,
.009347,-.00997,
.009684,-.009879,
.01,-.009732,
.010286,-.009532,
.010532,-.009286,
.010732,-.009,
.010879,-.008684,
.01097,-.008347,
.011,-.008,
.011,.008,
.01097,.008347,
.010879,.008684,
.010732,.009,
.010532,.009286,
.010286,.009532,
.01,.009732,
.009684,.009879,
.009347,.00997,
.009,.01,
-.009,.01,
-.009347,.00997,
-.009684,.009879,
-.01,.009732,
-.010286,.009532,
-.010532,.009286,
-.010732,.009,
-.010879,.008684,
-.01097,.008347,
-.011,.008,
-.011,-.008,
-.01097,-.008347,
-.010879,-.008684,
-.010732,-.009,
-.010532,-.009286,
-.010286,-.009532,
-.01,-.009732,
-.009684,-.009879,
-.009347,-.00997,
-.009,-.01,
0.0*
%
%ADD15MACRO15*%
%ADD60R,.08X.136*%
%AMMACRO23*
4,1,40,-.01,.009,
-.01,-.009,
-.00997,-.009347,
-.009879,-.009684,
-.009732,-.01,
-.009532,-.010286,
-.009286,-.010532,
-.009,-.010732,
-.008684,-.010879,
-.008347,-.01097,
-.008,-.011,
.008,-.011,
.008347,-.01097,
.008684,-.010879,
.009,-.010732,
.009286,-.010532,
.009532,-.010286,
.009732,-.01,
.009879,-.009684,
.00997,-.009347,
.01,-.009,
.01,.009,
.00997,.009347,
.009879,.009684,
.009732,.01,
.009532,.010286,
.009286,.010532,
.009,.010732,
.008684,.010879,
.008347,.01097,
.008,.011,
-.008,.011,
-.008347,.01097,
-.008684,.010879,
-.009,.010732,
-.009286,.010532,
-.009532,.010286,
-.009732,.01,
-.009879,.009684,
-.00997,.009347,
-.01,.009,
0.0*
%
%ADD23MACRO23*%
%ADD11C,.04*%
%ADD84C,.015*%
%ADD51R,.047X.108*%
%ADD115R,.026X.008*%
%ADD114R,.008X.026*%
%ADD80C,.016*%
%ADD58R,.037X.164*%
%AMMACRO47*
4,1,40,-.0155,.016,
-.0155,-.016,
-.015439,-.016695,
-.015259,-.017368,
-.014964,-.018,
-.014564,-.018571,
-.014071,-.019064,
-.0135,-.019464,
-.012868,-.019759,
-.012195,-.019939,
-.0115,-.02,
.0115,-.02,
.012195,-.019939,
.012868,-.019759,
.0135,-.019464,
.014071,-.019064,
.014564,-.018571,
.014964,-.018,
.015259,-.017368,
.015439,-.016695,
.0155,-.016,
.0155,.016,
.015439,.016695,
.015259,.017368,
.014964,.018,
.014564,.018571,
.014071,.019064,
.0135,.019464,
.012868,.019759,
.012195,.019939,
.0115,.02,
-.0115,.02,
-.012195,.019939,
-.012868,.019759,
-.0135,.019464,
-.014071,.019064,
-.014564,.018571,
-.014964,.018,
-.015259,.017368,
-.015439,.016695,
-.0155,.016,
0.0*
%
%ADD47MACRO47*%
%ADD37R,.075X.135*%
%ADD119R,.164X.037*%
%AMMACRO18*
4,1,40,.016,.0155,
-.016,.0155,
-.016695,.015439,
-.017368,.015259,
-.018,.014964,
-.018571,.014564,
-.019064,.014071,
-.019464,.0135,
-.019759,.012868,
-.019939,.012195,
-.02,.0115,
-.02,-.0115,
-.019939,-.012195,
-.019759,-.012868,
-.019464,-.0135,
-.019064,-.014071,
-.018571,-.014564,
-.018,-.014964,
-.017368,-.015259,
-.016695,-.015439,
-.016,-.0155,
.016,-.0155,
.016695,-.015439,
.017368,-.015259,
.018,-.014964,
.018571,-.014564,
.019064,-.014071,
.019464,-.0135,
.019759,-.012868,
.019939,-.012195,
.02,-.0115,
.02,.0115,
.019939,.012195,
.019759,.012868,
.019464,.0135,
.019064,.014071,
.018571,.014564,
.018,.014964,
.017368,.015259,
.016695,.015439,
.016,.0155,
0.0*
%
%ADD18MACRO18*%
%ADD117R,.028X.008*%
%ADD116R,.008X.028*%
%AMMACRO121*
4,1,6,.0895,.0505,
.0895,-.0505,
-.0895,-.0505,
-.0895,.0055,
-.0415,.0055,
-.0415,.0505,
.0895,.0505,
0.0*
%
%ADD121MACRO121*%
%ADD31C,.028*%
%ADD68R,.125X.098*%
%ADD38R,.095X.128*%
%ADD126R,.098X.125*%
%AMMACRO73*
4,1,40,.02,-.005,
.019878,-.006389,
.019518,-.007736,
.018928,-.009,
.018128,-.010142,
.017142,-.011128,
.016,-.011928,
.014736,-.012518,
.013389,-.012878,
.012,-.013,
-.012,-.013,
-.013389,-.012878,
-.014736,-.012518,
-.016,-.011928,
-.017142,-.011128,
-.018128,-.010142,
-.018928,-.009,
-.019518,-.007736,
-.019878,-.006389,
-.02,-.005,
-.02,.005,
-.019878,.006389,
-.019518,.007736,
-.018928,.009,
-.018128,.010142,
-.017142,.011128,
-.016,.011928,
-.014736,.012518,
-.013389,.012878,
-.012,.013,
.012,.013,
.013389,.012878,
.014736,.012518,
.016,.011928,
.017142,.011128,
.018128,.010142,
.018928,.009,
.019518,.007736,
.019878,.006389,
.02,.005,
.02,-.005,
0.0*
%
%ADD73MACRO73*%
%AMMACRO34*
4,1,40,.009,.008,
.009,-.008,
.00897,-.008347,
.008879,-.008684,
.008732,-.009,
.008532,-.009286,
.008286,-.009532,
.008,-.009732,
.007684,-.009879,
.007347,-.00997,
.007,-.01,
-.007,-.01,
-.007347,-.00997,
-.007684,-.009879,
-.008,-.009732,
-.008286,-.009532,
-.008532,-.009286,
-.008732,-.009,
-.008879,-.008684,
-.00897,-.008347,
-.009,-.008,
-.009,.008,
-.00897,.008347,
-.008879,.008684,
-.008732,.009,
-.008532,.009286,
-.008286,.009532,
-.008,.009732,
-.007684,.009879,
-.007347,.00997,
-.007,.01,
.007,.01,
.007347,.00997,
.007684,.009879,
.008,.009732,
.008286,.009532,
.008532,.009286,
.008732,.009,
.008879,.008684,
.00897,.008347,
.009,.008,
0.0*
%
%ADD34MACRO34*%
%AMMACRO13*
4,1,40,.008,-.009,
-.008,-.009,
-.008347,-.00897,
-.008684,-.008879,
-.009,-.008732,
-.009286,-.008532,
-.009532,-.008286,
-.009732,-.008,
-.009879,-.007684,
-.00997,-.007347,
-.01,-.007,
-.01,.007,
-.00997,.007347,
-.009879,.007684,
-.009732,.008,
-.009532,.008286,
-.009286,.008532,
-.009,.008732,
-.008684,.008879,
-.008347,.00897,
-.008,.009,
.008,.009,
.008347,.00897,
.008684,.008879,
.009,.008732,
.009286,.008532,
.009532,.008286,
.009732,.008,
.009879,.007684,
.00997,.007347,
.01,.007,
.01,-.007,
.00997,-.007347,
.009879,-.007684,
.009732,-.008,
.009532,-.008286,
.009286,-.008532,
.009,-.008732,
.008684,-.008879,
.008347,-.00897,
.008,-.009,
0.0*
%
%ADD13MACRO13*%
%AMMACRO78*
4,1,40,.0145,-.0055,
.014378,-.006889,
.014018,-.008236,
.013428,-.0095,
.012628,-.010642,
.011642,-.011628,
.0105,-.012428,
.009236,-.013018,
.007889,-.013378,
.0065,-.0135,
-.0065,-.0135,
-.007889,-.013378,
-.009236,-.013018,
-.0105,-.012428,
-.011642,-.011628,
-.012628,-.010642,
-.013428,-.0095,
-.014018,-.008236,
-.014378,-.006889,
-.0145,-.0055,
-.0145,.0055,
-.014378,.006889,
-.014018,.008236,
-.013428,.0095,
-.012628,.010642,
-.011642,.011628,
-.0105,.012428,
-.009236,.013018,
-.007889,.013378,
-.0065,.0135,
.0065,.0135,
.007889,.013378,
.009236,.013018,
.0105,.012428,
.011642,.011628,
.012628,.010642,
.013428,.0095,
.014018,.008236,
.014378,.006889,
.0145,.0055,
.0145,-.0055,
0.0*
%
%ADD78MACRO78*%
%AMMACRO30*
4,1,40,.009,.008,
.009,-.008,
.00897,-.008347,
.008879,-.008684,
.008732,-.009,
.008532,-.009286,
.008286,-.009532,
.008,-.009732,
.007684,-.009879,
.007347,-.00997,
.007,-.01,
-.007,-.01,
-.007347,-.00997,
-.007684,-.009879,
-.008,-.009732,
-.008286,-.009532,
-.008532,-.009286,
-.008732,-.009,
-.008879,-.008684,
-.00897,-.008347,
-.009,-.008,
-.009,.008,
-.00897,.008347,
-.008879,.008684,
-.008732,.009,
-.008532,.009286,
-.008286,.009532,
-.008,.009732,
-.007684,.009879,
-.007347,.00997,
-.007,.01,
.007,.01,
.007347,.00997,
.007684,.009879,
.008,.009732,
.008286,.009532,
.008532,.009286,
.008732,.009,
.008879,.008684,
.00897,.008347,
.009,.008,
0.0*
%
%ADD30MACRO30*%
%AMMACRO14*
4,1,40,.008,-.009,
-.008,-.009,
-.008347,-.00897,
-.008684,-.008879,
-.009,-.008732,
-.009286,-.008532,
-.009532,-.008286,
-.009732,-.008,
-.009879,-.007684,
-.00997,-.007347,
-.01,-.007,
-.01,.007,
-.00997,.007347,
-.009879,.007684,
-.009732,.008,
-.009532,.008286,
-.009286,.008532,
-.009,.008732,
-.008684,.008879,
-.008347,.00897,
-.008,.009,
.008,.009,
.008347,.00897,
.008684,.008879,
.009,.008732,
.009286,.008532,
.009532,.008286,
.009732,.008,
.009879,.007684,
.00997,.007347,
.01,.007,
.01,-.007,
.00997,-.007347,
.009879,-.007684,
.009732,-.008,
.009532,-.008286,
.009286,-.008532,
.009,-.008732,
.008684,-.008879,
.008347,-.00897,
.008,-.009,
0.0*
%
%ADD14MACRO14*%
%AMMACRO33*
4,1,3,.0125,-.025,
-.0125,0.0,
.0125,.025,
.0125,-.025,
0.0*
%
%ADD33MACRO33*%
%ADD83O,.01X.0135*%
%ADD81O,.0135X.01*%
%ADD61R,.03X.014*%
%ADD98R,.033X.012*%
%ADD96R,.012X.05*%
%ADD95R,.05X.012*%
%ADD57R,.014X.03*%
%ADD43R,.032X.022*%
%AMMACRO26*
4,1,3,-.0125,0.0,
.0125,.025,
.0125,-.025,
-.0125,0.0,
0.0*
%
%ADD26MACRO26*%
%ADD113R,.012X.033*%
%ADD72R,.012X.034*%
%ADD25R,.034X.012*%
%ADD103R,.032X.042*%
%ADD99R,.042X.032*%
%ADD63R,.04X.026*%
%AMMACRO19*
4,1,40,.01,-.009,
.01,.009,
.00997,.009347,
.009879,.009684,
.009732,.01,
.009532,.010286,
.009286,.010532,
.009,.010732,
.008684,.010879,
.008347,.01097,
.008,.011,
-.008,.011,
-.008347,.01097,
-.008684,.010879,
-.009,.010732,
-.009286,.010532,
-.009532,.010286,
-.009732,.01,
-.009879,.009684,
-.00997,.009347,
-.01,.009,
-.01,-.009,
-.00997,-.009347,
-.009879,-.009684,
-.009732,-.01,
-.009532,-.010286,
-.009286,-.010532,
-.009,-.010732,
-.008684,-.010879,
-.008347,-.01097,
-.008,-.011,
.008,-.011,
.008347,-.01097,
.008684,-.010879,
.009,-.010732,
.009286,-.010532,
.009532,-.010286,
.009732,-.01,
.009879,-.009684,
.00997,-.009347,
.01,-.009,
0.0*
%
%ADD19MACRO19*%
%AMMACRO16*
4,1,40,.009,.01,
-.009,.01,
-.009347,.00997,
-.009684,.009879,
-.01,.009732,
-.010286,.009532,
-.010532,.009286,
-.010732,.009,
-.010879,.008684,
-.01097,.008347,
-.011,.008,
-.011,-.008,
-.01097,-.008347,
-.010879,-.008684,
-.010732,-.009,
-.010532,-.009286,
-.010286,-.009532,
-.01,-.009732,
-.009684,-.009879,
-.009347,-.00997,
-.009,-.01,
.009,-.01,
.009347,-.00997,
.009684,-.009879,
.01,-.009732,
.010286,-.009532,
.010532,-.009286,
.010732,-.009,
.010879,-.008684,
.01097,-.008347,
.011,-.008,
.011,.008,
.01097,.008347,
.010879,.008684,
.010732,.009,
.010532,.009286,
.010286,.009532,
.01,.009732,
.009684,.009879,
.009347,.00997,
.009,.01,
0.0*
%
%ADD16MACRO16*%
%ADD125R,.026X.04*%
%ADD101R,.012X.028*%
%ADD100R,.028X.012*%
%ADD67R,.06X.025*%
%ADD111R,.025X.06*%
%AMMACRO108*
4,1,12,.0725,-.069,
.0725,-.015,
-.0725,-.015,
-.0725,-.025,
-.1475,-.025,
-.1475,.025,
-.0725,.025,
-.0725,.015,
.0725,.015,
.0725,.069,
.1475,.069,
.1475,-.069,
.0725,-.069,
0.0*
%
%ADD108MACRO108*%
%ADD75R,.012X.055*%
%ADD46R,.04X.073*%
%ADD10C,.14*%
%ADD107R,.05X.036*%
%ADD79R,.055X.014*%
%ADD66R,.026X.016*%
%ADD42R,.073X.04*%
%ADD110R,.037X.024*%
%ADD106R,.054X.025*%
%ADD76R,.038X.014*%
%AMMACRO49*
4,1,40,.0155,-.016,
.0155,.016,
.015439,.016695,
.015259,.017368,
.014964,.018,
.014564,.018571,
.014071,.019064,
.0135,.019464,
.012868,.019759,
.012195,.019939,
.0115,.02,
-.0115,.02,
-.012195,.019939,
-.012868,.019759,
-.0135,.019464,
-.014071,.019064,
-.014564,.018571,
-.014964,.018,
-.015259,.017368,
-.015439,.016695,
-.0155,.016,
-.0155,-.016,
-.015439,-.016695,
-.015259,-.017368,
-.014964,-.018,
-.014564,-.018571,
-.014071,-.019064,
-.0135,-.019464,
-.012868,-.019759,
-.012195,-.019939,
-.0115,-.02,
.0115,-.02,
.012195,-.019939,
.012868,-.019759,
.0135,-.019464,
.014071,-.019064,
.014564,-.018571,
.014964,-.018,
.015259,-.017368,
.015439,-.016695,
.0155,-.016,
0.0*
%
%ADD49MACRO49*%
%ADD22R,.014X.055*%
%AMMACRO17*
4,1,40,-.016,-.0155,
.016,-.0155,
.016695,-.015439,
.017368,-.015259,
.018,-.014964,
.018571,-.014564,
.019064,-.014071,
.019464,-.0135,
.019759,-.012868,
.019939,-.012195,
.02,-.0115,
.02,.0115,
.019939,.012195,
.019759,.012868,
.019464,.0135,
.019064,.014071,
.018571,.014564,
.018,.014964,
.017368,.015259,
.016695,.015439,
.016,.0155,
-.016,.0155,
-.016695,.015439,
-.017368,.015259,
-.018,.014964,
-.018571,.014564,
-.019064,.014071,
-.019464,.0135,
-.019759,.012868,
-.019939,.012195,
-.02,.0115,
-.02,-.0115,
-.019939,-.012195,
-.019759,-.012868,
-.019464,-.0135,
-.019064,-.014071,
-.018571,-.014564,
-.018,-.014964,
-.017368,-.015259,
-.016695,-.015439,
-.016,-.0155,
0.0*
%
%ADD17MACRO17*%
%ADD109R,.075X.05*%
%ADD69R,.073X.025*%
%ADD59R,.036X.026*%
%ADD50R,.014X.038*%
%ADD20R,.037X.061*%
%ADD120R,.026X.036*%
%ADD86R,.138X.181*%
%ADD56R,.016X.028*%
%ADD21R,.037X.053*%
%ADD12R,.061X.037*%
%ADD105R,.134X.169*%
%AMMACRO74*
4,1,40,.002,.016,
.003389,.015878,
.004736,.015518,
.006,.014928,
.007142,.014128,
.008128,.013142,
.008928,.012,
.009518,.010736,
.009878,.009389,
.01,.008,
.01,-.008,
.009878,-.009389,
.009518,-.010736,
.008928,-.012,
.008128,-.013142,
.007142,-.014128,
.006,-.014928,
.004736,-.015518,
.003389,-.015878,
.002,-.016,
-.002,-.016,
-.003389,-.015878,
-.004736,-.015518,
-.006,-.014928,
-.007142,-.014128,
-.008128,-.013142,
-.008928,-.012,
-.009518,-.010736,
-.009878,-.009389,
-.01,-.008,
-.01,.008,
-.009878,.009389,
-.009518,.010736,
-.008928,.012,
-.008128,.013142,
-.007142,.014128,
-.006,.014928,
-.004736,.015518,
-.003389,.015878,
-.002,.016,
.002,.016,
0.0*
%
%ADD74MACRO74*%
%ADD53R,.089X.011*%
%AMMACRO48*
4,1,40,-.016,.002,
-.015878,.003389,
-.015518,.004736,
-.014928,.006,
-.014128,.007142,
-.013142,.008128,
-.012,.008928,
-.010736,.009518,
-.009389,.009878,
-.008,.01,
.008,.01,
.009389,.009878,
.010736,.009518,
.012,.008928,
.013142,.008128,
.014128,.007142,
.014928,.006,
.015518,.004736,
.015878,.003389,
.016,.002,
.016,-.002,
.015878,-.003389,
.015518,-.004736,
.014928,-.006,
.014128,-.007142,
.013142,-.008128,
.012,-.008928,
.010736,-.009518,
.009389,-.009878,
.008,-.01,
-.008,-.01,
-.009389,-.009878,
-.010736,-.009518,
-.012,-.008928,
-.013142,-.008128,
-.014128,-.007142,
-.014928,-.006,
-.015518,-.004736,
-.015878,-.003389,
-.016,-.002,
-.016,.002,
0.0*
%
%ADD48MACRO48*%
%ADD124R,.074X.053*%
%ADD77R,.069X.05*%
%ADD65R,.085X.026*%
%ADD55R,.092X.018*%
%ADD44R,.037X.055*%
%ADD122R,.026X.085*%
%ADD54R,.092X.037*%
%ADD104R,.043X.079*%
%AMMACRO64*
4,1,6,.0505,-.0895,
-.0505,-.0895,
-.0505,.0895,
.0055,.0895,
.0055,.0415,
.0505,.0415,
.0505,-.0895,
0.0*
%
%ADD64MACRO64*%
%AMMACRO62*
4,1,40,.005,.02,
.006389,.019878,
.007736,.019518,
.009,.018928,
.010142,.018128,
.011128,.017142,
.011928,.016,
.012518,.014736,
.012878,.013389,
.013,.012,
.013,-.012,
.012878,-.013389,
.012518,-.014736,
.011928,-.016,
.011128,-.017142,
.010142,-.018128,
.009,-.018928,
.007736,-.019518,
.006389,-.019878,
.005,-.02,
-.005,-.02,
-.006389,-.019878,
-.007736,-.019518,
-.009,-.018928,
-.010142,-.018128,
-.011128,-.017142,
-.011928,-.016,
-.012518,-.014736,
-.012878,-.013389,
-.013,-.012,
-.013,.012,
-.012878,.013389,
-.012518,.014736,
-.011928,.016,
-.011128,.017142,
-.010142,.018128,
-.009,.018928,
-.007736,.019518,
-.006389,.019878,
-.005,.02,
.005,.02,
0.0*
%
%ADD62MACRO62*%
%ADD123R,.075X.095*%
%ADD102R,.066X.086*%
%ADD85R,.185X.268*%
%ADD52R,.097X.072*%
%ADD45R,.095X.075*%
%ADD39R,.173X.173*%
%ADD118R,.138X.138*%
%AMMACRO71*
4,1,40,-.0145,.0055,
-.014378,.006889,
-.014018,.008236,
-.013428,.0095,
-.012628,.010642,
-.011642,.011628,
-.0105,.012428,
-.009236,.013018,
-.007889,.013378,
-.0065,.0135,
.0065,.0135,
.007889,.013378,
.009236,.013018,
.0105,.012428,
.011642,.011628,
.012628,.010642,
.013428,.0095,
.014018,.008236,
.014378,.006889,
.0145,.0055,
.0145,-.0055,
.014378,-.006889,
.014018,-.008236,
.013428,-.0095,
.012628,-.010642,
.011642,-.011628,
.0105,-.012428,
.009236,-.013018,
.007889,-.013378,
.0065,-.0135,
-.0065,-.0135,
-.007889,-.013378,
-.009236,-.013018,
-.0105,-.012428,
-.011642,-.011628,
-.012628,-.010642,
-.013428,-.0095,
-.014018,-.008236,
-.014378,-.006889,
-.0145,-.0055,
-.0145,.0055,
0.0*
%
%ADD71MACRO71*%
%AMMACRO70*
4,1,40,.0055,.0145,
.006889,.014378,
.008236,.014018,
.0095,.013428,
.010642,.012628,
.011628,.011642,
.012428,.0105,
.013018,.009236,
.013378,.007889,
.0135,.0065,
.0135,-.0065,
.013378,-.007889,
.013018,-.009236,
.012428,-.0105,
.011628,-.011642,
.010642,-.012628,
.0095,-.013428,
.008236,-.014018,
.006889,-.014378,
.0055,-.0145,
-.0055,-.0145,
-.006889,-.014378,
-.008236,-.014018,
-.0095,-.013428,
-.010642,-.012628,
-.011628,-.011642,
-.012428,-.0105,
-.013018,-.009236,
-.013378,-.007889,
-.0135,-.0065,
-.0135,.0065,
-.013378,.007889,
-.013018,.009236,
-.012428,.0105,
-.011628,.011642,
-.010642,.012628,
-.0095,.013428,
-.008236,.014018,
-.006889,.014378,
-.0055,.0145,
.0055,.0145,
0.0*
%
%ADD70MACRO70*%
%AMMACRO24*
4,1,40,-.009,-.008,
-.009,.008,
-.00897,.008347,
-.008879,.008684,
-.008732,.009,
-.008532,.009286,
-.008286,.009532,
-.008,.009732,
-.007684,.009879,
-.007347,.00997,
-.007,.01,
.007,.01,
.007347,.00997,
.007684,.009879,
.008,.009732,
.008286,.009532,
.008532,.009286,
.008732,.009,
.008879,.008684,
.00897,.008347,
.009,.008,
.009,-.008,
.00897,-.008347,
.008879,-.008684,
.008732,-.009,
.008532,-.009286,
.008286,-.009532,
.008,-.009732,
.007684,-.009879,
.007347,-.00997,
.007,-.01,
-.007,-.01,
-.007347,-.00997,
-.007684,-.009879,
-.008,-.009732,
-.008286,-.009532,
-.008532,-.009286,
-.008732,-.009,
-.008879,-.008684,
-.00897,-.008347,
-.009,-.008,
0.0*
%
%ADD24MACRO24*%
%AMMACRO35*
4,1,40,-.008,.009,
.008,.009,
.008347,.00897,
.008684,.008879,
.009,.008732,
.009286,.008532,
.009532,.008286,
.009732,.008,
.009879,.007684,
.00997,.007347,
.01,.007,
.01,-.007,
.00997,-.007347,
.009879,-.007684,
.009732,-.008,
.009532,-.008286,
.009286,-.008532,
.009,-.008732,
.008684,-.008879,
.008347,-.00897,
.008,-.009,
-.008,-.009,
-.008347,-.00897,
-.008684,-.008879,
-.009,-.008732,
-.009286,-.008532,
-.009532,-.008286,
-.009732,-.008,
-.009879,-.007684,
-.00997,-.007347,
-.01,-.007,
-.01,.007,
-.00997,.007347,
-.009879,.007684,
-.009732,.008,
-.009532,.008286,
-.009286,.008532,
-.009,.008732,
-.008684,.008879,
-.008347,.00897,
-.008,.009,
0.0*
%
%ADD35MACRO35*%
%AMMACRO28*
4,1,20,-.0635,.1075,
-.049,.1075,
-.049,.118,
-.0395,.118,
-.0395,.1075,
.0395,.1075,
.0395,.118,
.049,.118,
.049,.1075,
.0635,.1075,
.0635,-.1075,
.049,-.1075,
.049,-.118,
.0395,-.118,
.0395,-.1075,
-.0395,-.1075,
-.0395,-.118,
-.049,-.118,
-.049,-.1075,
-.0635,-.1075,
-.0635,.1075,
0.0*
%
%ADD28MACRO28*%
%AMMACRO29*
4,1,40,-.009,-.008,
-.009,.008,
-.00897,.008347,
-.008879,.008684,
-.008732,.009,
-.008532,.009286,
-.008286,.009532,
-.008,.009732,
-.007684,.009879,
-.007347,.00997,
-.007,.01,
.007,.01,
.007347,.00997,
.007684,.009879,
.008,.009732,
.008286,.009532,
.008532,.009286,
.008732,.009,
.008879,.008684,
.00897,.008347,
.009,.008,
.009,-.008,
.00897,-.008347,
.008879,-.008684,
.008732,-.009,
.008532,-.009286,
.008286,-.009532,
.008,-.009732,
.007684,-.009879,
.007347,-.00997,
.007,-.01,
-.007,-.01,
-.007347,-.00997,
-.007684,-.009879,
-.008,-.009732,
-.008286,-.009532,
-.008532,-.009286,
-.008732,-.009,
-.008879,-.008684,
-.00897,-.008347,
-.009,-.008,
0.0*
%
%ADD29MACRO29*%
%AMMACRO36*
4,1,40,-.008,.009,
.008,.009,
.008347,.00897,
.008684,.008879,
.009,.008732,
.009286,.008532,
.009532,.008286,
.009732,.008,
.009879,.007684,
.00997,.007347,
.01,.007,
.01,-.007,
.00997,-.007347,
.009879,-.007684,
.009732,-.008,
.009532,-.008286,
.009286,-.008532,
.009,-.008732,
.008684,-.008879,
.008347,-.00897,
.008,-.009,
-.008,-.009,
-.008347,-.00897,
-.008684,-.008879,
-.009,-.008732,
-.009286,-.008532,
-.009532,-.008286,
-.009732,-.008,
-.009879,-.007684,
-.00997,-.007347,
-.01,-.007,
-.01,.007,
-.00997,.007347,
-.009879,.007684,
-.009732,.008,
-.009532,.008286,
-.009286,.008532,
-.009,.008732,
-.008684,.008879,
-.008347,.00897,
-.008,.009,
0.0*
%
%ADD36MACRO36*%
%ADD127C,.02*%
%ADD128C,.006*%
G75*
%LPD*%
G75*
G36*
G01X550200Y124200D02*
X560700D01*
Y134700D01*
X550200D01*
Y124200D01*
G37*
G36*
G01Y137300D02*
X560700D01*
Y147800D01*
X550200D01*
Y137300D01*
G37*
G36*
G01X563300Y124200D02*
X573800D01*
Y134700D01*
X563300D01*
Y124200D01*
G37*
G36*
G01Y137300D02*
X573800D01*
Y147800D01*
X563300D01*
Y137300D01*
G37*
G54D100*
X577000Y197705D03*
Y195735D03*
Y193765D03*
Y191795D03*
Y189830D03*
Y199670D03*
X590400Y189830D03*
Y191795D03*
Y193765D03*
Y195735D03*
Y197705D03*
Y199670D03*
G54D110*
X675839Y162260D03*
Y166000D03*
Y169740D03*
X685161Y166000D03*
Y162260D03*
Y169740D03*
G54D101*
X580745Y187050D03*
X586655D03*
X580745Y202450D03*
X586655D03*
G54D102*
X583700Y194750D03*
G54D120*
X785015Y132549D03*
X800015D03*
X795015D03*
X790015D03*
G54D111*
X681500Y194250D03*
X686500D03*
X691500D03*
Y213750D03*
X686500D03*
X681500D03*
X696500Y194250D03*
Y213750D03*
G54D10*
X-19686Y15748D03*
Y573228D03*
X846455Y15748D03*
Y573228D03*
G54D103*
X617931Y133000D03*
X623069D03*
X634431Y167500D03*
X639569D03*
G54D121*
X792515Y146060D03*
G54D112*
X731340Y73615D03*
G54D104*
X631500Y83177D03*
Y117823D03*
G54D122*
X785015Y152121D03*
G54D20*
X25800Y146500D03*
X19200D03*
X25800Y139400D03*
X19200D03*
X44450Y255500D03*
X64300Y118500D03*
X57700D03*
X60300Y171900D03*
X55800Y259000D03*
X62400D03*
X51050Y255500D03*
X66900Y171900D03*
X114200Y196500D03*
X120800D03*
X114200Y204000D03*
X120800D03*
X153200Y61000D03*
X159800D03*
X222200Y191000D03*
X228800D03*
X457200Y162200D03*
X463800D03*
X457200Y155100D03*
X463800D03*
X664300Y105000D03*
X657700D03*
X664300Y97500D03*
X657700D03*
X664300Y133000D03*
X657700D03*
X664300Y125500D03*
X657700D03*
X787700Y114000D03*
Y123000D03*
X780700Y256200D03*
X774100D03*
X794300Y114000D03*
Y123000D03*
X797800Y229400D03*
X804400D03*
X797800Y222300D03*
X804400D03*
G54D113*
X735277Y67865D03*
X733309D03*
X731340D03*
X729371D03*
X727403D03*
Y79365D03*
X729371D03*
X731340D03*
X733309D03*
X735277D03*
G54D11*
X-11600Y33200D03*
X18400Y76200D03*
X24000Y280000D03*
X325500Y229000D03*
X394100Y57700D03*
X468000Y171500D03*
X799500Y10500D03*
X833100Y564800D03*
X842500Y35000D03*
G54D123*
X778850Y243000D03*
X802150D03*
G54D105*
X638000Y215500D03*
G54D12*
X20000Y103800D03*
Y97200D03*
X32200Y98400D03*
Y91800D03*
X26100Y109800D03*
Y116400D03*
X33200Y109800D03*
Y116400D03*
X28550Y161900D03*
Y168500D03*
X62200Y131700D03*
Y138300D03*
X74000Y52700D03*
Y59300D03*
X79100Y89000D03*
Y95600D03*
X130500Y213100D03*
X137600D03*
X130500Y219700D03*
X137600D03*
X144700Y213100D03*
Y219700D03*
X165900Y208700D03*
Y215300D03*
X184500Y259800D03*
Y253200D03*
X188500Y264700D03*
Y271300D03*
X181000Y264700D03*
Y271300D03*
X192000Y259800D03*
Y253200D03*
X211500Y264700D03*
Y271300D03*
X219000Y264700D03*
Y271300D03*
X233500Y226800D03*
Y220200D03*
X226000Y226800D03*
Y220200D03*
X228500Y247700D03*
Y254300D03*
X236700Y207600D03*
Y201000D03*
X243800Y207600D03*
Y201000D03*
X241000Y226800D03*
Y220200D03*
X248500Y226800D03*
Y220200D03*
X236000Y247700D03*
Y254300D03*
X250600Y247700D03*
Y254300D03*
X243500Y247700D03*
Y254300D03*
X257700Y247700D03*
Y254300D03*
X339000Y56200D03*
Y62800D03*
X346500Y56200D03*
Y62800D03*
X377000Y52200D03*
Y58800D03*
X583000Y229700D03*
Y236300D03*
X590500Y229700D03*
Y236300D03*
X617000Y47707D03*
Y54307D03*
X624500Y47707D03*
Y54307D03*
X630000Y230200D03*
Y236800D03*
X637500Y230200D03*
Y236800D03*
X661000Y47707D03*
Y54307D03*
X668100Y47707D03*
Y54307D03*
G54D21*
X19200Y156200D03*
X25800D03*
G54D30*
X48000Y217500D03*
X49500Y116000D03*
X79400Y139200D03*
X74200Y194000D03*
X71100Y252600D03*
X102500Y197000D03*
Y194000D03*
X179100Y127700D03*
X180100Y176000D03*
X189500Y193500D03*
X262000Y49500D03*
X282500Y219000D03*
X423000Y260500D03*
X471200Y245500D03*
X503500Y155000D03*
X511500Y176000D03*
Y179000D03*
X520500Y215500D03*
X565000Y227000D03*
X601000Y46000D03*
X617500Y208000D03*
X667500Y161000D03*
Y171500D03*
G54D114*
X738017Y124213D03*
Y143313D03*
X752191Y124213D03*
Y143313D03*
G54D124*
X794500Y77800D03*
Y93200D03*
G54D22*
X28209Y175152D03*
X30769D03*
X25649D03*
X23089D03*
Y190832D03*
X25649D03*
X28209D03*
X30769D03*
G54D106*
X626889Y208000D03*
Y213000D03*
Y218000D03*
Y223000D03*
X649111Y213000D03*
Y208000D03*
Y223000D03*
Y218000D03*
G54D13*
X18000Y197000D03*
X54700Y269600D03*
X76000Y129000D03*
X67400Y249800D03*
X77100Y262900D03*
X73600Y262809D03*
X96500Y169000D03*
X98500Y192500D03*
X121500Y128500D03*
X164500Y193500D03*
X181000Y81500D03*
X174500Y99800D03*
X182200Y134000D03*
X205600Y49000D03*
X208600D03*
X218500Y212500D03*
X248500Y116500D03*
X242000Y174500D03*
X293300Y160500D03*
X310500Y234500D03*
X423500Y251500D03*
X465500Y147063D03*
X511500Y170000D03*
X633500Y49007D03*
X636800D03*
X645300D03*
X648500Y165500D03*
X650800Y49007D03*
X657500Y219000D03*
X686400Y173300D03*
X717000Y68000D03*
Y200000D03*
X741500Y87000D03*
X737000Y155500D03*
X744700Y70000D03*
X766500Y129500D03*
X805500Y138500D03*
G54D31*
X43500Y242000D03*
X44000Y234000D03*
X51000Y229500D03*
X86600Y249500D03*
X156070Y158720D03*
X175600Y94500D03*
X218500Y49500D03*
X297200Y146000D03*
X304300Y141400D03*
X379500Y270000D03*
X387000D03*
X550000Y85500D03*
X544000Y81000D03*
X582000Y74000D03*
X574500D03*
X617000Y79500D03*
Y87000D03*
X620000Y101500D03*
Y94000D03*
G54D115*
X735554Y126676D03*
Y140850D03*
X754654Y126676D03*
Y140850D03*
G54D40*
X78988Y218689D03*
X77413D03*
X75839D03*
Y241311D03*
X77413D03*
X78988D03*
X93161Y218689D03*
X91587D03*
X90012D03*
X88437D03*
X86862D03*
X85287D03*
X83713D03*
X82138D03*
X80563D03*
Y241311D03*
X82138D03*
X83713D03*
X85287D03*
X86862D03*
X88437D03*
X90012D03*
X91587D03*
X93161D03*
G54D50*
X125000Y49250D03*
X122440D03*
X125000Y55750D03*
X122440D03*
X127560Y49250D03*
Y55750D03*
X209060Y175750D03*
X206500D03*
X203940D03*
X209060Y182250D03*
X206500D03*
X203940D03*
X231260Y50950D03*
X228700D03*
X226140D03*
X231260Y57450D03*
X228700D03*
X226140D03*
X219940Y168750D03*
X222500D03*
X225060D03*
X219940Y162250D03*
X222500D03*
X225060D03*
X437940Y269750D03*
X440500D03*
X443060D03*
X437940Y263250D03*
X440500D03*
X443060D03*
G54D107*
X662362Y167248D03*
X653638D03*
X662362Y160752D03*
X653638D03*
G54D125*
X790015Y154371D03*
X795015D03*
X800015D03*
G54D14*
X18000Y200000D03*
X54700Y272600D03*
X76000Y132000D03*
X67400Y252800D03*
X77100Y265900D03*
X73600Y265809D03*
X96500Y172000D03*
X98500Y195500D03*
X121500Y131500D03*
X164500Y196500D03*
X181000Y84500D03*
X174500Y102800D03*
X182200Y137000D03*
X205600Y52000D03*
X208600D03*
X218500Y215500D03*
X248500Y119500D03*
X242000Y177500D03*
X293300Y163500D03*
X310500Y237500D03*
X423500Y254500D03*
X465500Y150063D03*
X511500Y173000D03*
X633500Y52007D03*
X636800D03*
X645300D03*
X648500Y168500D03*
X650800Y52007D03*
X657500Y222000D03*
X686400Y176300D03*
X717000Y71000D03*
Y203000D03*
X741500Y90000D03*
X737000Y158500D03*
X744700Y73000D03*
X766500Y132500D03*
X805500Y141500D03*
G54D116*
X741167Y124313D03*
X739592D03*
Y143213D03*
X741167D03*
X750616Y124313D03*
X749041D03*
X747466D03*
X745891D03*
X744317D03*
X742742D03*
Y143213D03*
X744317D03*
X745891D03*
X747466D03*
X749041D03*
X750616D03*
G54D23*
X18500Y173300D03*
Y176700D03*
Y180300D03*
X21900Y197300D03*
X18500Y183700D03*
X21900Y200700D03*
X51000Y123800D03*
Y127200D03*
X60000Y123800D03*
Y127200D03*
X63800Y205300D03*
Y208700D03*
X54000Y220900D03*
Y224300D03*
Y214300D03*
Y217700D03*
X67000Y82800D03*
Y86200D03*
X77100Y269000D03*
Y272400D03*
X92600Y197200D03*
X89600D03*
X92600Y200600D03*
X83400Y203400D03*
Y206800D03*
X89600Y200600D03*
X86400Y254900D03*
Y258300D03*
X83200Y262800D03*
Y266200D03*
X93900Y261700D03*
Y265100D03*
X95900Y200500D03*
Y203900D03*
X97000Y261700D03*
Y265100D03*
X113500Y50800D03*
Y54200D03*
X125000Y60300D03*
Y63700D03*
X124500Y128300D03*
Y131700D03*
X123700Y140900D03*
Y144300D03*
X115450Y137800D03*
Y141200D03*
X125000Y215300D03*
Y218700D03*
X113100Y234500D03*
Y237900D03*
X135000Y49800D03*
Y53200D03*
X131500Y49800D03*
Y53200D03*
X129500Y70800D03*
Y74200D03*
X142000Y152300D03*
X148000D03*
X151000D03*
X145000D03*
X153000Y163800D03*
Y167200D03*
X142000Y155700D03*
X148000D03*
X151000D03*
X145000D03*
X167000Y167300D03*
Y170700D03*
X190000Y80800D03*
Y84200D03*
X200000Y180800D03*
Y184200D03*
X212000Y48800D03*
Y52200D03*
X210800Y192300D03*
Y195700D03*
X215500Y212300D03*
Y215700D03*
X222500Y173800D03*
Y177200D03*
X219500Y173800D03*
Y177200D03*
X226000Y212300D03*
Y215700D03*
X239000Y98800D03*
Y102200D03*
X259000Y49300D03*
Y52700D03*
X261000Y165800D03*
Y169200D03*
X263000Y225300D03*
Y228700D03*
X275300Y170200D03*
Y173600D03*
X266000Y225300D03*
Y228700D03*
X271000Y225500D03*
Y228900D03*
X290500Y78300D03*
Y81700D03*
X291800Y97200D03*
Y100600D03*
X284500Y167300D03*
Y170700D03*
X290000Y192300D03*
Y195700D03*
X308000Y257800D03*
Y261200D03*
X319000Y257800D03*
X314500D03*
X319000Y261200D03*
X314500D03*
X368000Y50300D03*
Y53700D03*
X365000Y50300D03*
Y53700D03*
X362000Y50300D03*
Y53700D03*
X359000Y50300D03*
Y53700D03*
X382500Y53800D03*
Y57200D03*
X397900Y269400D03*
Y272800D03*
X444600Y251400D03*
Y254800D03*
X443000Y278300D03*
Y281700D03*
X452000Y278300D03*
Y281700D03*
X526500Y74800D03*
Y78200D03*
X522500Y201800D03*
Y205200D03*
X518500Y201800D03*
Y205200D03*
X530000Y72300D03*
X536500D03*
X533500D03*
X530000Y75700D03*
X536500D03*
X533500D03*
X566500Y74300D03*
Y77700D03*
X577000Y79800D03*
Y83200D03*
X612500Y204800D03*
Y208200D03*
Y216300D03*
Y219700D03*
X622500Y78300D03*
Y81700D03*
X634000Y129300D03*
Y132700D03*
X645000Y165300D03*
Y168700D03*
X643500Y178800D03*
Y182200D03*
X639800Y189500D03*
Y192900D03*
X694900Y181400D03*
X691900D03*
X694900Y184800D03*
X691900D03*
X688500Y223300D03*
Y226700D03*
X685500Y223300D03*
Y226700D03*
X697500Y223300D03*
Y226700D03*
X721300Y130200D03*
Y133600D03*
X718000Y130200D03*
Y133600D03*
X721700Y123200D03*
Y126600D03*
X715000Y140300D03*
Y143700D03*
X728000Y88400D03*
X731000D03*
X736500Y104600D03*
X728000Y91800D03*
X731000D03*
X736500Y108000D03*
X734000Y155300D03*
Y158700D03*
X731000Y155300D03*
Y158700D03*
X741500Y179300D03*
Y182700D03*
X738500Y179300D03*
Y182700D03*
X737000Y197800D03*
X728000Y210300D03*
Y213700D03*
X737000Y201200D03*
X751500Y155300D03*
Y158700D03*
X766500Y122800D03*
Y126200D03*
X779500Y34807D03*
Y38207D03*
X782500Y34807D03*
Y38207D03*
X805500Y131300D03*
Y134700D03*
G54D41*
X73189Y221339D03*
Y222913D03*
Y224488D03*
Y226063D03*
Y227638D03*
Y229213D03*
Y230787D03*
Y232362D03*
Y233937D03*
Y235512D03*
Y237087D03*
Y238661D03*
X95811Y227638D03*
Y226063D03*
Y224488D03*
Y222913D03*
Y221339D03*
Y238661D03*
Y237087D03*
Y235512D03*
Y233937D03*
Y232362D03*
Y230787D03*
Y229213D03*
G54D32*
X59650Y84300D03*
G54D24*
X32000Y222500D03*
Y219000D03*
Y229500D03*
Y226000D03*
Y236500D03*
Y233000D03*
Y243500D03*
Y240000D03*
Y250500D03*
Y247000D03*
Y257500D03*
Y254000D03*
X36000Y158000D03*
X43300Y212700D03*
Y207800D03*
X40500Y198800D03*
Y203700D03*
X43500D03*
Y198800D03*
X46300Y212700D03*
Y207800D03*
X61700Y198300D03*
Y201800D03*
X77000Y85000D03*
X70900Y207200D03*
X77500Y249800D03*
X89300Y207100D03*
X86500Y261500D03*
X180000Y75500D03*
X222800Y89900D03*
X437000Y278000D03*
X535500Y234100D03*
X608500Y96000D03*
Y93000D03*
X702000Y192500D03*
X718700Y119700D03*
Y116400D03*
X736200Y111100D03*
X742800Y108100D03*
X745000Y155500D03*
X776500Y16000D03*
G54D42*
X93200Y142200D03*
Y152800D03*
X101700Y142200D03*
Y152800D03*
X102500Y165700D03*
Y176300D03*
X107900Y243700D03*
Y254300D03*
G54D108*
X683000Y104500D03*
Y132500D03*
G54D33*
X62350Y84300D03*
G54D126*
X792700Y165671D03*
Y196329D03*
G54D117*
X735654Y128251D03*
Y129826D03*
Y131401D03*
Y132976D03*
Y134550D03*
Y136125D03*
Y137700D03*
Y139275D03*
X754554Y136125D03*
Y134550D03*
Y132976D03*
Y131401D03*
Y129826D03*
Y128251D03*
Y139275D03*
Y137700D03*
G54D51*
X117500Y228100D03*
X127300D03*
X117500Y239900D03*
X127300D03*
X784400Y103000D03*
X794200D03*
X804400Y212800D03*
X794600D03*
G54D60*
X148445Y257000D03*
X172555D03*
G54D15*
X31300Y87500D03*
X27900D03*
X22000Y169300D03*
X18600D03*
X24400Y210100D03*
X21000D03*
X28400Y206900D03*
X25000D03*
X38900Y184000D03*
X35500D03*
X52600Y244400D03*
X49200D03*
X52600Y241400D03*
X49200D03*
X64100Y232800D03*
X60700D03*
X52600Y250400D03*
X49200D03*
X64200Y269500D03*
X60800D03*
X61200Y272500D03*
X57800D03*
X76400Y139200D03*
X73000D03*
X95200Y192500D03*
X91800D03*
X83700Y194000D03*
X80300D03*
X83700Y186500D03*
X80300D03*
X108300Y188500D03*
X99000Y207100D03*
X95600D03*
X123800Y134800D03*
Y147500D03*
X111700Y188500D03*
X127200Y134800D03*
Y147500D03*
X136200Y269000D03*
X132800D03*
X156300Y152200D03*
X159700D03*
X164300Y155200D03*
X160900D03*
X183200Y72500D03*
X179800D03*
X197200D03*
X193800D03*
X200800Y92500D03*
X204200D03*
X211200D03*
X207800D03*
X212200Y216000D03*
X208800D03*
X233800Y70000D03*
Y67000D03*
X237200Y70000D03*
Y67000D03*
X262300Y53000D03*
X254700Y130000D03*
X251300D03*
X264600Y166300D03*
X278800Y59000D03*
X265700Y53000D03*
X278800Y62000D03*
X275700Y124000D03*
X272300D03*
X278200Y145500D03*
X274800D03*
X268000Y166300D03*
X273700Y178400D03*
X270300D03*
X271700Y170000D03*
X268300D03*
X275700Y219000D03*
X272300D03*
X270900Y232100D03*
X267500D03*
X282200Y59000D03*
Y62000D03*
X293200Y118000D03*
X289800D03*
X293200Y121000D03*
X289800D03*
X293200Y135500D03*
X289800D03*
X293200Y132500D03*
X289800D03*
X291700Y147500D03*
X288300D03*
X291700Y144000D03*
X288300D03*
X293700Y167000D03*
X290300D03*
X293700Y173500D03*
X290300D03*
X293700Y170500D03*
X290300D03*
X293300Y188800D03*
X289900D03*
X284700Y225000D03*
X281300D03*
X284700Y222000D03*
X281300D03*
X308700Y54000D03*
X305300D03*
X397800Y263100D03*
X394400D03*
X418600Y81500D03*
X415200D03*
X431900Y79500D03*
X428500D03*
X425200Y81500D03*
X421800D03*
X433200Y228000D03*
X429800D03*
X433700Y278000D03*
X430300D03*
X441200Y228000D03*
X437800D03*
X462200Y143563D03*
X458800D03*
X462200Y147063D03*
X458800D03*
X506200Y132000D03*
X502800D03*
X506200Y135000D03*
X502800D03*
X538700Y237100D03*
X535300D03*
X546600Y204600D03*
X543200D03*
X611700Y49007D03*
X608300D03*
X611700Y52007D03*
X608300D03*
X617300Y128500D03*
X615800Y178500D03*
X630200Y133000D03*
X626800D03*
X620700Y128500D03*
X619200Y178500D03*
X625800D03*
X622400D03*
X640200Y163000D03*
X636800D03*
X646500Y189400D03*
X643100D03*
X647200Y237500D03*
X643800D03*
X664200Y189500D03*
X660800D03*
X680800Y183000D03*
X669900Y184000D03*
X666500D03*
X684200Y183000D03*
X711300Y150000D03*
X724700Y147000D03*
X721300D03*
X714700Y150000D03*
X739900Y101500D03*
X736500D03*
X742200Y111100D03*
X745600D03*
X748200Y158500D03*
X744800D03*
X761700Y122000D03*
X758300D03*
X781700Y19000D03*
X778300D03*
X781700Y28000D03*
X778300D03*
X779700Y128600D03*
X776300D03*
G54D127*
G01X10636Y-27865D02*
G02I-12000J0D01*
G01X14636D02*
X-17364D01*
G01X5486D02*
G02I-6850J0D01*
G01X-1364Y-43865D02*
Y-11865D01*
G01X14636Y-43865D02*
Y-123865D01*
G01D02*
X1309236D01*
G01X14636Y-79365D02*
X1309236D01*
G01X14636Y-43865D02*
X1309236D01*
G01X521736D02*
Y-123865D01*
G01X659236Y-43865D02*
Y-123865D01*
G01X774236Y-43865D02*
Y-123865D01*
G01X941736Y-43865D02*
Y-123865D01*
G01X1111736Y-43865D02*
Y-123865D01*
G01X1309236Y-43865D02*
Y-123865D01*
G01X1341236Y-27865D02*
X1309236D01*
G01X1337236D02*
G02I-12000J0D01*
G01X1332086D02*
G02I-6850J0D01*
G01X1325236Y-43865D02*
Y-11865D01*
G54D70*
X214300Y56191D03*
X210560Y64609D03*
X218040D03*
G54D118*
X745104Y133763D03*
G54D52*
X121000Y254266D03*
Y267734D03*
G54D109*
X672000Y95500D03*
Y113500D03*
Y123500D03*
Y141500D03*
G54D16*
X27900Y84500D03*
X31300D03*
X25000Y203800D03*
X28400D03*
X35500Y187000D03*
X38900D03*
X60700Y211800D03*
X64100D03*
X60700Y226800D03*
X64100D03*
X60700Y220800D03*
X64100D03*
X60700Y223800D03*
X64100D03*
X60700Y235800D03*
X64100D03*
X60700Y229800D03*
X64100D03*
X60700Y238800D03*
X64100D03*
X49200Y247400D03*
X52600D03*
X76800Y82000D03*
X76900Y207200D03*
X71067Y249509D03*
X74467D03*
X80200Y82000D03*
X80300Y207200D03*
X101300Y188500D03*
X104700D03*
X102300Y200000D03*
X105700D03*
X108800Y228400D03*
X103600Y239500D03*
X107000D03*
X123800Y137800D03*
X113400Y214600D03*
X116800D03*
X112200Y228400D03*
X113500Y217800D03*
X116900D03*
X127200Y137800D03*
X148800Y205000D03*
X152200D03*
X167600Y193600D03*
X171000D03*
X167600Y196600D03*
X171000D03*
X170300Y241000D03*
X172800Y72500D03*
X176200D03*
X186800D03*
X174300Y84500D03*
X177700D03*
X174300Y81500D03*
X177700D03*
X174800Y109600D03*
X178200D03*
X180300Y131000D03*
X183700D03*
X173700Y241000D03*
X190200Y72500D03*
X216300Y92500D03*
X215800Y157000D03*
X217300Y180500D03*
Y183500D03*
X232300Y102000D03*
Y99000D03*
X219700Y92500D03*
X218800Y136000D03*
X222200D03*
X218800Y148000D03*
X222200D03*
X218800Y142000D03*
X222200D03*
X218800Y145000D03*
X222200D03*
X218800Y139000D03*
X222200D03*
X219200Y157000D03*
X229800Y164500D03*
X233200D03*
X220700Y180500D03*
Y183500D03*
X236000Y54400D03*
X239400D03*
X245300Y88500D03*
X248700D03*
X235700Y102000D03*
Y99000D03*
X245300Y91500D03*
X248700D03*
X251300Y127000D03*
X254700D03*
X253300Y186500D03*
X256700D03*
X279300Y121000D03*
X272300D03*
X275700D03*
X271200Y166300D03*
X274600D03*
X276900Y178400D03*
X266300Y198000D03*
X269700D03*
X266300Y201000D03*
X269700D03*
X281300Y72000D03*
X284700D03*
X288300Y104000D03*
X291700D03*
X288300Y107000D03*
X291700D03*
X282700Y121000D03*
X289800Y126500D03*
X293200D03*
X289800Y129500D03*
X293200D03*
X293400Y151500D03*
X286800Y164000D03*
X290200D03*
X280300Y178400D03*
X289800Y185500D03*
X293200D03*
X305300Y50500D03*
X308700D03*
X305300Y47500D03*
X308700D03*
X296800Y151500D03*
X322800Y251000D03*
X326200D03*
X394400Y266100D03*
X397800D03*
X419800Y78500D03*
X423200D03*
X437300Y79500D03*
X440700D03*
X502800Y142000D03*
X506200D03*
X502800Y145000D03*
X506200D03*
X502800Y148000D03*
X506200D03*
X502800Y139000D03*
X506200D03*
X539800Y72500D03*
Y75500D03*
X543200Y72500D03*
Y75500D03*
X556800Y190000D03*
Y186800D03*
X551800Y199200D03*
X555200D03*
X551800Y202200D03*
X555200D03*
X551800Y205200D03*
X555200D03*
X554500Y223700D03*
Y220700D03*
Y226700D03*
X560200Y190000D03*
Y186800D03*
X557900Y223700D03*
Y220700D03*
Y226700D03*
X600800Y49000D03*
X604200D03*
X608300Y46000D03*
X611700D03*
X629300Y192000D03*
X632700D03*
X647300Y173000D03*
X643100Y192500D03*
X646500D03*
X650700Y173000D03*
X660800Y192500D03*
X664200D03*
X653300Y189000D03*
X656700D03*
X661500Y205000D03*
X664900D03*
X661500Y208000D03*
X664900D03*
X667300Y158000D03*
X670700D03*
X666500Y180500D03*
X669900D03*
X711300Y147000D03*
Y153000D03*
X717800Y137000D03*
X721200D03*
X721300Y150000D03*
X724700D03*
X714700Y147000D03*
Y153000D03*
X721300D03*
X724700D03*
X726800Y169000D03*
Y172000D03*
X730200Y169000D03*
Y172000D03*
X763300Y145900D03*
X766700D03*
X763300Y142900D03*
X766700D03*
X778300Y22000D03*
X781700D03*
X778300Y25000D03*
X781700D03*
G54D25*
X45857Y91657D03*
Y93626D03*
Y95594D03*
Y97563D03*
Y99531D03*
Y101500D03*
Y103469D03*
Y105437D03*
Y107406D03*
Y109374D03*
Y111343D03*
X34357Y133657D03*
Y135626D03*
Y137594D03*
Y139563D03*
Y141531D03*
Y143500D03*
Y145469D03*
Y147437D03*
Y149406D03*
Y151374D03*
Y153343D03*
X64143Y105437D03*
Y103469D03*
Y101500D03*
Y99531D03*
Y97563D03*
Y95594D03*
Y93626D03*
Y91657D03*
Y111343D03*
Y109374D03*
Y107406D03*
X52643Y135626D03*
Y133657D03*
Y151374D03*
Y149406D03*
Y147437D03*
Y145469D03*
Y143500D03*
Y141531D03*
Y139563D03*
Y137594D03*
Y153343D03*
X218795Y197079D03*
Y199047D03*
Y201016D03*
Y202984D03*
Y204953D03*
Y206921D03*
X229205Y197079D03*
Y206921D03*
Y204953D03*
Y202984D03*
Y201016D03*
Y199047D03*
G54D43*
X87729Y270300D03*
X96391D03*
G54D61*
X171320Y160560D03*
Y155440D03*
Y158000D03*
Y164940D03*
Y167500D03*
Y170060D03*
X173120Y151060D03*
X180480D03*
Y145940D03*
X173120D03*
Y148500D03*
X178680Y160560D03*
Y155440D03*
Y164940D03*
Y170060D03*
X427820Y251940D03*
Y257060D03*
X435180Y251940D03*
Y257060D03*
Y254500D03*
X721380Y197525D03*
Y202645D03*
X733320Y192560D03*
X740680D03*
Y187440D03*
X733320D03*
Y190000D03*
X728740Y197525D03*
Y202645D03*
Y200085D03*
G54D34*
X52500Y116000D03*
X51000Y217500D03*
X77200Y194000D03*
X74100Y252600D03*
X82400Y139200D03*
X105500Y197000D03*
Y194000D03*
X182100Y127700D03*
X183100Y176000D03*
X192500Y193500D03*
X265000Y49500D03*
X285500Y219000D03*
X426000Y260500D03*
X474200Y245500D03*
X506500Y155000D03*
X514500Y176000D03*
Y179000D03*
X523500Y215500D03*
X568000Y227000D03*
X604000Y46000D03*
X620500Y208000D03*
X670500Y161000D03*
Y171500D03*
G54D128*
G01X-31497Y-1D02*
X26377D01*
G01X-35434Y3936D02*
G03X-31497Y-1I3937J0D01*
G01X-35434Y585039D02*
Y3936D01*
G01X-7874Y588976D02*
X-31497D01*
G01D02*
G03X-35434Y585039I0J-3937D01*
G01X-12698Y15747D02*
G03I-6988J0D01*
G01Y573227D02*
G03I-6988J0D01*
G01X826773Y286614D02*
G03X822836Y290551I-3937J0D01*
G01X3938D01*
G03X1Y286614I0J-3937D01*
G01Y61811D01*
G03X3938Y57874I3937J0D01*
G01X53938D01*
G02X57875Y53937I0J-3937D01*
G01Y12598D01*
X59844Y10629D01*
X336222D01*
X338190Y12598D01*
Y39960D01*
G02X345671I3740J0D01*
G01Y12598D01*
X347639Y10629D01*
X387797D01*
X389765Y12598D01*
Y42126D01*
G02X393702Y46063I3937J0D01*
G01X409450D01*
G02X413387Y42126I0J-3937D01*
G01Y3937D01*
G03X417324Y0I3937J0D01*
G01X822836D01*
G03X826773Y3937I0J3937D01*
G01Y286614D01*
G01X22440Y49999D02*
X-3937D01*
G01X-7874Y53936D02*
Y72440D01*
G01Y53936D02*
G03X-3937Y49999I3937J0D01*
G01X0Y72440D02*
G03X-7874I-3937J0D01*
G01Y103149D02*
G03X0I3937J0D01*
G01X-7874D02*
Y210235D01*
G01X0D02*
G03X-7874I-3937J0D01*
G01Y240944D02*
Y348031D01*
G01Y240944D02*
G03X0I3937J0D01*
G01X-3Y302361D02*
G03X3934Y298424I3937J0D01*
G01X822832D01*
G03X826769Y302361I0J3937D01*
G01Y527164D01*
G03X822832Y531101I-3937J0D01*
G01X772832D01*
G02X768895Y535038I0J3937D01*
G01Y576377D01*
X766926Y578346D01*
X490548D01*
X488580Y576377D01*
Y549015D01*
G02X481099I-3740J0D01*
G01Y576377D01*
X479131Y578346D01*
X438973D01*
X437005Y576377D01*
Y546849D01*
G02X433068Y542912I-3937J0D01*
G01X417320D01*
G02X413383Y546849I0J3937D01*
G01Y585038D01*
G03X409446Y588975I-3937J0D01*
G01X3934D01*
G03X-3Y585038I0J-3937D01*
G01Y302361D01*
G01X0Y348031D02*
G03X-7874I-3937J0D01*
G01Y378739D02*
Y485826D01*
G01Y378739D02*
G03X0I3937J0D01*
G01Y485826D02*
G03X-7874I-3937J0D01*
G01Y516535D02*
Y588976D01*
G01Y516535D02*
G03X0I3937J-1D01*
G01X26377Y-1D02*
Y46062D01*
G01D02*
G03X22440Y49999I-3937J0D01*
G01X70851Y-113865D02*
Y-96365D01*
G01X80021D02*
Y-113865D01*
G01Y-105115D02*
X70851D01*
G01X92936Y-113865D02*
X91626Y-113573D01*
X90316Y-112407D01*
X89442Y-110365D01*
X89006Y-108032D01*
X89442Y-105698D01*
X90316Y-103657D01*
X91626Y-102490D01*
X92936Y-102199D01*
X94246Y-102490D01*
X95556Y-103657D01*
X96429Y-105698D01*
X96648Y-108032D01*
X96429Y-110365D01*
X95556Y-112407D01*
X94246Y-113573D01*
X92936Y-113865D01*
G01X106724D02*
Y-102199D01*
G01Y-105115D02*
X107598Y-103657D01*
X108908Y-102490D01*
X110654Y-102199D01*
X112182Y-102490D01*
X113493Y-103657D01*
X114148Y-105698D01*
Y-113865D01*
G01X124661Y-105990D02*
X131648D01*
X130993Y-103948D01*
X129901Y-102782D01*
X128373Y-102199D01*
X126844Y-102490D01*
X125534Y-103365D01*
X124661Y-105407D01*
X124224Y-107157D01*
Y-108907D01*
X124661Y-110657D01*
X125753Y-112407D01*
X127063Y-113573D01*
X128591Y-113865D01*
X130119Y-113282D01*
X131648Y-111532D01*
G01X140851Y-119115D02*
X142161Y-119698D01*
X143908Y-119115D01*
X144999Y-117949D01*
X145873Y-116490D01*
X147182Y-111824D01*
X150021Y-102199D01*
G01X143034D02*
X147182Y-111824D01*
G01X182182Y-104532D02*
X183056Y-103657D01*
X183711Y-102199D01*
X184148Y-100156D01*
X183711Y-98407D01*
X182838Y-97240D01*
X181309Y-96365D01*
X175414D01*
Y-113865D01*
X182619D01*
X184148Y-112699D01*
X185021Y-110948D01*
X185458Y-108907D01*
X185021Y-106865D01*
X183711Y-105115D01*
X182182Y-104532D01*
X175414D01*
G01X201866Y-113865D02*
Y-102199D01*
G01Y-104240D02*
X200993Y-103074D01*
X199682Y-102490D01*
X198154Y-102199D01*
X196626Y-102782D01*
X195316Y-103948D01*
X194442Y-105698D01*
X194006Y-108032D01*
X194442Y-110365D01*
X195316Y-112115D01*
X196626Y-113282D01*
X198154Y-113865D01*
X199682Y-113573D01*
X200993Y-112699D01*
X201866Y-111532D01*
G01X219366Y-96365D02*
Y-113865D01*
G01Y-111241D02*
X218493Y-112699D01*
X217182Y-113573D01*
X215654Y-113865D01*
X213908Y-113282D01*
X212598Y-111824D01*
X211724Y-110074D01*
X211506Y-108032D01*
X211724Y-105990D01*
X212598Y-104240D01*
X213908Y-102782D01*
X215654Y-102199D01*
X217182Y-102490D01*
X218274Y-103074D01*
X219366Y-104240D01*
G01X229879Y-118240D02*
X231408Y-119407D01*
X233154Y-119698D01*
X234682Y-119407D01*
X235993Y-117949D01*
X236866Y-115907D01*
Y-102199D01*
G01Y-104532D02*
X235993Y-103365D01*
X234682Y-102490D01*
X233154Y-102199D01*
X231408Y-102782D01*
X230316Y-103948D01*
X229442Y-105990D01*
X229006Y-108032D01*
X229224Y-109782D01*
X230098Y-111824D01*
X231408Y-113282D01*
X233154Y-113865D01*
X234464Y-113573D01*
X235993Y-112407D01*
X236866Y-111241D01*
G01X247161Y-105990D02*
X254148D01*
X253493Y-103948D01*
X252401Y-102782D01*
X250873Y-102199D01*
X249344Y-102490D01*
X248034Y-103365D01*
X247161Y-105407D01*
X246724Y-107157D01*
Y-108907D01*
X247161Y-110657D01*
X248253Y-112407D01*
X249563Y-113573D01*
X251091Y-113865D01*
X252619Y-113282D01*
X254148Y-111532D01*
G01X264879Y-113865D02*
Y-102199D01*
G01Y-104532D02*
X265971Y-103365D01*
X267063Y-102490D01*
X268591Y-102199D01*
X269682Y-102490D01*
X270993Y-103365D01*
G01X298569Y-113865D02*
Y-96365D01*
X303809D01*
X305556Y-97240D01*
X306866Y-99282D01*
X307303Y-101615D01*
X306866Y-103948D01*
X305774Y-105698D01*
X303809Y-106574D01*
X298569D01*
G01X324366Y-113865D02*
Y-102199D01*
G01Y-104240D02*
X323493Y-103074D01*
X322182Y-102490D01*
X320654Y-102199D01*
X319126Y-102782D01*
X317816Y-103948D01*
X316942Y-105698D01*
X316506Y-108032D01*
X316942Y-110365D01*
X317816Y-112115D01*
X319126Y-113282D01*
X320654Y-113865D01*
X322182Y-113573D01*
X323493Y-112699D01*
X324366Y-111532D01*
G01X334224Y-113865D02*
Y-102199D01*
G01Y-105115D02*
X335098Y-103657D01*
X336408Y-102490D01*
X338154Y-102199D01*
X339682Y-102490D01*
X340993Y-103657D01*
X341648Y-105698D01*
Y-113865D01*
G01X355436Y-96365D02*
Y-113865D01*
G01X352379Y-102199D02*
X358493D01*
G01X369224Y-113865D02*
Y-96365D01*
G01Y-104823D02*
X370316Y-103365D01*
X371408Y-102490D01*
X373154Y-102199D01*
X374464Y-102490D01*
X375993Y-103657D01*
X376648Y-105407D01*
Y-113865D01*
G01X387161Y-105990D02*
X394148D01*
X393493Y-103948D01*
X392401Y-102782D01*
X390873Y-102199D01*
X389344Y-102490D01*
X388034Y-103365D01*
X387161Y-105407D01*
X386724Y-107157D01*
Y-108907D01*
X387161Y-110657D01*
X388253Y-112407D01*
X389563Y-113573D01*
X391091Y-113865D01*
X392619Y-113282D01*
X394148Y-111532D01*
G01X404879Y-113865D02*
Y-102199D01*
G01Y-104532D02*
X405971Y-103365D01*
X407063Y-102490D01*
X408591Y-102199D01*
X409682Y-102490D01*
X410993Y-103365D01*
G01X437259Y-113865D02*
Y-96365D01*
X442936Y-110948D01*
X448613Y-96365D01*
Y-113865D01*
G01X462182Y-104532D02*
X463056Y-103657D01*
X463711Y-102199D01*
X464148Y-100156D01*
X463711Y-98407D01*
X462838Y-97240D01*
X461309Y-96365D01*
X455414D01*
Y-113865D01*
X462619D01*
X464148Y-112699D01*
X465021Y-110948D01*
X465458Y-108907D01*
X465021Y-106865D01*
X463711Y-105115D01*
X462182Y-104532D01*
X455414D01*
G01X102756Y290550D02*
G03Y298424I0J3937D01*
G01X133465D02*
G03Y290550I0J-3937D01*
G01X227259Y-68865D02*
Y-51365D01*
X232936Y-65948D01*
X238613Y-51365D01*
Y-68865D01*
G01X250436D02*
X249126Y-68573D01*
X247816Y-67407D01*
X246942Y-65365D01*
X246506Y-63032D01*
X246942Y-60698D01*
X247816Y-58657D01*
X249126Y-57490D01*
X250436Y-57199D01*
X251746Y-57490D01*
X253056Y-58657D01*
X253929Y-60698D01*
X254148Y-63032D01*
X253929Y-65365D01*
X253056Y-67407D01*
X251746Y-68573D01*
X250436Y-68865D01*
G01X271866Y-51365D02*
Y-68865D01*
G01Y-66241D02*
X270993Y-67699D01*
X269682Y-68573D01*
X268154Y-68865D01*
X266408Y-68282D01*
X265098Y-66824D01*
X264224Y-65074D01*
X264006Y-63032D01*
X264224Y-60990D01*
X265098Y-59240D01*
X266408Y-57782D01*
X268154Y-57199D01*
X269682Y-57490D01*
X270774Y-58074D01*
X271866Y-59240D01*
G01X282161Y-60990D02*
X289148D01*
X288493Y-58948D01*
X287401Y-57782D01*
X285873Y-57199D01*
X284344Y-57490D01*
X283034Y-58365D01*
X282161Y-60407D01*
X281724Y-62157D01*
Y-63907D01*
X282161Y-65657D01*
X283253Y-67407D01*
X284563Y-68573D01*
X286091Y-68865D01*
X287619Y-68282D01*
X289148Y-66532D01*
G01X302936Y-68865D02*
Y-51365D01*
G01X299606Y290551D02*
G03Y298425I0J3937D01*
G01X330314D02*
G03Y290551I0J-3937D01*
G01X496457Y290550D02*
G03Y298424I0J3937D01*
G01X527166D02*
G03Y290550I0J-3937D01*
G01X542319Y-68865D02*
Y-51365D01*
X547559D01*
X549306Y-52240D01*
X550616Y-54282D01*
X551053Y-56615D01*
X550616Y-58948D01*
X549524Y-60698D01*
X547559Y-61574D01*
X542319D01*
G01X568989Y-52824D02*
X567679Y-51948D01*
X566151Y-51365D01*
X564404D01*
X562439Y-52240D01*
X560911Y-53698D01*
X559819Y-55449D01*
X558946Y-58365D01*
X558727Y-60990D01*
X559164Y-63615D01*
X559819Y-65365D01*
X561129Y-67115D01*
X562658Y-68282D01*
X564186Y-68865D01*
X565714D01*
X567243Y-68282D01*
X568553Y-67407D01*
X569645Y-66241D01*
G01X583432Y-59532D02*
X584306Y-58657D01*
X584961Y-57199D01*
X585398Y-55156D01*
X584961Y-53407D01*
X584088Y-52240D01*
X582559Y-51365D01*
X576664D01*
Y-68865D01*
X583869D01*
X585398Y-67699D01*
X586271Y-65948D01*
X586708Y-63907D01*
X586271Y-61865D01*
X584961Y-60115D01*
X583432Y-59532D01*
X576664D01*
G01X592636Y-74698D02*
X605736D01*
G01X611664Y-68865D02*
Y-51365D01*
X621708Y-68865D01*
Y-51365D01*
G01X634186Y-68865D02*
X632439Y-68573D01*
X630911Y-67407D01*
X629601Y-65657D01*
X628727Y-63615D01*
X628291Y-61282D01*
Y-58948D01*
X628727Y-56615D01*
X629601Y-54573D01*
X630911Y-52824D01*
X632439Y-51657D01*
X634186Y-51365D01*
X635932Y-51657D01*
X637461Y-52824D01*
X638771Y-54573D01*
X639645Y-56615D01*
X640081Y-58948D01*
Y-61282D01*
X639645Y-63615D01*
X638771Y-65657D01*
X637461Y-67407D01*
X635932Y-68573D01*
X634186Y-68865D01*
G01X555436Y-113865D02*
Y-96365D01*
X552816Y-99865D01*
G01Y-113865D02*
X558056D01*
G01X568133Y-110365D02*
X569442Y-112407D01*
X571189Y-113573D01*
X573154Y-113865D01*
X574901Y-113573D01*
X576648Y-112115D01*
X577739Y-110365D01*
X577958Y-108615D01*
X577521Y-106574D01*
X575993Y-105115D01*
X574464Y-104532D01*
X572499D01*
G01X574464D02*
X575774Y-103657D01*
X576866Y-102199D01*
X577303Y-100449D01*
X576866Y-98698D01*
X575774Y-97240D01*
X573809Y-96365D01*
X571844Y-96657D01*
X569879Y-97824D01*
G01X590436Y-113865D02*
Y-96365D01*
X587816Y-99865D01*
G01Y-113865D02*
X593056D01*
G01X603133Y-110365D02*
X604442Y-112407D01*
X606189Y-113573D01*
X608154Y-113865D01*
X609901Y-113573D01*
X611648Y-112115D01*
X612739Y-110365D01*
X612958Y-108615D01*
X612521Y-106574D01*
X610993Y-105115D01*
X609464Y-104532D01*
X607499D01*
G01X609464D02*
X610774Y-103657D01*
X611866Y-102199D01*
X612303Y-100449D01*
X611866Y-98698D01*
X610774Y-97240D01*
X608809Y-96365D01*
X606844Y-96657D01*
X604879Y-97824D01*
G01X625436Y-96365D02*
X623689Y-96948D01*
X622379Y-98407D01*
X621506Y-100156D01*
X620851Y-102490D01*
X620633Y-105115D01*
X620851Y-107740D01*
X621506Y-110074D01*
X622379Y-111824D01*
X623689Y-113282D01*
X625436Y-113865D01*
X627182Y-113282D01*
X628493Y-111824D01*
X629366Y-110074D01*
X630021Y-107740D01*
X630239Y-105115D01*
X630021Y-102490D01*
X629366Y-100156D01*
X628493Y-98407D01*
X627182Y-96948D01*
X625436Y-96365D01*
G01X685027Y-51365D02*
X690486Y-68865D01*
X695945Y-51365D01*
G01X712353Y-68865D02*
X703619D01*
Y-51365D01*
X712353D01*
G01X708859Y-59823D02*
X703619D01*
G01X721119Y-68865D02*
Y-51365D01*
X726578D01*
X728324Y-52240D01*
X729416Y-53407D01*
X729853Y-55740D01*
X729416Y-58074D01*
X728106Y-59532D01*
X726578Y-60407D01*
X721119D01*
G01X726578D02*
X729853Y-68865D01*
G01X742986Y-69448D02*
X742549Y-69157D01*
Y-68573D01*
X742986Y-68282D01*
X743423Y-68573D01*
Y-69157D01*
X742986Y-69448D01*
G01X693308Y290550D02*
G03Y298424I0J3937D01*
G01X707986Y-113865D02*
Y-96365D01*
X705366Y-99865D01*
G01Y-113865D02*
X710606D01*
G01X727232Y-104532D02*
X728106Y-103657D01*
X728761Y-102199D01*
X729198Y-100156D01*
X728761Y-98407D01*
X727888Y-97240D01*
X726359Y-96365D01*
X720464D01*
Y-113865D01*
X727669D01*
X729198Y-112699D01*
X730071Y-110948D01*
X730508Y-108907D01*
X730071Y-106865D01*
X728761Y-105115D01*
X727232Y-104532D01*
X720464D01*
G01X724016Y298424D02*
G03Y290550I0J-3937D01*
G01X800393Y588976D02*
Y542913D01*
G01D02*
G03X804330Y538976I3937J0D01*
G01X858267Y588976D02*
X800393D01*
G01X818569Y-51365D02*
Y-68865D01*
X827303D01*
G01X844366D02*
Y-57199D01*
G01Y-59240D02*
X843493Y-58074D01*
X842182Y-57490D01*
X840654Y-57199D01*
X839126Y-57782D01*
X837816Y-58948D01*
X836942Y-60698D01*
X836506Y-63032D01*
X836942Y-65365D01*
X837816Y-67115D01*
X839126Y-68282D01*
X840654Y-68865D01*
X842182Y-68573D01*
X843493Y-67699D01*
X844366Y-66532D01*
G01X853351Y-74115D02*
X854661Y-74698D01*
X856408Y-74115D01*
X857499Y-72949D01*
X858373Y-71490D01*
X859682Y-66824D01*
X862521Y-57199D01*
G01X855534D02*
X859682Y-66824D01*
G01X872161Y-60990D02*
X879148D01*
X878493Y-58948D01*
X877401Y-57782D01*
X875873Y-57199D01*
X874344Y-57490D01*
X873034Y-58365D01*
X872161Y-60407D01*
X871724Y-62157D01*
Y-63907D01*
X872161Y-65657D01*
X873253Y-67407D01*
X874563Y-68573D01*
X876091Y-68865D01*
X877619Y-68282D01*
X879148Y-66532D01*
G01X889879Y-68865D02*
Y-57199D01*
G01Y-59532D02*
X890971Y-58365D01*
X892063Y-57490D01*
X893591Y-57199D01*
X894682Y-57490D01*
X895993Y-58365D01*
G01X804330Y538976D02*
X830708D01*
G01X831686Y-96365D02*
Y-113865D01*
G01X826664Y-96365D02*
X836708D01*
G01X844601Y-111532D02*
X846348Y-112990D01*
X848313Y-113865D01*
X850059D01*
X851806Y-112990D01*
X853116Y-111532D01*
X853771Y-109490D01*
X853334Y-107449D01*
X852243Y-105698D01*
X850278Y-104532D01*
X847658Y-103948D01*
X846129Y-102782D01*
X845474Y-100740D01*
X845911Y-98698D01*
X847003Y-97240D01*
X848531Y-96365D01*
X850059D01*
X851588Y-96948D01*
X852898Y-98407D01*
G01X861009Y-113865D02*
Y-96365D01*
X866686Y-110948D01*
X872363Y-96365D01*
Y-113865D01*
G01X879383D02*
Y-96365D01*
X883749D01*
X885496Y-97240D01*
X886806Y-98407D01*
X887898Y-100156D01*
X888771Y-102199D01*
X888989Y-105115D01*
X888771Y-108032D01*
X887898Y-110074D01*
X886806Y-111824D01*
X885496Y-112990D01*
X883749Y-113865D01*
X879383D01*
G01X834645Y72440D02*
G03X826771I-3937J0D01*
G01Y103149D02*
G03X834645I3937J0D01*
G01Y210235D02*
G03X826771I-3937J0D01*
G01Y240944D02*
G03X834645I3937J0D01*
G01Y348031D02*
G03X826771I-3937J0D01*
G01Y378739D02*
G03X834645I3937J0D01*
G01Y485826D02*
G03X826771I-3937J0D01*
G01Y516535D02*
G03X834645I3937J-1D01*
G01Y535039D02*
G03X830708Y538976I-3937J0D01*
G01X834645Y72440D02*
Y-1D01*
G01D02*
X858267D01*
G01X853444Y15747D02*
G03I-6988J0D01*
G01X834645Y210235D02*
Y103149D01*
G01Y348031D02*
Y240944D01*
G01Y485826D02*
Y378739D01*
G01Y535039D02*
Y516535D01*
G01X853444Y573227D02*
G03I-6988J0D01*
G01X862204Y3936D02*
Y585039D01*
G01X858267Y-1D02*
G03X862204Y3936I0J3937D01*
G01Y585039D02*
G03X858267Y588976I-3937J0D01*
G01X943619Y-110365D02*
X944711Y-112115D01*
X946021Y-113282D01*
X947549Y-113865D01*
X949296Y-113282D01*
X950606Y-112115D01*
X951916Y-110365D01*
X952353Y-108032D01*
Y-96365D01*
G01X965486Y-113865D02*
X963739Y-113573D01*
X962211Y-112407D01*
X960901Y-110657D01*
X960027Y-108615D01*
X959591Y-106282D01*
Y-103948D01*
X960027Y-101615D01*
X960901Y-99573D01*
X962211Y-97824D01*
X963739Y-96657D01*
X965486Y-96365D01*
X967232Y-96657D01*
X968761Y-97824D01*
X970071Y-99573D01*
X970945Y-101615D01*
X971381Y-103948D01*
Y-106282D01*
X970945Y-108615D01*
X970071Y-110657D01*
X968761Y-112407D01*
X967232Y-113573D01*
X965486Y-113865D01*
G01X978401Y-111532D02*
X980148Y-112990D01*
X982113Y-113865D01*
X983859D01*
X985606Y-112990D01*
X986916Y-111532D01*
X987571Y-109490D01*
X987134Y-107449D01*
X986043Y-105698D01*
X984078Y-104532D01*
X981458Y-103948D01*
X979929Y-102782D01*
X979274Y-100740D01*
X979711Y-98698D01*
X980803Y-97240D01*
X982331Y-96365D01*
X983859D01*
X985388Y-96948D01*
X986698Y-98407D01*
G01X1004853Y-113865D02*
X996119D01*
Y-96365D01*
X1004853D01*
G01X1001359Y-104823D02*
X996119D01*
G01X1013619Y-113865D02*
Y-96365D01*
X1018859D01*
X1020606Y-97240D01*
X1021916Y-99282D01*
X1022353Y-101615D01*
X1021916Y-103948D01*
X1020824Y-105698D01*
X1018859Y-106574D01*
X1013619D01*
G01X1030901Y-113865D02*
Y-96365D01*
G01X1040071D02*
Y-113865D01*
G01Y-105115D02*
X1030901D01*
G01X1066119Y-96365D02*
Y-113865D01*
X1074853D01*
G01X1082527D02*
X1087986Y-96365D01*
X1093445Y-113865D01*
G01X1091479Y-107740D02*
X1084492D01*
G01X1100683Y-96365D02*
Y-108907D01*
X1101556Y-111532D01*
X1103303Y-113282D01*
X1105486Y-113865D01*
X1107669Y-113282D01*
X1109416Y-111532D01*
X1110289Y-108907D01*
Y-96365D01*
G01X960683Y-68865D02*
Y-51365D01*
X965049D01*
X966796Y-52240D01*
X968106Y-53407D01*
X969198Y-55156D01*
X970071Y-57199D01*
X970289Y-60115D01*
X970071Y-63032D01*
X969198Y-65074D01*
X968106Y-66824D01*
X966796Y-67990D01*
X965049Y-68865D01*
X960683D01*
G01X979711Y-60990D02*
X986698D01*
X986043Y-58948D01*
X984951Y-57782D01*
X983423Y-57199D01*
X981894Y-57490D01*
X980584Y-58365D01*
X979711Y-60407D01*
X979274Y-62157D01*
Y-63907D01*
X979711Y-65657D01*
X980803Y-67407D01*
X982113Y-68573D01*
X983641Y-68865D01*
X985169Y-68282D01*
X986698Y-66532D01*
G01X997211Y-66824D02*
X998303Y-67990D01*
X999831Y-68865D01*
X1001141D01*
X1002451Y-68282D01*
X1003324Y-67407D01*
X1003761Y-66241D01*
X1003543Y-64490D01*
X1002669Y-63615D01*
X998739Y-61865D01*
X997866Y-59823D01*
X998303Y-58365D01*
X999176Y-57490D01*
X1000486Y-57199D01*
X1001796Y-57490D01*
X1003106Y-58365D01*
G01X1017986Y-57199D02*
Y-68865D01*
G01Y-52532D02*
X1017549Y-52240D01*
Y-51657D01*
X1017986Y-51365D01*
X1018423Y-51657D01*
Y-52240D01*
X1017986Y-52532D01*
G01X1032429Y-73240D02*
X1033958Y-74407D01*
X1035704Y-74698D01*
X1037232Y-74407D01*
X1038543Y-72949D01*
X1039416Y-70907D01*
Y-57199D01*
G01Y-59532D02*
X1038543Y-58365D01*
X1037232Y-57490D01*
X1035704Y-57199D01*
X1033958Y-57782D01*
X1032866Y-58948D01*
X1031992Y-60990D01*
X1031556Y-63032D01*
X1031774Y-64782D01*
X1032648Y-66824D01*
X1033958Y-68282D01*
X1035704Y-68865D01*
X1037014Y-68573D01*
X1038543Y-67407D01*
X1039416Y-66241D01*
G01X1049274Y-68865D02*
Y-57199D01*
G01Y-60115D02*
X1050148Y-58657D01*
X1051458Y-57490D01*
X1053204Y-57199D01*
X1054732Y-57490D01*
X1056043Y-58657D01*
X1056698Y-60698D01*
Y-68865D01*
G01X1067211Y-60990D02*
X1074198D01*
X1073543Y-58948D01*
X1072451Y-57782D01*
X1070923Y-57199D01*
X1069394Y-57490D01*
X1068084Y-58365D01*
X1067211Y-60407D01*
X1066774Y-62157D01*
Y-63907D01*
X1067211Y-65657D01*
X1068303Y-67407D01*
X1069613Y-68573D01*
X1071141Y-68865D01*
X1072669Y-68282D01*
X1074198Y-66532D01*
G01X1084929Y-68865D02*
Y-57199D01*
G01Y-59532D02*
X1086021Y-58365D01*
X1087113Y-57490D01*
X1088641Y-57199D01*
X1089732Y-57490D01*
X1091043Y-58365D01*
G01X1131686Y-113865D02*
Y-96365D01*
X1129066Y-99865D01*
G01Y-113865D02*
X1134306D01*
G01X1149186D02*
Y-96365D01*
X1146566Y-99865D01*
G01Y-113865D02*
X1151806D01*
G01X1162756Y-114448D02*
X1170616Y-96365D01*
G01X1184186Y-113865D02*
Y-96365D01*
X1181566Y-99865D01*
G01Y-113865D02*
X1186806D01*
G01X1196883Y-110365D02*
X1198192Y-112407D01*
X1199939Y-113573D01*
X1201904Y-113865D01*
X1203651Y-113573D01*
X1205398Y-112115D01*
X1206489Y-110365D01*
X1206708Y-108615D01*
X1206271Y-106574D01*
X1204743Y-105115D01*
X1203214Y-104532D01*
X1201249D01*
G01X1203214D02*
X1204524Y-103657D01*
X1205616Y-102199D01*
X1206053Y-100449D01*
X1205616Y-98698D01*
X1204524Y-97240D01*
X1202559Y-96365D01*
X1200594Y-96657D01*
X1198629Y-97824D01*
G01X1215256Y-114448D02*
X1223116Y-96365D01*
G01X1232538Y-99282D02*
X1233848Y-97532D01*
X1235376Y-96657D01*
X1237123Y-96365D01*
X1239306Y-96948D01*
X1240834Y-98407D01*
X1241271Y-100156D01*
X1241053Y-101907D01*
X1240179Y-103365D01*
X1235813Y-106282D01*
X1233848Y-108323D01*
X1232538Y-111241D01*
X1232101Y-113865D01*
X1241271D01*
G01X1254186Y-96365D02*
X1252439Y-96948D01*
X1251129Y-98407D01*
X1250256Y-100156D01*
X1249601Y-102490D01*
X1249383Y-105115D01*
X1249601Y-107740D01*
X1250256Y-110074D01*
X1251129Y-111824D01*
X1252439Y-113282D01*
X1254186Y-113865D01*
X1255932Y-113282D01*
X1257243Y-111824D01*
X1258116Y-110074D01*
X1258771Y-107740D01*
X1258989Y-105115D01*
X1258771Y-102490D01*
X1258116Y-100156D01*
X1257243Y-98407D01*
X1255932Y-96948D01*
X1254186Y-96365D01*
G01X1271686Y-113865D02*
Y-96365D01*
X1269066Y-99865D01*
G01Y-113865D02*
X1274306D01*
G01X1291806D02*
Y-96365D01*
X1283727Y-108907D01*
X1294645D01*
G01X1179383Y-68865D02*
Y-51365D01*
X1183749D01*
X1185496Y-52240D01*
X1186806Y-53407D01*
X1187898Y-55156D01*
X1188771Y-57199D01*
X1188989Y-60115D01*
X1188771Y-63032D01*
X1187898Y-65074D01*
X1186806Y-66824D01*
X1185496Y-67990D01*
X1183749Y-68865D01*
X1179383D01*
G01X1205616D02*
Y-57199D01*
G01Y-59240D02*
X1204743Y-58074D01*
X1203432Y-57490D01*
X1201904Y-57199D01*
X1200376Y-57782D01*
X1199066Y-58948D01*
X1198192Y-60698D01*
X1197756Y-63032D01*
X1198192Y-65365D01*
X1199066Y-67115D01*
X1200376Y-68282D01*
X1201904Y-68865D01*
X1203432Y-68573D01*
X1204743Y-67699D01*
X1205616Y-66532D01*
G01X1219186Y-51365D02*
Y-68865D01*
G01X1216129Y-57199D02*
X1222243D01*
G01X1233411Y-60990D02*
X1240398D01*
X1239743Y-58948D01*
X1238651Y-57782D01*
X1237123Y-57199D01*
X1235594Y-57490D01*
X1234284Y-58365D01*
X1233411Y-60407D01*
X1232974Y-62157D01*
Y-63907D01*
X1233411Y-65657D01*
X1234503Y-67407D01*
X1235813Y-68573D01*
X1237341Y-68865D01*
X1238869Y-68282D01*
X1240398Y-66532D01*
G54D35*
X54000Y127000D03*
X60600Y208500D03*
X73000Y132000D03*
X70200Y265800D03*
X86400Y206600D03*
X98900Y203700D03*
X118500Y131500D03*
X153200Y216000D03*
X150200D03*
X167400Y155600D03*
X182500Y91000D03*
X187600Y149200D03*
X184500D03*
X183500Y188500D03*
X178800Y203600D03*
X181800D03*
X197700Y51500D03*
X194700D03*
X188400Y206250D03*
X216000Y167500D03*
X217700Y191500D03*
X253500Y55000D03*
X250500D03*
X277000Y228300D03*
X274000D03*
X293300Y157500D03*
X314500Y244000D03*
X448000Y254500D03*
X537500Y61000D03*
X538500Y84500D03*
X534500Y210000D03*
X555300Y211100D03*
X585500Y83000D03*
X591500D03*
X594500D03*
X597500Y235000D03*
X616000Y109000D03*
X613000D03*
X609400Y235000D03*
X612500D03*
X619500D03*
X724700Y126400D03*
X721000Y143500D03*
X717000Y193500D03*
X718500Y209900D03*
X733500Y172000D03*
X744500Y192500D03*
Y239000D03*
G54D71*
X232791Y82260D03*
Y89740D03*
X241209Y86000D03*
X248591Y102060D03*
Y109540D03*
X257009Y105800D03*
X273791Y193260D03*
Y200740D03*
X282209Y197000D03*
G54D62*
X170760Y189000D03*
X174500Y181000D03*
X178240Y189000D03*
G54D44*
X99331Y70650D03*
X115669D03*
X531331Y195500D03*
X547669D03*
G54D53*
X143220Y78955D03*
Y80925D03*
Y82895D03*
Y84860D03*
Y86830D03*
Y88800D03*
Y90770D03*
Y92735D03*
Y94705D03*
Y96675D03*
Y98640D03*
Y100610D03*
Y102580D03*
Y104545D03*
Y106515D03*
Y108485D03*
Y110455D03*
Y112420D03*
Y114390D03*
Y116360D03*
Y118325D03*
Y120295D03*
Y122265D03*
Y124230D03*
Y126200D03*
Y128170D03*
Y130140D03*
Y132105D03*
Y134075D03*
Y136045D03*
X165755Y78955D03*
Y80925D03*
Y82895D03*
Y84860D03*
Y86830D03*
Y88800D03*
Y90770D03*
Y92735D03*
Y94705D03*
Y96675D03*
Y98640D03*
Y100610D03*
Y102580D03*
Y104545D03*
Y106515D03*
Y108485D03*
Y110455D03*
Y112420D03*
Y114390D03*
Y116360D03*
Y118325D03*
Y120295D03*
Y122265D03*
Y124230D03*
Y126200D03*
Y128170D03*
Y130140D03*
Y132105D03*
Y134075D03*
Y136045D03*
G54D17*
X26100Y97900D03*
Y103100D03*
X39300Y111500D03*
Y116700D03*
X68800Y133400D03*
Y138600D03*
X71800Y170400D03*
Y175600D03*
X92000Y167900D03*
Y173100D03*
X94420Y252800D03*
Y258000D03*
X109000Y124900D03*
Y130100D03*
X103500Y124900D03*
Y130100D03*
X101000Y243500D03*
Y248700D03*
X99420Y252800D03*
Y258000D03*
X114500Y124900D03*
Y130100D03*
X121000Y214900D03*
Y220100D03*
X135500Y150100D03*
Y155300D03*
X160500Y195900D03*
Y201100D03*
X187200Y137500D03*
Y142700D03*
X214000Y171000D03*
Y176200D03*
X209800Y199400D03*
Y204600D03*
X513500Y188400D03*
Y193600D03*
X512500Y219400D03*
Y224600D03*
X517500Y219400D03*
Y224600D03*
X674200Y47407D03*
Y52607D03*
X720500Y55900D03*
X715500D03*
X720500Y61100D03*
X715500D03*
X742500Y60900D03*
Y66100D03*
X732300Y102100D03*
Y107300D03*
X747500Y60900D03*
Y66100D03*
X764500Y149900D03*
Y155100D03*
G54D26*
X46850Y126000D03*
X211350Y210500D03*
G54D119*
X792515Y137280D03*
G54D80*
X317132Y102711D03*
X313932Y105911D03*
Y102711D03*
X317132Y105911D03*
X320332Y102711D03*
Y105911D03*
X323532Y102711D03*
X313932Y109111D03*
X317132D03*
X320332D03*
X313932Y112311D03*
Y115511D03*
Y196351D03*
Y193151D03*
Y202751D03*
X317132Y205951D03*
X313932D03*
X323532D03*
X320332D03*
X317132Y199551D03*
X313932D03*
X317132Y202751D03*
X320332Y199551D03*
Y202751D03*
X326732Y102711D03*
Y205951D03*
X431192Y102711D03*
X427992D03*
Y205951D03*
X431192D03*
X437592Y105911D03*
X434392Y102711D03*
Y105911D03*
X440792Y109111D03*
X437592D03*
X434392D03*
X440792Y112311D03*
Y115511D03*
Y196351D03*
Y193151D03*
Y202751D03*
Y205951D03*
X437592D03*
X434392D03*
X437592Y199551D03*
X434392Y202751D03*
Y199551D03*
X440792D03*
X437592Y202751D03*
G54D36*
X54000Y124000D03*
X60600Y205500D03*
X73000Y129000D03*
X70200Y262800D03*
X86400Y203600D03*
X98900Y200700D03*
X118500Y128500D03*
X153200Y213000D03*
X150200D03*
X167400Y152600D03*
X182500Y88000D03*
X187600Y146200D03*
X184500D03*
X183500Y185500D03*
X178800Y200600D03*
X181800D03*
X197700Y48500D03*
X194700D03*
X188400Y203250D03*
X216000Y164500D03*
X217700Y188500D03*
X253500Y52000D03*
X250500D03*
X277000Y225300D03*
X274000D03*
X293300Y154500D03*
X314500Y241000D03*
X448000Y251500D03*
X537500Y58000D03*
X538500Y81500D03*
X534500Y207000D03*
X555300Y208100D03*
X585500Y80000D03*
X591500D03*
X594500D03*
X597500Y232000D03*
X616000Y106000D03*
X613000D03*
X609400Y232000D03*
X612500D03*
X619500D03*
X724700Y123400D03*
X721000Y140500D03*
X717000Y190500D03*
X718500Y206900D03*
X733500Y169000D03*
X744500Y189500D03*
Y236000D03*
G54D45*
X111500Y89850D03*
Y113150D03*
G54D54*
X136800Y260189D03*
G54D63*
X172811Y226000D03*
Y221000D03*
Y231000D03*
G54D72*
X224984Y196795D03*
X223016D03*
Y207205D03*
X224984D03*
G54D81*
X313392Y118471D03*
Y136191D03*
Y130531D03*
Y124131D03*
Y148261D03*
Y141861D03*
Y165991D03*
Y153921D03*
Y159591D03*
Y177311D03*
Y171651D03*
Y189381D03*
Y183711D03*
X441332Y119281D03*
Y131351D03*
Y124951D03*
Y149071D03*
Y137011D03*
Y142671D03*
Y166801D03*
Y160401D03*
Y154741D03*
Y172471D03*
Y178131D03*
Y190191D03*
Y184531D03*
G54D18*
X20000Y116100D03*
Y110900D03*
Y129600D03*
Y124400D03*
X72500Y90900D03*
Y96100D03*
X72400Y198000D03*
X77400D03*
X72400Y203200D03*
X77400D03*
X108550Y146600D03*
Y141400D03*
X177000Y134900D03*
Y140100D03*
X204000Y197400D03*
X198200Y197401D03*
X204000Y202600D03*
X198200Y202601D03*
X198500Y258600D03*
Y253400D03*
X255000Y225600D03*
Y220400D03*
X287500Y160100D03*
Y154900D03*
X507000Y224600D03*
Y219400D03*
X522500Y224600D03*
Y219400D03*
X605300Y235600D03*
Y230400D03*
X740000Y238600D03*
Y233400D03*
X749800Y105700D03*
Y110900D03*
G36*
G01X506496Y35416D02*
X506371Y35426D01*
X506246Y35466D01*
X506136Y35526D01*
X506036Y35606D01*
X505956Y35706D01*
X505896Y35816D01*
X505856Y35941D01*
X505846Y36066D01*
Y37196D01*
X505816Y37226D01*
X505716Y37366D01*
X505696Y37406D01*
X505681Y37441D01*
X505661Y37481D01*
X505646Y37521D01*
X505636Y37561D01*
X505621Y37606D01*
X505616Y37646D01*
X505606Y37686D01*
X505601Y37731D01*
Y37771D01*
X505596Y37816D01*
X505601Y37861D01*
Y37901D01*
X505606Y37946D01*
X505616Y37986D01*
X505621Y38026D01*
X505636Y38071D01*
X505646Y38111D01*
X505661Y38151D01*
X505681Y38191D01*
X505696Y38226D01*
X505716Y38266D01*
X505816Y38406D01*
X505846Y38436D01*
Y41866D01*
X505856Y41991D01*
X505896Y42116D01*
X505956Y42226D01*
X506036Y42326D01*
X506136Y42406D01*
X506246Y42466D01*
X506371Y42506D01*
X506496Y42516D01*
X506621Y42506D01*
X506746Y42466D01*
X506856Y42406D01*
X506956Y42326D01*
X507036Y42226D01*
X507096Y42116D01*
X507136Y41991D01*
X507146Y41866D01*
Y38436D01*
X507176Y38406D01*
X507276Y38266D01*
X507296Y38226D01*
X507311Y38191D01*
X507331Y38151D01*
X507346Y38111D01*
X507356Y38071D01*
X507371Y38026D01*
X507376Y37986D01*
X507386Y37946D01*
X507391Y37901D01*
Y37861D01*
X507396Y37816D01*
X507391Y37771D01*
Y37731D01*
X507386Y37686D01*
X507376Y37646D01*
X507371Y37606D01*
X507356Y37561D01*
X507346Y37521D01*
X507331Y37481D01*
X507311Y37441D01*
X507296Y37406D01*
X507276Y37366D01*
X507176Y37226D01*
X507146Y37196D01*
Y36066D01*
X507136Y35941D01*
X507096Y35816D01*
X507036Y35706D01*
X506956Y35606D01*
X506856Y35526D01*
X506746Y35466D01*
X506621Y35426D01*
X506496Y35416D01*
G37*
G36*
G01X525393D02*
X525268Y35426D01*
X525143Y35466D01*
X525033Y35526D01*
X524933Y35606D01*
X524853Y35706D01*
X524793Y35816D01*
X524753Y35941D01*
X524743Y36066D01*
Y37196D01*
X524713Y37226D01*
X524613Y37366D01*
X524593Y37406D01*
X524578Y37441D01*
X524558Y37481D01*
X524543Y37521D01*
X524533Y37561D01*
X524518Y37606D01*
X524513Y37646D01*
X524503Y37686D01*
X524498Y37731D01*
Y37771D01*
X524493Y37816D01*
X524498Y37861D01*
Y37901D01*
X524503Y37946D01*
X524513Y37986D01*
X524518Y38026D01*
X524533Y38071D01*
X524543Y38111D01*
X524558Y38151D01*
X524578Y38191D01*
X524593Y38226D01*
X524613Y38266D01*
X524713Y38406D01*
X524743Y38436D01*
Y41866D01*
X524753Y41991D01*
X524793Y42116D01*
X524853Y42226D01*
X524933Y42326D01*
X525033Y42406D01*
X525143Y42466D01*
X525268Y42506D01*
X525393Y42516D01*
X525518Y42506D01*
X525643Y42466D01*
X525753Y42406D01*
X525853Y42326D01*
X525933Y42226D01*
X525993Y42116D01*
X526033Y41991D01*
X526043Y41866D01*
Y38436D01*
X526073Y38406D01*
X526173Y38266D01*
X526193Y38226D01*
X526208Y38191D01*
X526228Y38151D01*
X526243Y38111D01*
X526253Y38071D01*
X526268Y38026D01*
X526273Y37986D01*
X526283Y37946D01*
X526288Y37901D01*
Y37861D01*
X526293Y37816D01*
X526288Y37771D01*
Y37731D01*
X526283Y37686D01*
X526273Y37646D01*
X526268Y37606D01*
X526253Y37561D01*
X526243Y37521D01*
X526228Y37481D01*
X526208Y37441D01*
X526193Y37406D01*
X526173Y37366D01*
X526073Y37226D01*
X526043Y37196D01*
Y36066D01*
X526033Y35941D01*
X525993Y35816D01*
X525933Y35706D01*
X525853Y35606D01*
X525753Y35526D01*
X525643Y35466D01*
X525518Y35426D01*
X525393Y35416D01*
G37*
G36*
G01X520669D02*
X520544Y35426D01*
X520419Y35466D01*
X520309Y35526D01*
X520209Y35606D01*
X520129Y35706D01*
X520069Y35816D01*
X520029Y35941D01*
X520019Y36066D01*
Y37196D01*
X519989Y37226D01*
X519889Y37366D01*
X519869Y37406D01*
X519854Y37441D01*
X519834Y37481D01*
X519819Y37521D01*
X519809Y37561D01*
X519794Y37606D01*
X519789Y37646D01*
X519779Y37686D01*
X519774Y37731D01*
Y37771D01*
X519769Y37816D01*
X519774Y37861D01*
Y37901D01*
X519779Y37946D01*
X519789Y37986D01*
X519794Y38026D01*
X519809Y38071D01*
X519819Y38111D01*
X519834Y38151D01*
X519854Y38191D01*
X519869Y38226D01*
X519889Y38266D01*
X519989Y38406D01*
X520019Y38436D01*
Y41866D01*
X520029Y41991D01*
X520069Y42116D01*
X520129Y42226D01*
X520209Y42326D01*
X520309Y42406D01*
X520419Y42466D01*
X520544Y42506D01*
X520669Y42516D01*
X520794Y42506D01*
X520919Y42466D01*
X521029Y42406D01*
X521129Y42326D01*
X521209Y42226D01*
X521269Y42116D01*
X521309Y41991D01*
X521319Y41866D01*
Y38436D01*
X521349Y38406D01*
X521449Y38266D01*
X521469Y38226D01*
X521484Y38191D01*
X521504Y38151D01*
X521519Y38111D01*
X521529Y38071D01*
X521544Y38026D01*
X521549Y37986D01*
X521559Y37946D01*
X521564Y37901D01*
Y37861D01*
X521569Y37816D01*
X521564Y37771D01*
Y37731D01*
X521559Y37686D01*
X521549Y37646D01*
X521544Y37606D01*
X521529Y37561D01*
X521519Y37521D01*
X521504Y37481D01*
X521484Y37441D01*
X521469Y37406D01*
X521449Y37366D01*
X521349Y37226D01*
X521319Y37196D01*
Y36066D01*
X521309Y35941D01*
X521269Y35816D01*
X521209Y35706D01*
X521129Y35606D01*
X521029Y35526D01*
X520919Y35466D01*
X520794Y35426D01*
X520669Y35416D01*
G37*
G36*
G01X515945D02*
X515820Y35426D01*
X515695Y35466D01*
X515585Y35526D01*
X515485Y35606D01*
X515405Y35706D01*
X515345Y35816D01*
X515305Y35941D01*
X515295Y36066D01*
Y37196D01*
X515265Y37226D01*
X515165Y37366D01*
X515145Y37406D01*
X515130Y37441D01*
X515110Y37481D01*
X515095Y37521D01*
X515085Y37561D01*
X515070Y37606D01*
X515065Y37646D01*
X515055Y37686D01*
X515050Y37731D01*
Y37771D01*
X515045Y37816D01*
X515050Y37861D01*
Y37901D01*
X515055Y37946D01*
X515065Y37986D01*
X515070Y38026D01*
X515085Y38071D01*
X515095Y38111D01*
X515110Y38151D01*
X515130Y38191D01*
X515145Y38226D01*
X515165Y38266D01*
X515265Y38406D01*
X515295Y38436D01*
Y41866D01*
X515305Y41991D01*
X515345Y42116D01*
X515405Y42226D01*
X515485Y42326D01*
X515585Y42406D01*
X515695Y42466D01*
X515820Y42506D01*
X515945Y42516D01*
X516070Y42506D01*
X516195Y42466D01*
X516305Y42406D01*
X516405Y42326D01*
X516485Y42226D01*
X516545Y42116D01*
X516585Y41991D01*
X516595Y41866D01*
Y38436D01*
X516625Y38406D01*
X516725Y38266D01*
X516745Y38226D01*
X516760Y38191D01*
X516780Y38151D01*
X516795Y38111D01*
X516805Y38071D01*
X516820Y38026D01*
X516825Y37986D01*
X516835Y37946D01*
X516840Y37901D01*
Y37861D01*
X516845Y37816D01*
X516840Y37771D01*
Y37731D01*
X516835Y37686D01*
X516825Y37646D01*
X516820Y37606D01*
X516805Y37561D01*
X516795Y37521D01*
X516780Y37481D01*
X516760Y37441D01*
X516745Y37406D01*
X516725Y37366D01*
X516625Y37226D01*
X516595Y37196D01*
Y36066D01*
X516585Y35941D01*
X516545Y35816D01*
X516485Y35706D01*
X516405Y35606D01*
X516305Y35526D01*
X516195Y35466D01*
X516070Y35426D01*
X515945Y35416D01*
G37*
G36*
G01X511220D02*
X511095Y35426D01*
X510970Y35466D01*
X510860Y35526D01*
X510760Y35606D01*
X510680Y35706D01*
X510620Y35816D01*
X510580Y35941D01*
X510570Y36066D01*
Y37196D01*
X510540Y37226D01*
X510440Y37366D01*
X510420Y37406D01*
X510405Y37441D01*
X510385Y37481D01*
X510370Y37521D01*
X510360Y37561D01*
X510345Y37606D01*
X510340Y37646D01*
X510330Y37686D01*
X510325Y37731D01*
Y37771D01*
X510320Y37816D01*
X510325Y37861D01*
Y37901D01*
X510330Y37946D01*
X510340Y37986D01*
X510345Y38026D01*
X510360Y38071D01*
X510370Y38111D01*
X510385Y38151D01*
X510405Y38191D01*
X510420Y38226D01*
X510440Y38266D01*
X510540Y38406D01*
X510570Y38436D01*
Y41866D01*
X510580Y41991D01*
X510620Y42116D01*
X510680Y42226D01*
X510760Y42326D01*
X510860Y42406D01*
X510970Y42466D01*
X511095Y42506D01*
X511220Y42516D01*
X511345Y42506D01*
X511470Y42466D01*
X511580Y42406D01*
X511680Y42326D01*
X511760Y42226D01*
X511820Y42116D01*
X511860Y41991D01*
X511870Y41866D01*
Y38436D01*
X511900Y38406D01*
X512000Y38266D01*
X512020Y38226D01*
X512035Y38191D01*
X512055Y38151D01*
X512070Y38111D01*
X512080Y38071D01*
X512095Y38026D01*
X512100Y37986D01*
X512110Y37946D01*
X512115Y37901D01*
Y37861D01*
X512120Y37816D01*
X512115Y37771D01*
Y37731D01*
X512110Y37686D01*
X512100Y37646D01*
X512095Y37606D01*
X512080Y37561D01*
X512070Y37521D01*
X512055Y37481D01*
X512035Y37441D01*
X512020Y37406D01*
X512000Y37366D01*
X511900Y37226D01*
X511870Y37196D01*
Y36066D01*
X511860Y35941D01*
X511820Y35816D01*
X511760Y35706D01*
X511680Y35606D01*
X511580Y35526D01*
X511470Y35466D01*
X511345Y35426D01*
X511220Y35416D01*
G37*
G36*
G01X539567D02*
X539442Y35426D01*
X539317Y35466D01*
X539207Y35526D01*
X539107Y35606D01*
X539027Y35706D01*
X538967Y35816D01*
X538927Y35941D01*
X538917Y36066D01*
Y37196D01*
X538887Y37226D01*
X538787Y37366D01*
X538767Y37406D01*
X538752Y37441D01*
X538732Y37481D01*
X538717Y37521D01*
X538707Y37561D01*
X538692Y37606D01*
X538687Y37646D01*
X538677Y37686D01*
X538672Y37731D01*
Y37771D01*
X538667Y37816D01*
X538672Y37861D01*
Y37901D01*
X538677Y37946D01*
X538687Y37986D01*
X538692Y38026D01*
X538707Y38071D01*
X538717Y38111D01*
X538732Y38151D01*
X538752Y38191D01*
X538767Y38226D01*
X538787Y38266D01*
X538887Y38406D01*
X538917Y38436D01*
Y41866D01*
X538927Y41991D01*
X538967Y42116D01*
X539027Y42226D01*
X539107Y42326D01*
X539207Y42406D01*
X539317Y42466D01*
X539442Y42506D01*
X539567Y42516D01*
X539692Y42506D01*
X539817Y42466D01*
X539927Y42406D01*
X540027Y42326D01*
X540107Y42226D01*
X540167Y42116D01*
X540207Y41991D01*
X540217Y41866D01*
Y38436D01*
X540247Y38406D01*
X540347Y38266D01*
X540367Y38226D01*
X540382Y38191D01*
X540402Y38151D01*
X540417Y38111D01*
X540427Y38071D01*
X540442Y38026D01*
X540447Y37986D01*
X540457Y37946D01*
X540462Y37901D01*
Y37861D01*
X540467Y37816D01*
X540462Y37771D01*
Y37731D01*
X540457Y37686D01*
X540447Y37646D01*
X540442Y37606D01*
X540427Y37561D01*
X540417Y37521D01*
X540402Y37481D01*
X540382Y37441D01*
X540367Y37406D01*
X540347Y37366D01*
X540247Y37226D01*
X540217Y37196D01*
Y36066D01*
X540207Y35941D01*
X540167Y35816D01*
X540107Y35706D01*
X540027Y35606D01*
X539927Y35526D01*
X539817Y35466D01*
X539692Y35426D01*
X539567Y35416D01*
G37*
G36*
G01X534842D02*
X534717Y35426D01*
X534592Y35466D01*
X534482Y35526D01*
X534382Y35606D01*
X534302Y35706D01*
X534242Y35816D01*
X534202Y35941D01*
X534192Y36066D01*
Y37196D01*
X534162Y37226D01*
X534062Y37366D01*
X534042Y37406D01*
X534027Y37441D01*
X534007Y37481D01*
X533992Y37521D01*
X533982Y37561D01*
X533967Y37606D01*
X533962Y37646D01*
X533952Y37686D01*
X533947Y37731D01*
Y37771D01*
X533942Y37816D01*
X533947Y37861D01*
Y37901D01*
X533952Y37946D01*
X533962Y37986D01*
X533967Y38026D01*
X533982Y38071D01*
X533992Y38111D01*
X534007Y38151D01*
X534027Y38191D01*
X534042Y38226D01*
X534062Y38266D01*
X534162Y38406D01*
X534192Y38436D01*
Y41866D01*
X534202Y41991D01*
X534242Y42116D01*
X534302Y42226D01*
X534382Y42326D01*
X534482Y42406D01*
X534592Y42466D01*
X534717Y42506D01*
X534842Y42516D01*
X534967Y42506D01*
X535092Y42466D01*
X535202Y42406D01*
X535302Y42326D01*
X535382Y42226D01*
X535442Y42116D01*
X535482Y41991D01*
X535492Y41866D01*
Y38436D01*
X535522Y38406D01*
X535622Y38266D01*
X535642Y38226D01*
X535657Y38191D01*
X535677Y38151D01*
X535692Y38111D01*
X535702Y38071D01*
X535717Y38026D01*
X535722Y37986D01*
X535732Y37946D01*
X535737Y37901D01*
Y37861D01*
X535742Y37816D01*
X535737Y37771D01*
Y37731D01*
X535732Y37686D01*
X535722Y37646D01*
X535717Y37606D01*
X535702Y37561D01*
X535692Y37521D01*
X535677Y37481D01*
X535657Y37441D01*
X535642Y37406D01*
X535622Y37366D01*
X535522Y37226D01*
X535492Y37196D01*
Y36066D01*
X535482Y35941D01*
X535442Y35816D01*
X535382Y35706D01*
X535302Y35606D01*
X535202Y35526D01*
X535092Y35466D01*
X534967Y35426D01*
X534842Y35416D01*
G37*
G36*
G01X530118D02*
X529993Y35426D01*
X529868Y35466D01*
X529758Y35526D01*
X529658Y35606D01*
X529578Y35706D01*
X529518Y35816D01*
X529478Y35941D01*
X529468Y36066D01*
Y37196D01*
X529438Y37226D01*
X529338Y37366D01*
X529318Y37406D01*
X529303Y37441D01*
X529283Y37481D01*
X529268Y37521D01*
X529258Y37561D01*
X529243Y37606D01*
X529238Y37646D01*
X529228Y37686D01*
X529223Y37731D01*
Y37771D01*
X529218Y37816D01*
X529223Y37861D01*
Y37901D01*
X529228Y37946D01*
X529238Y37986D01*
X529243Y38026D01*
X529258Y38071D01*
X529268Y38111D01*
X529283Y38151D01*
X529303Y38191D01*
X529318Y38226D01*
X529338Y38266D01*
X529438Y38406D01*
X529468Y38436D01*
Y41866D01*
X529478Y41991D01*
X529518Y42116D01*
X529578Y42226D01*
X529658Y42326D01*
X529758Y42406D01*
X529868Y42466D01*
X529993Y42506D01*
X530118Y42516D01*
X530243Y42506D01*
X530368Y42466D01*
X530478Y42406D01*
X530578Y42326D01*
X530658Y42226D01*
X530718Y42116D01*
X530758Y41991D01*
X530768Y41866D01*
Y38436D01*
X530798Y38406D01*
X530898Y38266D01*
X530918Y38226D01*
X530933Y38191D01*
X530953Y38151D01*
X530968Y38111D01*
X530978Y38071D01*
X530993Y38026D01*
X530998Y37986D01*
X531008Y37946D01*
X531013Y37901D01*
Y37861D01*
X531018Y37816D01*
X531013Y37771D01*
Y37731D01*
X531008Y37686D01*
X530998Y37646D01*
X530993Y37606D01*
X530978Y37561D01*
X530968Y37521D01*
X530953Y37481D01*
X530933Y37441D01*
X530918Y37406D01*
X530898Y37366D01*
X530798Y37226D01*
X530768Y37196D01*
Y36066D01*
X530758Y35941D01*
X530718Y35816D01*
X530658Y35706D01*
X530578Y35606D01*
X530478Y35526D01*
X530368Y35466D01*
X530243Y35426D01*
X530118Y35416D01*
G37*
G36*
G01X553740D02*
X553615Y35426D01*
X553490Y35466D01*
X553380Y35526D01*
X553280Y35606D01*
X553200Y35706D01*
X553140Y35816D01*
X553100Y35941D01*
X553090Y36066D01*
Y37196D01*
X553060Y37226D01*
X552960Y37366D01*
X552940Y37406D01*
X552925Y37441D01*
X552905Y37481D01*
X552890Y37521D01*
X552880Y37561D01*
X552865Y37606D01*
X552860Y37646D01*
X552850Y37686D01*
X552845Y37731D01*
Y37771D01*
X552840Y37816D01*
X552845Y37861D01*
Y37901D01*
X552850Y37946D01*
X552860Y37986D01*
X552865Y38026D01*
X552880Y38071D01*
X552890Y38111D01*
X552905Y38151D01*
X552925Y38191D01*
X552940Y38226D01*
X552960Y38266D01*
X553060Y38406D01*
X553090Y38436D01*
Y41866D01*
X553100Y41991D01*
X553140Y42116D01*
X553200Y42226D01*
X553280Y42326D01*
X553380Y42406D01*
X553490Y42466D01*
X553615Y42506D01*
X553740Y42516D01*
X553865Y42506D01*
X553990Y42466D01*
X554100Y42406D01*
X554200Y42326D01*
X554280Y42226D01*
X554340Y42116D01*
X554380Y41991D01*
X554390Y41866D01*
Y38436D01*
X554420Y38406D01*
X554520Y38266D01*
X554540Y38226D01*
X554555Y38191D01*
X554575Y38151D01*
X554590Y38111D01*
X554600Y38071D01*
X554615Y38026D01*
X554620Y37986D01*
X554630Y37946D01*
X554635Y37901D01*
Y37861D01*
X554640Y37816D01*
X554635Y37771D01*
Y37731D01*
X554630Y37686D01*
X554620Y37646D01*
X554615Y37606D01*
X554600Y37561D01*
X554590Y37521D01*
X554575Y37481D01*
X554555Y37441D01*
X554540Y37406D01*
X554520Y37366D01*
X554420Y37226D01*
X554390Y37196D01*
Y36066D01*
X554380Y35941D01*
X554340Y35816D01*
X554280Y35706D01*
X554200Y35606D01*
X554100Y35526D01*
X553990Y35466D01*
X553865Y35426D01*
X553740Y35416D01*
G37*
G36*
G01X549015D02*
X548890Y35426D01*
X548765Y35466D01*
X548655Y35526D01*
X548555Y35606D01*
X548475Y35706D01*
X548415Y35816D01*
X548375Y35941D01*
X548365Y36066D01*
Y37196D01*
X548335Y37226D01*
X548235Y37366D01*
X548215Y37406D01*
X548200Y37441D01*
X548180Y37481D01*
X548165Y37521D01*
X548155Y37561D01*
X548140Y37606D01*
X548135Y37646D01*
X548125Y37686D01*
X548120Y37731D01*
Y37771D01*
X548115Y37816D01*
X548120Y37861D01*
Y37901D01*
X548125Y37946D01*
X548135Y37986D01*
X548140Y38026D01*
X548155Y38071D01*
X548165Y38111D01*
X548180Y38151D01*
X548200Y38191D01*
X548215Y38226D01*
X548235Y38266D01*
X548335Y38406D01*
X548365Y38436D01*
Y41866D01*
X548375Y41991D01*
X548415Y42116D01*
X548475Y42226D01*
X548555Y42326D01*
X548655Y42406D01*
X548765Y42466D01*
X548890Y42506D01*
X549015Y42516D01*
X549140Y42506D01*
X549265Y42466D01*
X549375Y42406D01*
X549475Y42326D01*
X549555Y42226D01*
X549615Y42116D01*
X549655Y41991D01*
X549665Y41866D01*
Y38436D01*
X549695Y38406D01*
X549795Y38266D01*
X549815Y38226D01*
X549830Y38191D01*
X549850Y38151D01*
X549865Y38111D01*
X549875Y38071D01*
X549890Y38026D01*
X549895Y37986D01*
X549905Y37946D01*
X549910Y37901D01*
Y37861D01*
X549915Y37816D01*
X549910Y37771D01*
Y37731D01*
X549905Y37686D01*
X549895Y37646D01*
X549890Y37606D01*
X549875Y37561D01*
X549865Y37521D01*
X549850Y37481D01*
X549830Y37441D01*
X549815Y37406D01*
X549795Y37366D01*
X549695Y37226D01*
X549665Y37196D01*
Y36066D01*
X549655Y35941D01*
X549615Y35816D01*
X549555Y35706D01*
X549475Y35606D01*
X549375Y35526D01*
X549265Y35466D01*
X549140Y35426D01*
X549015Y35416D01*
G37*
G36*
G01X544291D02*
X544166Y35426D01*
X544041Y35466D01*
X543931Y35526D01*
X543831Y35606D01*
X543751Y35706D01*
X543691Y35816D01*
X543651Y35941D01*
X543641Y36066D01*
Y37196D01*
X543611Y37226D01*
X543511Y37366D01*
X543491Y37406D01*
X543476Y37441D01*
X543456Y37481D01*
X543441Y37521D01*
X543431Y37561D01*
X543416Y37606D01*
X543411Y37646D01*
X543401Y37686D01*
X543396Y37731D01*
Y37771D01*
X543391Y37816D01*
X543396Y37861D01*
Y37901D01*
X543401Y37946D01*
X543411Y37986D01*
X543416Y38026D01*
X543431Y38071D01*
X543441Y38111D01*
X543456Y38151D01*
X543476Y38191D01*
X543491Y38226D01*
X543511Y38266D01*
X543611Y38406D01*
X543641Y38436D01*
Y41866D01*
X543651Y41991D01*
X543691Y42116D01*
X543751Y42226D01*
X543831Y42326D01*
X543931Y42406D01*
X544041Y42466D01*
X544166Y42506D01*
X544291Y42516D01*
X544416Y42506D01*
X544541Y42466D01*
X544651Y42406D01*
X544751Y42326D01*
X544831Y42226D01*
X544891Y42116D01*
X544931Y41991D01*
X544941Y41866D01*
Y38436D01*
X544971Y38406D01*
X545071Y38266D01*
X545091Y38226D01*
X545106Y38191D01*
X545126Y38151D01*
X545141Y38111D01*
X545151Y38071D01*
X545166Y38026D01*
X545171Y37986D01*
X545181Y37946D01*
X545186Y37901D01*
Y37861D01*
X545191Y37816D01*
X545186Y37771D01*
Y37731D01*
X545181Y37686D01*
X545171Y37646D01*
X545166Y37606D01*
X545151Y37561D01*
X545141Y37521D01*
X545126Y37481D01*
X545106Y37441D01*
X545091Y37406D01*
X545071Y37366D01*
X544971Y37226D01*
X544941Y37196D01*
Y36066D01*
X544931Y35941D01*
X544891Y35816D01*
X544831Y35706D01*
X544751Y35606D01*
X544651Y35526D01*
X544541Y35466D01*
X544416Y35426D01*
X544291Y35416D01*
G37*
G36*
G01X572638D02*
X572513Y35426D01*
X572388Y35466D01*
X572278Y35526D01*
X572178Y35606D01*
X572098Y35706D01*
X572038Y35816D01*
X571998Y35941D01*
X571988Y36066D01*
Y37196D01*
X571958Y37226D01*
X571858Y37366D01*
X571838Y37406D01*
X571823Y37441D01*
X571803Y37481D01*
X571788Y37521D01*
X571778Y37561D01*
X571763Y37606D01*
X571758Y37646D01*
X571748Y37686D01*
X571743Y37731D01*
Y37771D01*
X571738Y37816D01*
X571743Y37861D01*
Y37901D01*
X571748Y37946D01*
X571758Y37986D01*
X571763Y38026D01*
X571778Y38071D01*
X571788Y38111D01*
X571803Y38151D01*
X571823Y38191D01*
X571838Y38226D01*
X571858Y38266D01*
X571958Y38406D01*
X571988Y38436D01*
Y41866D01*
X571998Y41991D01*
X572038Y42116D01*
X572098Y42226D01*
X572178Y42326D01*
X572278Y42406D01*
X572388Y42466D01*
X572513Y42506D01*
X572638Y42516D01*
X572763Y42506D01*
X572888Y42466D01*
X572998Y42406D01*
X573098Y42326D01*
X573178Y42226D01*
X573238Y42116D01*
X573278Y41991D01*
X573288Y41866D01*
Y38436D01*
X573318Y38406D01*
X573418Y38266D01*
X573438Y38226D01*
X573453Y38191D01*
X573473Y38151D01*
X573488Y38111D01*
X573498Y38071D01*
X573513Y38026D01*
X573518Y37986D01*
X573528Y37946D01*
X573533Y37901D01*
Y37861D01*
X573538Y37816D01*
X573533Y37771D01*
Y37731D01*
X573528Y37686D01*
X573518Y37646D01*
X573513Y37606D01*
X573498Y37561D01*
X573488Y37521D01*
X573473Y37481D01*
X573453Y37441D01*
X573438Y37406D01*
X573418Y37366D01*
X573318Y37226D01*
X573288Y37196D01*
Y36066D01*
X573278Y35941D01*
X573238Y35816D01*
X573178Y35706D01*
X573098Y35606D01*
X572998Y35526D01*
X572888Y35466D01*
X572763Y35426D01*
X572638Y35416D01*
G37*
G36*
G01X567913D02*
X567788Y35426D01*
X567663Y35466D01*
X567553Y35526D01*
X567453Y35606D01*
X567373Y35706D01*
X567313Y35816D01*
X567273Y35941D01*
X567263Y36066D01*
Y37196D01*
X567233Y37226D01*
X567133Y37366D01*
X567113Y37406D01*
X567098Y37441D01*
X567078Y37481D01*
X567063Y37521D01*
X567053Y37561D01*
X567038Y37606D01*
X567033Y37646D01*
X567023Y37686D01*
X567018Y37731D01*
Y37771D01*
X567013Y37816D01*
X567018Y37861D01*
Y37901D01*
X567023Y37946D01*
X567033Y37986D01*
X567038Y38026D01*
X567053Y38071D01*
X567063Y38111D01*
X567078Y38151D01*
X567098Y38191D01*
X567113Y38226D01*
X567133Y38266D01*
X567233Y38406D01*
X567263Y38436D01*
Y41866D01*
X567273Y41991D01*
X567313Y42116D01*
X567373Y42226D01*
X567453Y42326D01*
X567553Y42406D01*
X567663Y42466D01*
X567788Y42506D01*
X567913Y42516D01*
X568038Y42506D01*
X568163Y42466D01*
X568273Y42406D01*
X568373Y42326D01*
X568453Y42226D01*
X568513Y42116D01*
X568553Y41991D01*
X568563Y41866D01*
Y38436D01*
X568593Y38406D01*
X568693Y38266D01*
X568713Y38226D01*
X568728Y38191D01*
X568748Y38151D01*
X568763Y38111D01*
X568773Y38071D01*
X568788Y38026D01*
X568793Y37986D01*
X568803Y37946D01*
X568808Y37901D01*
Y37861D01*
X568813Y37816D01*
X568808Y37771D01*
Y37731D01*
X568803Y37686D01*
X568793Y37646D01*
X568788Y37606D01*
X568773Y37561D01*
X568763Y37521D01*
X568748Y37481D01*
X568728Y37441D01*
X568713Y37406D01*
X568693Y37366D01*
X568593Y37226D01*
X568563Y37196D01*
Y36066D01*
X568553Y35941D01*
X568513Y35816D01*
X568453Y35706D01*
X568373Y35606D01*
X568273Y35526D01*
X568163Y35466D01*
X568038Y35426D01*
X567913Y35416D01*
G37*
G36*
G01X563189D02*
X563064Y35426D01*
X562939Y35466D01*
X562829Y35526D01*
X562729Y35606D01*
X562649Y35706D01*
X562589Y35816D01*
X562549Y35941D01*
X562539Y36066D01*
Y37196D01*
X562509Y37226D01*
X562409Y37366D01*
X562389Y37406D01*
X562374Y37441D01*
X562354Y37481D01*
X562339Y37521D01*
X562329Y37561D01*
X562314Y37606D01*
X562309Y37646D01*
X562299Y37686D01*
X562294Y37731D01*
Y37771D01*
X562289Y37816D01*
X562294Y37861D01*
Y37901D01*
X562299Y37946D01*
X562309Y37986D01*
X562314Y38026D01*
X562329Y38071D01*
X562339Y38111D01*
X562354Y38151D01*
X562374Y38191D01*
X562389Y38226D01*
X562409Y38266D01*
X562509Y38406D01*
X562539Y38436D01*
Y41866D01*
X562549Y41991D01*
X562589Y42116D01*
X562649Y42226D01*
X562729Y42326D01*
X562829Y42406D01*
X562939Y42466D01*
X563064Y42506D01*
X563189Y42516D01*
X563314Y42506D01*
X563439Y42466D01*
X563549Y42406D01*
X563649Y42326D01*
X563729Y42226D01*
X563789Y42116D01*
X563829Y41991D01*
X563839Y41866D01*
Y38436D01*
X563869Y38406D01*
X563969Y38266D01*
X563989Y38226D01*
X564004Y38191D01*
X564024Y38151D01*
X564039Y38111D01*
X564049Y38071D01*
X564064Y38026D01*
X564069Y37986D01*
X564079Y37946D01*
X564084Y37901D01*
Y37861D01*
X564089Y37816D01*
X564084Y37771D01*
Y37731D01*
X564079Y37686D01*
X564069Y37646D01*
X564064Y37606D01*
X564049Y37561D01*
X564039Y37521D01*
X564024Y37481D01*
X564004Y37441D01*
X563989Y37406D01*
X563969Y37366D01*
X563869Y37226D01*
X563839Y37196D01*
Y36066D01*
X563829Y35941D01*
X563789Y35816D01*
X563729Y35706D01*
X563649Y35606D01*
X563549Y35526D01*
X563439Y35466D01*
X563314Y35426D01*
X563189Y35416D01*
G37*
G36*
G01X558464D02*
X558339Y35426D01*
X558214Y35466D01*
X558104Y35526D01*
X558004Y35606D01*
X557924Y35706D01*
X557864Y35816D01*
X557824Y35941D01*
X557814Y36066D01*
Y37196D01*
X557784Y37226D01*
X557684Y37366D01*
X557664Y37406D01*
X557649Y37441D01*
X557629Y37481D01*
X557614Y37521D01*
X557604Y37561D01*
X557589Y37606D01*
X557584Y37646D01*
X557574Y37686D01*
X557569Y37731D01*
Y37771D01*
X557564Y37816D01*
X557569Y37861D01*
Y37901D01*
X557574Y37946D01*
X557584Y37986D01*
X557589Y38026D01*
X557604Y38071D01*
X557614Y38111D01*
X557629Y38151D01*
X557649Y38191D01*
X557664Y38226D01*
X557684Y38266D01*
X557784Y38406D01*
X557814Y38436D01*
Y41866D01*
X557824Y41991D01*
X557864Y42116D01*
X557924Y42226D01*
X558004Y42326D01*
X558104Y42406D01*
X558214Y42466D01*
X558339Y42506D01*
X558464Y42516D01*
X558589Y42506D01*
X558714Y42466D01*
X558824Y42406D01*
X558924Y42326D01*
X559004Y42226D01*
X559064Y42116D01*
X559104Y41991D01*
X559114Y41866D01*
Y38436D01*
X559144Y38406D01*
X559244Y38266D01*
X559264Y38226D01*
X559279Y38191D01*
X559299Y38151D01*
X559314Y38111D01*
X559324Y38071D01*
X559339Y38026D01*
X559344Y37986D01*
X559354Y37946D01*
X559359Y37901D01*
Y37861D01*
X559364Y37816D01*
X559359Y37771D01*
Y37731D01*
X559354Y37686D01*
X559344Y37646D01*
X559339Y37606D01*
X559324Y37561D01*
X559314Y37521D01*
X559299Y37481D01*
X559279Y37441D01*
X559264Y37406D01*
X559244Y37366D01*
X559144Y37226D01*
X559114Y37196D01*
Y36066D01*
X559104Y35941D01*
X559064Y35816D01*
X559004Y35706D01*
X558924Y35606D01*
X558824Y35526D01*
X558714Y35466D01*
X558589Y35426D01*
X558464Y35416D01*
G37*
G36*
G01X586811D02*
X586686Y35426D01*
X586561Y35466D01*
X586451Y35526D01*
X586351Y35606D01*
X586271Y35706D01*
X586211Y35816D01*
X586171Y35941D01*
X586161Y36066D01*
Y37196D01*
X586131Y37226D01*
X586031Y37366D01*
X586011Y37406D01*
X585996Y37441D01*
X585976Y37481D01*
X585961Y37521D01*
X585951Y37561D01*
X585936Y37606D01*
X585931Y37646D01*
X585921Y37686D01*
X585916Y37731D01*
Y37771D01*
X585911Y37816D01*
X585916Y37861D01*
Y37901D01*
X585921Y37946D01*
X585931Y37986D01*
X585936Y38026D01*
X585951Y38071D01*
X585961Y38111D01*
X585976Y38151D01*
X585996Y38191D01*
X586011Y38226D01*
X586031Y38266D01*
X586131Y38406D01*
X586161Y38436D01*
Y41866D01*
X586171Y41991D01*
X586211Y42116D01*
X586271Y42226D01*
X586351Y42326D01*
X586451Y42406D01*
X586561Y42466D01*
X586686Y42506D01*
X586811Y42516D01*
X586936Y42506D01*
X587061Y42466D01*
X587171Y42406D01*
X587271Y42326D01*
X587351Y42226D01*
X587411Y42116D01*
X587451Y41991D01*
X587461Y41866D01*
Y38436D01*
X587491Y38406D01*
X587591Y38266D01*
X587611Y38226D01*
X587626Y38191D01*
X587646Y38151D01*
X587661Y38111D01*
X587671Y38071D01*
X587686Y38026D01*
X587691Y37986D01*
X587701Y37946D01*
X587706Y37901D01*
Y37861D01*
X587711Y37816D01*
X587706Y37771D01*
Y37731D01*
X587701Y37686D01*
X587691Y37646D01*
X587686Y37606D01*
X587671Y37561D01*
X587661Y37521D01*
X587646Y37481D01*
X587626Y37441D01*
X587611Y37406D01*
X587591Y37366D01*
X587491Y37226D01*
X587461Y37196D01*
Y36066D01*
X587451Y35941D01*
X587411Y35816D01*
X587351Y35706D01*
X587271Y35606D01*
X587171Y35526D01*
X587061Y35466D01*
X586936Y35426D01*
X586811Y35416D01*
G37*
G36*
G01X582086D02*
X581961Y35426D01*
X581836Y35466D01*
X581726Y35526D01*
X581626Y35606D01*
X581546Y35706D01*
X581486Y35816D01*
X581446Y35941D01*
X581436Y36066D01*
Y37196D01*
X581406Y37226D01*
X581306Y37366D01*
X581286Y37406D01*
X581271Y37441D01*
X581251Y37481D01*
X581236Y37521D01*
X581226Y37561D01*
X581211Y37606D01*
X581206Y37646D01*
X581196Y37686D01*
X581191Y37731D01*
Y37771D01*
X581186Y37816D01*
X581191Y37861D01*
Y37901D01*
X581196Y37946D01*
X581206Y37986D01*
X581211Y38026D01*
X581226Y38071D01*
X581236Y38111D01*
X581251Y38151D01*
X581271Y38191D01*
X581286Y38226D01*
X581306Y38266D01*
X581406Y38406D01*
X581436Y38436D01*
Y41866D01*
X581446Y41991D01*
X581486Y42116D01*
X581546Y42226D01*
X581626Y42326D01*
X581726Y42406D01*
X581836Y42466D01*
X581961Y42506D01*
X582086Y42516D01*
X582211Y42506D01*
X582336Y42466D01*
X582446Y42406D01*
X582546Y42326D01*
X582626Y42226D01*
X582686Y42116D01*
X582726Y41991D01*
X582736Y41866D01*
Y38436D01*
X582766Y38406D01*
X582866Y38266D01*
X582886Y38226D01*
X582901Y38191D01*
X582921Y38151D01*
X582936Y38111D01*
X582946Y38071D01*
X582961Y38026D01*
X582966Y37986D01*
X582976Y37946D01*
X582981Y37901D01*
Y37861D01*
X582986Y37816D01*
X582981Y37771D01*
Y37731D01*
X582976Y37686D01*
X582966Y37646D01*
X582961Y37606D01*
X582946Y37561D01*
X582936Y37521D01*
X582921Y37481D01*
X582901Y37441D01*
X582886Y37406D01*
X582866Y37366D01*
X582766Y37226D01*
X582736Y37196D01*
Y36066D01*
X582726Y35941D01*
X582686Y35816D01*
X582626Y35706D01*
X582546Y35606D01*
X582446Y35526D01*
X582336Y35466D01*
X582211Y35426D01*
X582086Y35416D01*
G37*
G36*
G01X577362D02*
X577237Y35426D01*
X577112Y35466D01*
X577002Y35526D01*
X576902Y35606D01*
X576822Y35706D01*
X576762Y35816D01*
X576722Y35941D01*
X576712Y36066D01*
Y37196D01*
X576682Y37226D01*
X576582Y37366D01*
X576562Y37406D01*
X576547Y37441D01*
X576527Y37481D01*
X576512Y37521D01*
X576502Y37561D01*
X576487Y37606D01*
X576482Y37646D01*
X576472Y37686D01*
X576467Y37731D01*
Y37771D01*
X576462Y37816D01*
X576467Y37861D01*
Y37901D01*
X576472Y37946D01*
X576482Y37986D01*
X576487Y38026D01*
X576502Y38071D01*
X576512Y38111D01*
X576527Y38151D01*
X576547Y38191D01*
X576562Y38226D01*
X576582Y38266D01*
X576682Y38406D01*
X576712Y38436D01*
Y41866D01*
X576722Y41991D01*
X576762Y42116D01*
X576822Y42226D01*
X576902Y42326D01*
X577002Y42406D01*
X577112Y42466D01*
X577237Y42506D01*
X577362Y42516D01*
X577487Y42506D01*
X577612Y42466D01*
X577722Y42406D01*
X577822Y42326D01*
X577902Y42226D01*
X577962Y42116D01*
X578002Y41991D01*
X578012Y41866D01*
Y38436D01*
X578042Y38406D01*
X578142Y38266D01*
X578162Y38226D01*
X578177Y38191D01*
X578197Y38151D01*
X578212Y38111D01*
X578222Y38071D01*
X578237Y38026D01*
X578242Y37986D01*
X578252Y37946D01*
X578257Y37901D01*
Y37861D01*
X578262Y37816D01*
X578257Y37771D01*
Y37731D01*
X578252Y37686D01*
X578242Y37646D01*
X578237Y37606D01*
X578222Y37561D01*
X578212Y37521D01*
X578197Y37481D01*
X578177Y37441D01*
X578162Y37406D01*
X578142Y37366D01*
X578042Y37226D01*
X578012Y37196D01*
Y36066D01*
X578002Y35941D01*
X577962Y35816D01*
X577902Y35706D01*
X577822Y35606D01*
X577722Y35526D01*
X577612Y35466D01*
X577487Y35426D01*
X577362Y35416D01*
G37*
G36*
G01X600984D02*
X600859Y35426D01*
X600734Y35466D01*
X600624Y35526D01*
X600524Y35606D01*
X600444Y35706D01*
X600384Y35816D01*
X600344Y35941D01*
X600334Y36066D01*
Y37196D01*
X600304Y37226D01*
X600204Y37366D01*
X600184Y37406D01*
X600169Y37441D01*
X600149Y37481D01*
X600134Y37521D01*
X600124Y37561D01*
X600109Y37606D01*
X600104Y37646D01*
X600094Y37686D01*
X600089Y37731D01*
Y37771D01*
X600084Y37816D01*
X600089Y37861D01*
Y37901D01*
X600094Y37946D01*
X600104Y37986D01*
X600109Y38026D01*
X600124Y38071D01*
X600134Y38111D01*
X600149Y38151D01*
X600169Y38191D01*
X600184Y38226D01*
X600204Y38266D01*
X600304Y38406D01*
X600334Y38436D01*
Y41866D01*
X600344Y41991D01*
X600384Y42116D01*
X600444Y42226D01*
X600524Y42326D01*
X600624Y42406D01*
X600734Y42466D01*
X600859Y42506D01*
X600984Y42516D01*
X601109Y42506D01*
X601234Y42466D01*
X601344Y42406D01*
X601444Y42326D01*
X601524Y42226D01*
X601584Y42116D01*
X601624Y41991D01*
X601634Y41866D01*
Y38436D01*
X601664Y38406D01*
X601764Y38266D01*
X601784Y38226D01*
X601799Y38191D01*
X601819Y38151D01*
X601834Y38111D01*
X601844Y38071D01*
X601859Y38026D01*
X601864Y37986D01*
X601874Y37946D01*
X601879Y37901D01*
Y37861D01*
X601884Y37816D01*
X601879Y37771D01*
Y37731D01*
X601874Y37686D01*
X601864Y37646D01*
X601859Y37606D01*
X601844Y37561D01*
X601834Y37521D01*
X601819Y37481D01*
X601799Y37441D01*
X601784Y37406D01*
X601764Y37366D01*
X601664Y37226D01*
X601634Y37196D01*
Y36066D01*
X601624Y35941D01*
X601584Y35816D01*
X601524Y35706D01*
X601444Y35606D01*
X601344Y35526D01*
X601234Y35466D01*
X601109Y35426D01*
X600984Y35416D01*
G37*
G36*
G01X615157D02*
X615032Y35426D01*
X614907Y35466D01*
X614797Y35526D01*
X614697Y35606D01*
X614617Y35706D01*
X614557Y35816D01*
X614517Y35941D01*
X614507Y36066D01*
Y37196D01*
X614477Y37226D01*
X614377Y37366D01*
X614357Y37406D01*
X614342Y37441D01*
X614322Y37481D01*
X614307Y37521D01*
X614297Y37561D01*
X614282Y37606D01*
X614277Y37646D01*
X614267Y37686D01*
X614262Y37731D01*
Y37771D01*
X614257Y37816D01*
X614262Y37861D01*
Y37901D01*
X614267Y37946D01*
X614277Y37986D01*
X614282Y38026D01*
X614297Y38071D01*
X614307Y38111D01*
X614322Y38151D01*
X614342Y38191D01*
X614357Y38226D01*
X614377Y38266D01*
X614477Y38406D01*
X614507Y38436D01*
Y41866D01*
X614517Y41991D01*
X614557Y42116D01*
X614617Y42226D01*
X614697Y42326D01*
X614797Y42406D01*
X614907Y42466D01*
X615032Y42506D01*
X615157Y42516D01*
X615282Y42506D01*
X615407Y42466D01*
X615517Y42406D01*
X615617Y42326D01*
X615697Y42226D01*
X615757Y42116D01*
X615797Y41991D01*
X615807Y41866D01*
Y38436D01*
X615837Y38406D01*
X615937Y38266D01*
X615957Y38226D01*
X615972Y38191D01*
X615992Y38151D01*
X616007Y38111D01*
X616017Y38071D01*
X616032Y38026D01*
X616037Y37986D01*
X616047Y37946D01*
X616052Y37901D01*
Y37861D01*
X616057Y37816D01*
X616052Y37771D01*
Y37731D01*
X616047Y37686D01*
X616037Y37646D01*
X616032Y37606D01*
X616017Y37561D01*
X616007Y37521D01*
X615992Y37481D01*
X615972Y37441D01*
X615957Y37406D01*
X615937Y37366D01*
X615837Y37226D01*
X615807Y37196D01*
Y36066D01*
X615797Y35941D01*
X615757Y35816D01*
X615697Y35706D01*
X615617Y35606D01*
X615517Y35526D01*
X615407Y35466D01*
X615282Y35426D01*
X615157Y35416D01*
G37*
G36*
G01X610433D02*
X610308Y35426D01*
X610183Y35466D01*
X610073Y35526D01*
X609973Y35606D01*
X609893Y35706D01*
X609833Y35816D01*
X609793Y35941D01*
X609783Y36066D01*
Y37196D01*
X609753Y37226D01*
X609653Y37366D01*
X609633Y37406D01*
X609618Y37441D01*
X609598Y37481D01*
X609583Y37521D01*
X609573Y37561D01*
X609558Y37606D01*
X609553Y37646D01*
X609543Y37686D01*
X609538Y37731D01*
Y37771D01*
X609533Y37816D01*
X609538Y37861D01*
Y37901D01*
X609543Y37946D01*
X609553Y37986D01*
X609558Y38026D01*
X609573Y38071D01*
X609583Y38111D01*
X609598Y38151D01*
X609618Y38191D01*
X609633Y38226D01*
X609653Y38266D01*
X609753Y38406D01*
X609783Y38436D01*
Y41866D01*
X609793Y41991D01*
X609833Y42116D01*
X609893Y42226D01*
X609973Y42326D01*
X610073Y42406D01*
X610183Y42466D01*
X610308Y42506D01*
X610433Y42516D01*
X610558Y42506D01*
X610683Y42466D01*
X610793Y42406D01*
X610893Y42326D01*
X610973Y42226D01*
X611033Y42116D01*
X611073Y41991D01*
X611083Y41866D01*
Y38436D01*
X611113Y38406D01*
X611213Y38266D01*
X611233Y38226D01*
X611248Y38191D01*
X611268Y38151D01*
X611283Y38111D01*
X611293Y38071D01*
X611308Y38026D01*
X611313Y37986D01*
X611323Y37946D01*
X611328Y37901D01*
Y37861D01*
X611333Y37816D01*
X611328Y37771D01*
Y37731D01*
X611323Y37686D01*
X611313Y37646D01*
X611308Y37606D01*
X611293Y37561D01*
X611283Y37521D01*
X611268Y37481D01*
X611248Y37441D01*
X611233Y37406D01*
X611213Y37366D01*
X611113Y37226D01*
X611083Y37196D01*
Y36066D01*
X611073Y35941D01*
X611033Y35816D01*
X610973Y35706D01*
X610893Y35606D01*
X610793Y35526D01*
X610683Y35466D01*
X610558Y35426D01*
X610433Y35416D01*
G37*
G36*
G01X605708D02*
X605583Y35426D01*
X605458Y35466D01*
X605348Y35526D01*
X605248Y35606D01*
X605168Y35706D01*
X605108Y35816D01*
X605068Y35941D01*
X605058Y36066D01*
Y37196D01*
X605028Y37226D01*
X604928Y37366D01*
X604908Y37406D01*
X604893Y37441D01*
X604873Y37481D01*
X604858Y37521D01*
X604848Y37561D01*
X604833Y37606D01*
X604828Y37646D01*
X604818Y37686D01*
X604813Y37731D01*
Y37771D01*
X604808Y37816D01*
X604813Y37861D01*
Y37901D01*
X604818Y37946D01*
X604828Y37986D01*
X604833Y38026D01*
X604848Y38071D01*
X604858Y38111D01*
X604873Y38151D01*
X604893Y38191D01*
X604908Y38226D01*
X604928Y38266D01*
X605028Y38406D01*
X605058Y38436D01*
Y41866D01*
X605068Y41991D01*
X605108Y42116D01*
X605168Y42226D01*
X605248Y42326D01*
X605348Y42406D01*
X605458Y42466D01*
X605583Y42506D01*
X605708Y42516D01*
X605833Y42506D01*
X605958Y42466D01*
X606068Y42406D01*
X606168Y42326D01*
X606248Y42226D01*
X606308Y42116D01*
X606348Y41991D01*
X606358Y41866D01*
Y38436D01*
X606388Y38406D01*
X606488Y38266D01*
X606508Y38226D01*
X606523Y38191D01*
X606543Y38151D01*
X606558Y38111D01*
X606568Y38071D01*
X606583Y38026D01*
X606588Y37986D01*
X606598Y37946D01*
X606603Y37901D01*
Y37861D01*
X606608Y37816D01*
X606603Y37771D01*
Y37731D01*
X606598Y37686D01*
X606588Y37646D01*
X606583Y37606D01*
X606568Y37561D01*
X606558Y37521D01*
X606543Y37481D01*
X606523Y37441D01*
X606508Y37406D01*
X606488Y37366D01*
X606388Y37226D01*
X606358Y37196D01*
Y36066D01*
X606348Y35941D01*
X606308Y35816D01*
X606248Y35706D01*
X606168Y35606D01*
X606068Y35526D01*
X605958Y35466D01*
X605833Y35426D01*
X605708Y35416D01*
G37*
G36*
G01X634055D02*
X633930Y35426D01*
X633805Y35466D01*
X633695Y35526D01*
X633595Y35606D01*
X633515Y35706D01*
X633455Y35816D01*
X633415Y35941D01*
X633405Y36066D01*
Y37196D01*
X633375Y37226D01*
X633275Y37366D01*
X633255Y37406D01*
X633240Y37441D01*
X633220Y37481D01*
X633205Y37521D01*
X633195Y37561D01*
X633180Y37606D01*
X633175Y37646D01*
X633165Y37686D01*
X633160Y37731D01*
Y37771D01*
X633155Y37816D01*
X633160Y37861D01*
Y37901D01*
X633165Y37946D01*
X633175Y37986D01*
X633180Y38026D01*
X633195Y38071D01*
X633205Y38111D01*
X633220Y38151D01*
X633240Y38191D01*
X633255Y38226D01*
X633275Y38266D01*
X633375Y38406D01*
X633405Y38436D01*
Y41866D01*
X633415Y41991D01*
X633455Y42116D01*
X633515Y42226D01*
X633595Y42326D01*
X633695Y42406D01*
X633805Y42466D01*
X633930Y42506D01*
X634055Y42516D01*
X634180Y42506D01*
X634305Y42466D01*
X634415Y42406D01*
X634515Y42326D01*
X634595Y42226D01*
X634655Y42116D01*
X634695Y41991D01*
X634705Y41866D01*
Y38436D01*
X634735Y38406D01*
X634835Y38266D01*
X634855Y38226D01*
X634870Y38191D01*
X634890Y38151D01*
X634905Y38111D01*
X634915Y38071D01*
X634930Y38026D01*
X634935Y37986D01*
X634945Y37946D01*
X634950Y37901D01*
Y37861D01*
X634955Y37816D01*
X634950Y37771D01*
Y37731D01*
X634945Y37686D01*
X634935Y37646D01*
X634930Y37606D01*
X634915Y37561D01*
X634905Y37521D01*
X634890Y37481D01*
X634870Y37441D01*
X634855Y37406D01*
X634835Y37366D01*
X634735Y37226D01*
X634705Y37196D01*
Y36066D01*
X634695Y35941D01*
X634655Y35816D01*
X634595Y35706D01*
X634515Y35606D01*
X634415Y35526D01*
X634305Y35466D01*
X634180Y35426D01*
X634055Y35416D01*
G37*
G36*
G01X629330D02*
X629205Y35426D01*
X629080Y35466D01*
X628970Y35526D01*
X628870Y35606D01*
X628790Y35706D01*
X628730Y35816D01*
X628690Y35941D01*
X628680Y36066D01*
Y37196D01*
X628650Y37226D01*
X628550Y37366D01*
X628530Y37406D01*
X628515Y37441D01*
X628495Y37481D01*
X628480Y37521D01*
X628470Y37561D01*
X628455Y37606D01*
X628450Y37646D01*
X628440Y37686D01*
X628435Y37731D01*
Y37771D01*
X628430Y37816D01*
X628435Y37861D01*
Y37901D01*
X628440Y37946D01*
X628450Y37986D01*
X628455Y38026D01*
X628470Y38071D01*
X628480Y38111D01*
X628495Y38151D01*
X628515Y38191D01*
X628530Y38226D01*
X628550Y38266D01*
X628650Y38406D01*
X628680Y38436D01*
Y41866D01*
X628690Y41991D01*
X628730Y42116D01*
X628790Y42226D01*
X628870Y42326D01*
X628970Y42406D01*
X629080Y42466D01*
X629205Y42506D01*
X629330Y42516D01*
X629455Y42506D01*
X629580Y42466D01*
X629690Y42406D01*
X629790Y42326D01*
X629870Y42226D01*
X629930Y42116D01*
X629970Y41991D01*
X629980Y41866D01*
Y38436D01*
X630010Y38406D01*
X630110Y38266D01*
X630130Y38226D01*
X630145Y38191D01*
X630165Y38151D01*
X630180Y38111D01*
X630190Y38071D01*
X630205Y38026D01*
X630210Y37986D01*
X630220Y37946D01*
X630225Y37901D01*
Y37861D01*
X630230Y37816D01*
X630225Y37771D01*
Y37731D01*
X630220Y37686D01*
X630210Y37646D01*
X630205Y37606D01*
X630190Y37561D01*
X630180Y37521D01*
X630165Y37481D01*
X630145Y37441D01*
X630130Y37406D01*
X630110Y37366D01*
X630010Y37226D01*
X629980Y37196D01*
Y36066D01*
X629970Y35941D01*
X629930Y35816D01*
X629870Y35706D01*
X629790Y35606D01*
X629690Y35526D01*
X629580Y35466D01*
X629455Y35426D01*
X629330Y35416D01*
G37*
G36*
G01X624606D02*
X624481Y35426D01*
X624356Y35466D01*
X624246Y35526D01*
X624146Y35606D01*
X624066Y35706D01*
X624006Y35816D01*
X623966Y35941D01*
X623956Y36066D01*
Y37196D01*
X623926Y37226D01*
X623826Y37366D01*
X623806Y37406D01*
X623791Y37441D01*
X623771Y37481D01*
X623756Y37521D01*
X623746Y37561D01*
X623731Y37606D01*
X623726Y37646D01*
X623716Y37686D01*
X623711Y37731D01*
Y37771D01*
X623706Y37816D01*
X623711Y37861D01*
Y37901D01*
X623716Y37946D01*
X623726Y37986D01*
X623731Y38026D01*
X623746Y38071D01*
X623756Y38111D01*
X623771Y38151D01*
X623791Y38191D01*
X623806Y38226D01*
X623826Y38266D01*
X623926Y38406D01*
X623956Y38436D01*
Y41866D01*
X623966Y41991D01*
X624006Y42116D01*
X624066Y42226D01*
X624146Y42326D01*
X624246Y42406D01*
X624356Y42466D01*
X624481Y42506D01*
X624606Y42516D01*
X624731Y42506D01*
X624856Y42466D01*
X624966Y42406D01*
X625066Y42326D01*
X625146Y42226D01*
X625206Y42116D01*
X625246Y41991D01*
X625256Y41866D01*
Y38436D01*
X625286Y38406D01*
X625386Y38266D01*
X625406Y38226D01*
X625421Y38191D01*
X625441Y38151D01*
X625456Y38111D01*
X625466Y38071D01*
X625481Y38026D01*
X625486Y37986D01*
X625496Y37946D01*
X625501Y37901D01*
Y37861D01*
X625506Y37816D01*
X625501Y37771D01*
Y37731D01*
X625496Y37686D01*
X625486Y37646D01*
X625481Y37606D01*
X625466Y37561D01*
X625456Y37521D01*
X625441Y37481D01*
X625421Y37441D01*
X625406Y37406D01*
X625386Y37366D01*
X625286Y37226D01*
X625256Y37196D01*
Y36066D01*
X625246Y35941D01*
X625206Y35816D01*
X625146Y35706D01*
X625066Y35606D01*
X624966Y35526D01*
X624856Y35466D01*
X624731Y35426D01*
X624606Y35416D01*
G37*
G36*
G01X619882D02*
X619757Y35426D01*
X619632Y35466D01*
X619522Y35526D01*
X619422Y35606D01*
X619342Y35706D01*
X619282Y35816D01*
X619242Y35941D01*
X619232Y36066D01*
Y37196D01*
X619202Y37226D01*
X619102Y37366D01*
X619082Y37406D01*
X619067Y37441D01*
X619047Y37481D01*
X619032Y37521D01*
X619022Y37561D01*
X619007Y37606D01*
X619002Y37646D01*
X618992Y37686D01*
X618987Y37731D01*
Y37771D01*
X618982Y37816D01*
X618987Y37861D01*
Y37901D01*
X618992Y37946D01*
X619002Y37986D01*
X619007Y38026D01*
X619022Y38071D01*
X619032Y38111D01*
X619047Y38151D01*
X619067Y38191D01*
X619082Y38226D01*
X619102Y38266D01*
X619202Y38406D01*
X619232Y38436D01*
Y41866D01*
X619242Y41991D01*
X619282Y42116D01*
X619342Y42226D01*
X619422Y42326D01*
X619522Y42406D01*
X619632Y42466D01*
X619757Y42506D01*
X619882Y42516D01*
X620007Y42506D01*
X620132Y42466D01*
X620242Y42406D01*
X620342Y42326D01*
X620422Y42226D01*
X620482Y42116D01*
X620522Y41991D01*
X620532Y41866D01*
Y38436D01*
X620562Y38406D01*
X620662Y38266D01*
X620682Y38226D01*
X620697Y38191D01*
X620717Y38151D01*
X620732Y38111D01*
X620742Y38071D01*
X620757Y38026D01*
X620762Y37986D01*
X620772Y37946D01*
X620777Y37901D01*
Y37861D01*
X620782Y37816D01*
X620777Y37771D01*
Y37731D01*
X620772Y37686D01*
X620762Y37646D01*
X620757Y37606D01*
X620742Y37561D01*
X620732Y37521D01*
X620717Y37481D01*
X620697Y37441D01*
X620682Y37406D01*
X620662Y37366D01*
X620562Y37226D01*
X620532Y37196D01*
Y36066D01*
X620522Y35941D01*
X620482Y35816D01*
X620422Y35706D01*
X620342Y35606D01*
X620242Y35526D01*
X620132Y35466D01*
X620007Y35426D01*
X619882Y35416D01*
G37*
G36*
G01X648228D02*
X648103Y35426D01*
X647978Y35466D01*
X647868Y35526D01*
X647768Y35606D01*
X647688Y35706D01*
X647628Y35816D01*
X647588Y35941D01*
X647578Y36066D01*
Y37196D01*
X647548Y37226D01*
X647448Y37366D01*
X647428Y37406D01*
X647413Y37441D01*
X647393Y37481D01*
X647378Y37521D01*
X647368Y37561D01*
X647353Y37606D01*
X647348Y37646D01*
X647338Y37686D01*
X647333Y37731D01*
Y37771D01*
X647328Y37816D01*
X647333Y37861D01*
Y37901D01*
X647338Y37946D01*
X647348Y37986D01*
X647353Y38026D01*
X647368Y38071D01*
X647378Y38111D01*
X647393Y38151D01*
X647413Y38191D01*
X647428Y38226D01*
X647448Y38266D01*
X647548Y38406D01*
X647578Y38436D01*
Y41866D01*
X647588Y41991D01*
X647628Y42116D01*
X647688Y42226D01*
X647768Y42326D01*
X647868Y42406D01*
X647978Y42466D01*
X648103Y42506D01*
X648228Y42516D01*
X648353Y42506D01*
X648478Y42466D01*
X648588Y42406D01*
X648688Y42326D01*
X648768Y42226D01*
X648828Y42116D01*
X648868Y41991D01*
X648878Y41866D01*
Y38436D01*
X648908Y38406D01*
X649008Y38266D01*
X649028Y38226D01*
X649043Y38191D01*
X649063Y38151D01*
X649078Y38111D01*
X649088Y38071D01*
X649103Y38026D01*
X649108Y37986D01*
X649118Y37946D01*
X649123Y37901D01*
Y37861D01*
X649128Y37816D01*
X649123Y37771D01*
Y37731D01*
X649118Y37686D01*
X649108Y37646D01*
X649103Y37606D01*
X649088Y37561D01*
X649078Y37521D01*
X649063Y37481D01*
X649043Y37441D01*
X649028Y37406D01*
X649008Y37366D01*
X648908Y37226D01*
X648878Y37196D01*
Y36066D01*
X648868Y35941D01*
X648828Y35816D01*
X648768Y35706D01*
X648688Y35606D01*
X648588Y35526D01*
X648478Y35466D01*
X648353Y35426D01*
X648228Y35416D01*
G37*
G36*
G01X643504D02*
X643379Y35426D01*
X643254Y35466D01*
X643144Y35526D01*
X643044Y35606D01*
X642964Y35706D01*
X642904Y35816D01*
X642864Y35941D01*
X642854Y36066D01*
Y37196D01*
X642824Y37226D01*
X642724Y37366D01*
X642704Y37406D01*
X642689Y37441D01*
X642669Y37481D01*
X642654Y37521D01*
X642644Y37561D01*
X642629Y37606D01*
X642624Y37646D01*
X642614Y37686D01*
X642609Y37731D01*
Y37771D01*
X642604Y37816D01*
X642609Y37861D01*
Y37901D01*
X642614Y37946D01*
X642624Y37986D01*
X642629Y38026D01*
X642644Y38071D01*
X642654Y38111D01*
X642669Y38151D01*
X642689Y38191D01*
X642704Y38226D01*
X642724Y38266D01*
X642824Y38406D01*
X642854Y38436D01*
Y41866D01*
X642864Y41991D01*
X642904Y42116D01*
X642964Y42226D01*
X643044Y42326D01*
X643144Y42406D01*
X643254Y42466D01*
X643379Y42506D01*
X643504Y42516D01*
X643629Y42506D01*
X643754Y42466D01*
X643864Y42406D01*
X643964Y42326D01*
X644044Y42226D01*
X644104Y42116D01*
X644144Y41991D01*
X644154Y41866D01*
Y38436D01*
X644184Y38406D01*
X644284Y38266D01*
X644304Y38226D01*
X644319Y38191D01*
X644339Y38151D01*
X644354Y38111D01*
X644364Y38071D01*
X644379Y38026D01*
X644384Y37986D01*
X644394Y37946D01*
X644399Y37901D01*
Y37861D01*
X644404Y37816D01*
X644399Y37771D01*
Y37731D01*
X644394Y37686D01*
X644384Y37646D01*
X644379Y37606D01*
X644364Y37561D01*
X644354Y37521D01*
X644339Y37481D01*
X644319Y37441D01*
X644304Y37406D01*
X644284Y37366D01*
X644184Y37226D01*
X644154Y37196D01*
Y36066D01*
X644144Y35941D01*
X644104Y35816D01*
X644044Y35706D01*
X643964Y35606D01*
X643864Y35526D01*
X643754Y35466D01*
X643629Y35426D01*
X643504Y35416D01*
G37*
G36*
G01X638779D02*
X638654Y35426D01*
X638529Y35466D01*
X638419Y35526D01*
X638319Y35606D01*
X638239Y35706D01*
X638179Y35816D01*
X638139Y35941D01*
X638129Y36066D01*
Y37196D01*
X638099Y37226D01*
X637999Y37366D01*
X637979Y37406D01*
X637964Y37441D01*
X637944Y37481D01*
X637929Y37521D01*
X637919Y37561D01*
X637904Y37606D01*
X637899Y37646D01*
X637889Y37686D01*
X637884Y37731D01*
Y37771D01*
X637879Y37816D01*
X637884Y37861D01*
Y37901D01*
X637889Y37946D01*
X637899Y37986D01*
X637904Y38026D01*
X637919Y38071D01*
X637929Y38111D01*
X637944Y38151D01*
X637964Y38191D01*
X637979Y38226D01*
X637999Y38266D01*
X638099Y38406D01*
X638129Y38436D01*
Y41866D01*
X638139Y41991D01*
X638179Y42116D01*
X638239Y42226D01*
X638319Y42326D01*
X638419Y42406D01*
X638529Y42466D01*
X638654Y42506D01*
X638779Y42516D01*
X638904Y42506D01*
X639029Y42466D01*
X639139Y42406D01*
X639239Y42326D01*
X639319Y42226D01*
X639379Y42116D01*
X639419Y41991D01*
X639429Y41866D01*
Y38436D01*
X639459Y38406D01*
X639559Y38266D01*
X639579Y38226D01*
X639594Y38191D01*
X639614Y38151D01*
X639629Y38111D01*
X639639Y38071D01*
X639654Y38026D01*
X639659Y37986D01*
X639669Y37946D01*
X639674Y37901D01*
Y37861D01*
X639679Y37816D01*
X639674Y37771D01*
Y37731D01*
X639669Y37686D01*
X639659Y37646D01*
X639654Y37606D01*
X639639Y37561D01*
X639629Y37521D01*
X639614Y37481D01*
X639594Y37441D01*
X639579Y37406D01*
X639559Y37366D01*
X639459Y37226D01*
X639429Y37196D01*
Y36066D01*
X639419Y35941D01*
X639379Y35816D01*
X639319Y35706D01*
X639239Y35606D01*
X639139Y35526D01*
X639029Y35466D01*
X638904Y35426D01*
X638779Y35416D01*
G37*
G36*
G01X662401D02*
X662276Y35426D01*
X662151Y35466D01*
X662041Y35526D01*
X661941Y35606D01*
X661861Y35706D01*
X661801Y35816D01*
X661761Y35941D01*
X661751Y36066D01*
Y37196D01*
X661721Y37226D01*
X661621Y37366D01*
X661601Y37406D01*
X661586Y37441D01*
X661566Y37481D01*
X661551Y37521D01*
X661541Y37561D01*
X661526Y37606D01*
X661521Y37646D01*
X661511Y37686D01*
X661506Y37731D01*
Y37771D01*
X661501Y37816D01*
X661506Y37861D01*
Y37901D01*
X661511Y37946D01*
X661521Y37986D01*
X661526Y38026D01*
X661541Y38071D01*
X661551Y38111D01*
X661566Y38151D01*
X661586Y38191D01*
X661601Y38226D01*
X661621Y38266D01*
X661721Y38406D01*
X661751Y38436D01*
Y41866D01*
X661761Y41991D01*
X661801Y42116D01*
X661861Y42226D01*
X661941Y42326D01*
X662041Y42406D01*
X662151Y42466D01*
X662276Y42506D01*
X662401Y42516D01*
X662526Y42506D01*
X662651Y42466D01*
X662761Y42406D01*
X662861Y42326D01*
X662941Y42226D01*
X663001Y42116D01*
X663041Y41991D01*
X663051Y41866D01*
Y38436D01*
X663081Y38406D01*
X663181Y38266D01*
X663201Y38226D01*
X663216Y38191D01*
X663236Y38151D01*
X663251Y38111D01*
X663261Y38071D01*
X663276Y38026D01*
X663281Y37986D01*
X663291Y37946D01*
X663296Y37901D01*
Y37861D01*
X663301Y37816D01*
X663296Y37771D01*
Y37731D01*
X663291Y37686D01*
X663281Y37646D01*
X663276Y37606D01*
X663261Y37561D01*
X663251Y37521D01*
X663236Y37481D01*
X663216Y37441D01*
X663201Y37406D01*
X663181Y37366D01*
X663081Y37226D01*
X663051Y37196D01*
Y36066D01*
X663041Y35941D01*
X663001Y35816D01*
X662941Y35706D01*
X662861Y35606D01*
X662761Y35526D01*
X662651Y35466D01*
X662526Y35426D01*
X662401Y35416D01*
G37*
G36*
G01X657677D02*
X657552Y35426D01*
X657427Y35466D01*
X657317Y35526D01*
X657217Y35606D01*
X657137Y35706D01*
X657077Y35816D01*
X657037Y35941D01*
X657027Y36066D01*
Y37196D01*
X656997Y37226D01*
X656897Y37366D01*
X656877Y37406D01*
X656862Y37441D01*
X656842Y37481D01*
X656827Y37521D01*
X656817Y37561D01*
X656802Y37606D01*
X656797Y37646D01*
X656787Y37686D01*
X656782Y37731D01*
Y37771D01*
X656777Y37816D01*
X656782Y37861D01*
Y37901D01*
X656787Y37946D01*
X656797Y37986D01*
X656802Y38026D01*
X656817Y38071D01*
X656827Y38111D01*
X656842Y38151D01*
X656862Y38191D01*
X656877Y38226D01*
X656897Y38266D01*
X656997Y38406D01*
X657027Y38436D01*
Y41866D01*
X657037Y41991D01*
X657077Y42116D01*
X657137Y42226D01*
X657217Y42326D01*
X657317Y42406D01*
X657427Y42466D01*
X657552Y42506D01*
X657677Y42516D01*
X657802Y42506D01*
X657927Y42466D01*
X658037Y42406D01*
X658137Y42326D01*
X658217Y42226D01*
X658277Y42116D01*
X658317Y41991D01*
X658327Y41866D01*
Y38436D01*
X658357Y38406D01*
X658457Y38266D01*
X658477Y38226D01*
X658492Y38191D01*
X658512Y38151D01*
X658527Y38111D01*
X658537Y38071D01*
X658552Y38026D01*
X658557Y37986D01*
X658567Y37946D01*
X658572Y37901D01*
Y37861D01*
X658577Y37816D01*
X658572Y37771D01*
Y37731D01*
X658567Y37686D01*
X658557Y37646D01*
X658552Y37606D01*
X658537Y37561D01*
X658527Y37521D01*
X658512Y37481D01*
X658492Y37441D01*
X658477Y37406D01*
X658457Y37366D01*
X658357Y37226D01*
X658327Y37196D01*
Y36066D01*
X658317Y35941D01*
X658277Y35816D01*
X658217Y35706D01*
X658137Y35606D01*
X658037Y35526D01*
X657927Y35466D01*
X657802Y35426D01*
X657677Y35416D01*
G37*
G36*
G01X652952D02*
X652827Y35426D01*
X652702Y35466D01*
X652592Y35526D01*
X652492Y35606D01*
X652412Y35706D01*
X652352Y35816D01*
X652312Y35941D01*
X652302Y36066D01*
Y37196D01*
X652272Y37226D01*
X652172Y37366D01*
X652152Y37406D01*
X652137Y37441D01*
X652117Y37481D01*
X652102Y37521D01*
X652092Y37561D01*
X652077Y37606D01*
X652072Y37646D01*
X652062Y37686D01*
X652057Y37731D01*
Y37771D01*
X652052Y37816D01*
X652057Y37861D01*
Y37901D01*
X652062Y37946D01*
X652072Y37986D01*
X652077Y38026D01*
X652092Y38071D01*
X652102Y38111D01*
X652117Y38151D01*
X652137Y38191D01*
X652152Y38226D01*
X652172Y38266D01*
X652272Y38406D01*
X652302Y38436D01*
Y41866D01*
X652312Y41991D01*
X652352Y42116D01*
X652412Y42226D01*
X652492Y42326D01*
X652592Y42406D01*
X652702Y42466D01*
X652827Y42506D01*
X652952Y42516D01*
X653077Y42506D01*
X653202Y42466D01*
X653312Y42406D01*
X653412Y42326D01*
X653492Y42226D01*
X653552Y42116D01*
X653592Y41991D01*
X653602Y41866D01*
Y38436D01*
X653632Y38406D01*
X653732Y38266D01*
X653752Y38226D01*
X653767Y38191D01*
X653787Y38151D01*
X653802Y38111D01*
X653812Y38071D01*
X653827Y38026D01*
X653832Y37986D01*
X653842Y37946D01*
X653847Y37901D01*
Y37861D01*
X653852Y37816D01*
X653847Y37771D01*
Y37731D01*
X653842Y37686D01*
X653832Y37646D01*
X653827Y37606D01*
X653812Y37561D01*
X653802Y37521D01*
X653787Y37481D01*
X653767Y37441D01*
X653752Y37406D01*
X653732Y37366D01*
X653632Y37226D01*
X653602Y37196D01*
Y36066D01*
X653592Y35941D01*
X653552Y35816D01*
X653492Y35706D01*
X653412Y35606D01*
X653312Y35526D01*
X653202Y35466D01*
X653077Y35426D01*
X652952Y35416D01*
G37*
G36*
G01X676575D02*
X676450Y35426D01*
X676325Y35466D01*
X676215Y35526D01*
X676115Y35606D01*
X676035Y35706D01*
X675975Y35816D01*
X675935Y35941D01*
X675925Y36066D01*
Y37196D01*
X675895Y37226D01*
X675795Y37366D01*
X675775Y37406D01*
X675760Y37441D01*
X675740Y37481D01*
X675725Y37521D01*
X675715Y37561D01*
X675700Y37606D01*
X675695Y37646D01*
X675685Y37686D01*
X675680Y37731D01*
Y37771D01*
X675675Y37816D01*
X675680Y37861D01*
Y37901D01*
X675685Y37946D01*
X675695Y37986D01*
X675700Y38026D01*
X675715Y38071D01*
X675725Y38111D01*
X675740Y38151D01*
X675760Y38191D01*
X675775Y38226D01*
X675795Y38266D01*
X675895Y38406D01*
X675925Y38436D01*
Y41866D01*
X675935Y41991D01*
X675975Y42116D01*
X676035Y42226D01*
X676115Y42326D01*
X676215Y42406D01*
X676325Y42466D01*
X676450Y42506D01*
X676575Y42516D01*
X676700Y42506D01*
X676825Y42466D01*
X676935Y42406D01*
X677035Y42326D01*
X677115Y42226D01*
X677175Y42116D01*
X677215Y41991D01*
X677225Y41866D01*
Y38436D01*
X677255Y38406D01*
X677355Y38266D01*
X677375Y38226D01*
X677390Y38191D01*
X677410Y38151D01*
X677425Y38111D01*
X677435Y38071D01*
X677450Y38026D01*
X677455Y37986D01*
X677465Y37946D01*
X677470Y37901D01*
Y37861D01*
X677475Y37816D01*
X677470Y37771D01*
Y37731D01*
X677465Y37686D01*
X677455Y37646D01*
X677450Y37606D01*
X677435Y37561D01*
X677425Y37521D01*
X677410Y37481D01*
X677390Y37441D01*
X677375Y37406D01*
X677355Y37366D01*
X677255Y37226D01*
X677225Y37196D01*
Y36066D01*
X677215Y35941D01*
X677175Y35816D01*
X677115Y35706D01*
X677035Y35606D01*
X676935Y35526D01*
X676825Y35466D01*
X676700Y35426D01*
X676575Y35416D01*
G37*
G36*
G01X671850D02*
X671725Y35426D01*
X671600Y35466D01*
X671490Y35526D01*
X671390Y35606D01*
X671310Y35706D01*
X671250Y35816D01*
X671210Y35941D01*
X671200Y36066D01*
Y37196D01*
X671170Y37226D01*
X671070Y37366D01*
X671050Y37406D01*
X671035Y37441D01*
X671015Y37481D01*
X671000Y37521D01*
X670990Y37561D01*
X670975Y37606D01*
X670970Y37646D01*
X670960Y37686D01*
X670955Y37731D01*
Y37771D01*
X670950Y37816D01*
X670955Y37861D01*
Y37901D01*
X670960Y37946D01*
X670970Y37986D01*
X670975Y38026D01*
X670990Y38071D01*
X671000Y38111D01*
X671015Y38151D01*
X671035Y38191D01*
X671050Y38226D01*
X671070Y38266D01*
X671170Y38406D01*
X671200Y38436D01*
Y41866D01*
X671210Y41991D01*
X671250Y42116D01*
X671310Y42226D01*
X671390Y42326D01*
X671490Y42406D01*
X671600Y42466D01*
X671725Y42506D01*
X671850Y42516D01*
X671975Y42506D01*
X672100Y42466D01*
X672210Y42406D01*
X672310Y42326D01*
X672390Y42226D01*
X672450Y42116D01*
X672490Y41991D01*
X672500Y41866D01*
Y38436D01*
X672530Y38406D01*
X672630Y38266D01*
X672650Y38226D01*
X672665Y38191D01*
X672685Y38151D01*
X672700Y38111D01*
X672710Y38071D01*
X672725Y38026D01*
X672730Y37986D01*
X672740Y37946D01*
X672745Y37901D01*
Y37861D01*
X672750Y37816D01*
X672745Y37771D01*
Y37731D01*
X672740Y37686D01*
X672730Y37646D01*
X672725Y37606D01*
X672710Y37561D01*
X672700Y37521D01*
X672685Y37481D01*
X672665Y37441D01*
X672650Y37406D01*
X672630Y37366D01*
X672530Y37226D01*
X672500Y37196D01*
Y36066D01*
X672490Y35941D01*
X672450Y35816D01*
X672390Y35706D01*
X672310Y35606D01*
X672210Y35526D01*
X672100Y35466D01*
X671975Y35426D01*
X671850Y35416D01*
G37*
G36*
G01X667126D02*
X667001Y35426D01*
X666876Y35466D01*
X666766Y35526D01*
X666666Y35606D01*
X666586Y35706D01*
X666526Y35816D01*
X666486Y35941D01*
X666476Y36066D01*
Y37196D01*
X666446Y37226D01*
X666346Y37366D01*
X666326Y37406D01*
X666311Y37441D01*
X666291Y37481D01*
X666276Y37521D01*
X666266Y37561D01*
X666251Y37606D01*
X666246Y37646D01*
X666236Y37686D01*
X666231Y37731D01*
Y37771D01*
X666226Y37816D01*
X666231Y37861D01*
Y37901D01*
X666236Y37946D01*
X666246Y37986D01*
X666251Y38026D01*
X666266Y38071D01*
X666276Y38111D01*
X666291Y38151D01*
X666311Y38191D01*
X666326Y38226D01*
X666346Y38266D01*
X666446Y38406D01*
X666476Y38436D01*
Y41866D01*
X666486Y41991D01*
X666526Y42116D01*
X666586Y42226D01*
X666666Y42326D01*
X666766Y42406D01*
X666876Y42466D01*
X667001Y42506D01*
X667126Y42516D01*
X667251Y42506D01*
X667376Y42466D01*
X667486Y42406D01*
X667586Y42326D01*
X667666Y42226D01*
X667726Y42116D01*
X667766Y41991D01*
X667776Y41866D01*
Y38436D01*
X667806Y38406D01*
X667906Y38266D01*
X667926Y38226D01*
X667941Y38191D01*
X667961Y38151D01*
X667976Y38111D01*
X667986Y38071D01*
X668001Y38026D01*
X668006Y37986D01*
X668016Y37946D01*
X668021Y37901D01*
Y37861D01*
X668026Y37816D01*
X668021Y37771D01*
Y37731D01*
X668016Y37686D01*
X668006Y37646D01*
X668001Y37606D01*
X667986Y37561D01*
X667976Y37521D01*
X667961Y37481D01*
X667941Y37441D01*
X667926Y37406D01*
X667906Y37366D01*
X667806Y37226D01*
X667776Y37196D01*
Y36066D01*
X667766Y35941D01*
X667726Y35816D01*
X667666Y35706D01*
X667586Y35606D01*
X667486Y35526D01*
X667376Y35466D01*
X667251Y35426D01*
X667126Y35416D01*
G37*
G36*
G01X695472D02*
X695347Y35426D01*
X695222Y35466D01*
X695112Y35526D01*
X695012Y35606D01*
X694932Y35706D01*
X694872Y35816D01*
X694832Y35941D01*
X694822Y36066D01*
Y37196D01*
X694792Y37226D01*
X694692Y37366D01*
X694672Y37406D01*
X694657Y37441D01*
X694637Y37481D01*
X694622Y37521D01*
X694612Y37561D01*
X694597Y37606D01*
X694592Y37646D01*
X694582Y37686D01*
X694577Y37731D01*
Y37771D01*
X694572Y37816D01*
X694577Y37861D01*
Y37901D01*
X694582Y37946D01*
X694592Y37986D01*
X694597Y38026D01*
X694612Y38071D01*
X694622Y38111D01*
X694637Y38151D01*
X694657Y38191D01*
X694672Y38226D01*
X694692Y38266D01*
X694792Y38406D01*
X694822Y38436D01*
Y41866D01*
X694832Y41991D01*
X694872Y42116D01*
X694932Y42226D01*
X695012Y42326D01*
X695112Y42406D01*
X695222Y42466D01*
X695347Y42506D01*
X695472Y42516D01*
X695597Y42506D01*
X695722Y42466D01*
X695832Y42406D01*
X695932Y42326D01*
X696012Y42226D01*
X696072Y42116D01*
X696112Y41991D01*
X696122Y41866D01*
Y38436D01*
X696152Y38406D01*
X696252Y38266D01*
X696272Y38226D01*
X696287Y38191D01*
X696307Y38151D01*
X696322Y38111D01*
X696332Y38071D01*
X696347Y38026D01*
X696352Y37986D01*
X696362Y37946D01*
X696367Y37901D01*
Y37861D01*
X696372Y37816D01*
X696367Y37771D01*
Y37731D01*
X696362Y37686D01*
X696352Y37646D01*
X696347Y37606D01*
X696332Y37561D01*
X696322Y37521D01*
X696307Y37481D01*
X696287Y37441D01*
X696272Y37406D01*
X696252Y37366D01*
X696152Y37226D01*
X696122Y37196D01*
Y36066D01*
X696112Y35941D01*
X696072Y35816D01*
X696012Y35706D01*
X695932Y35606D01*
X695832Y35526D01*
X695722Y35466D01*
X695597Y35426D01*
X695472Y35416D01*
G37*
G36*
G01X690748D02*
X690623Y35426D01*
X690498Y35466D01*
X690388Y35526D01*
X690288Y35606D01*
X690208Y35706D01*
X690148Y35816D01*
X690108Y35941D01*
X690098Y36066D01*
Y37196D01*
X690068Y37226D01*
X689968Y37366D01*
X689948Y37406D01*
X689933Y37441D01*
X689913Y37481D01*
X689898Y37521D01*
X689888Y37561D01*
X689873Y37606D01*
X689868Y37646D01*
X689858Y37686D01*
X689853Y37731D01*
Y37771D01*
X689848Y37816D01*
X689853Y37861D01*
Y37901D01*
X689858Y37946D01*
X689868Y37986D01*
X689873Y38026D01*
X689888Y38071D01*
X689898Y38111D01*
X689913Y38151D01*
X689933Y38191D01*
X689948Y38226D01*
X689968Y38266D01*
X690068Y38406D01*
X690098Y38436D01*
Y41866D01*
X690108Y41991D01*
X690148Y42116D01*
X690208Y42226D01*
X690288Y42326D01*
X690388Y42406D01*
X690498Y42466D01*
X690623Y42506D01*
X690748Y42516D01*
X690873Y42506D01*
X690998Y42466D01*
X691108Y42406D01*
X691208Y42326D01*
X691288Y42226D01*
X691348Y42116D01*
X691388Y41991D01*
X691398Y41866D01*
Y38436D01*
X691428Y38406D01*
X691528Y38266D01*
X691548Y38226D01*
X691563Y38191D01*
X691583Y38151D01*
X691598Y38111D01*
X691608Y38071D01*
X691623Y38026D01*
X691628Y37986D01*
X691638Y37946D01*
X691643Y37901D01*
Y37861D01*
X691648Y37816D01*
X691643Y37771D01*
Y37731D01*
X691638Y37686D01*
X691628Y37646D01*
X691623Y37606D01*
X691608Y37561D01*
X691598Y37521D01*
X691583Y37481D01*
X691563Y37441D01*
X691548Y37406D01*
X691528Y37366D01*
X691428Y37226D01*
X691398Y37196D01*
Y36066D01*
X691388Y35941D01*
X691348Y35816D01*
X691288Y35706D01*
X691208Y35606D01*
X691108Y35526D01*
X690998Y35466D01*
X690873Y35426D01*
X690748Y35416D01*
G37*
G36*
G01X686023D02*
X685898Y35426D01*
X685773Y35466D01*
X685663Y35526D01*
X685563Y35606D01*
X685483Y35706D01*
X685423Y35816D01*
X685383Y35941D01*
X685373Y36066D01*
Y37196D01*
X685343Y37226D01*
X685243Y37366D01*
X685223Y37406D01*
X685208Y37441D01*
X685188Y37481D01*
X685173Y37521D01*
X685163Y37561D01*
X685148Y37606D01*
X685143Y37646D01*
X685133Y37686D01*
X685128Y37731D01*
Y37771D01*
X685123Y37816D01*
X685128Y37861D01*
Y37901D01*
X685133Y37946D01*
X685143Y37986D01*
X685148Y38026D01*
X685163Y38071D01*
X685173Y38111D01*
X685188Y38151D01*
X685208Y38191D01*
X685223Y38226D01*
X685243Y38266D01*
X685343Y38406D01*
X685373Y38436D01*
Y41866D01*
X685383Y41991D01*
X685423Y42116D01*
X685483Y42226D01*
X685563Y42326D01*
X685663Y42406D01*
X685773Y42466D01*
X685898Y42506D01*
X686023Y42516D01*
X686148Y42506D01*
X686273Y42466D01*
X686383Y42406D01*
X686483Y42326D01*
X686563Y42226D01*
X686623Y42116D01*
X686663Y41991D01*
X686673Y41866D01*
Y38436D01*
X686703Y38406D01*
X686803Y38266D01*
X686823Y38226D01*
X686838Y38191D01*
X686858Y38151D01*
X686873Y38111D01*
X686883Y38071D01*
X686898Y38026D01*
X686903Y37986D01*
X686913Y37946D01*
X686918Y37901D01*
Y37861D01*
X686923Y37816D01*
X686918Y37771D01*
Y37731D01*
X686913Y37686D01*
X686903Y37646D01*
X686898Y37606D01*
X686883Y37561D01*
X686873Y37521D01*
X686858Y37481D01*
X686838Y37441D01*
X686823Y37406D01*
X686803Y37366D01*
X686703Y37226D01*
X686673Y37196D01*
Y36066D01*
X686663Y35941D01*
X686623Y35816D01*
X686563Y35706D01*
X686483Y35606D01*
X686383Y35526D01*
X686273Y35466D01*
X686148Y35426D01*
X686023Y35416D01*
G37*
G36*
G01X681299D02*
X681174Y35426D01*
X681049Y35466D01*
X680939Y35526D01*
X680839Y35606D01*
X680759Y35706D01*
X680699Y35816D01*
X680659Y35941D01*
X680649Y36066D01*
Y37196D01*
X680619Y37226D01*
X680519Y37366D01*
X680499Y37406D01*
X680484Y37441D01*
X680464Y37481D01*
X680449Y37521D01*
X680439Y37561D01*
X680424Y37606D01*
X680419Y37646D01*
X680409Y37686D01*
X680404Y37731D01*
Y37771D01*
X680399Y37816D01*
X680404Y37861D01*
Y37901D01*
X680409Y37946D01*
X680419Y37986D01*
X680424Y38026D01*
X680439Y38071D01*
X680449Y38111D01*
X680464Y38151D01*
X680484Y38191D01*
X680499Y38226D01*
X680519Y38266D01*
X680619Y38406D01*
X680649Y38436D01*
Y41866D01*
X680659Y41991D01*
X680699Y42116D01*
X680759Y42226D01*
X680839Y42326D01*
X680939Y42406D01*
X681049Y42466D01*
X681174Y42506D01*
X681299Y42516D01*
X681424Y42506D01*
X681549Y42466D01*
X681659Y42406D01*
X681759Y42326D01*
X681839Y42226D01*
X681899Y42116D01*
X681939Y41991D01*
X681949Y41866D01*
Y38436D01*
X681979Y38406D01*
X682079Y38266D01*
X682099Y38226D01*
X682114Y38191D01*
X682134Y38151D01*
X682149Y38111D01*
X682159Y38071D01*
X682174Y38026D01*
X682179Y37986D01*
X682189Y37946D01*
X682194Y37901D01*
Y37861D01*
X682199Y37816D01*
X682194Y37771D01*
Y37731D01*
X682189Y37686D01*
X682179Y37646D01*
X682174Y37606D01*
X682159Y37561D01*
X682149Y37521D01*
X682134Y37481D01*
X682114Y37441D01*
X682099Y37406D01*
X682079Y37366D01*
X681979Y37226D01*
X681949Y37196D01*
Y36066D01*
X681939Y35941D01*
X681899Y35816D01*
X681839Y35706D01*
X681759Y35606D01*
X681659Y35526D01*
X681549Y35466D01*
X681424Y35426D01*
X681299Y35416D01*
G37*
G36*
G01X709645D02*
X709520Y35426D01*
X709395Y35466D01*
X709285Y35526D01*
X709185Y35606D01*
X709105Y35706D01*
X709045Y35816D01*
X709005Y35941D01*
X708995Y36066D01*
Y37196D01*
X708965Y37226D01*
X708865Y37366D01*
X708845Y37406D01*
X708830Y37441D01*
X708810Y37481D01*
X708795Y37521D01*
X708785Y37561D01*
X708770Y37606D01*
X708765Y37646D01*
X708755Y37686D01*
X708750Y37731D01*
Y37771D01*
X708745Y37816D01*
X708750Y37861D01*
Y37901D01*
X708755Y37946D01*
X708765Y37986D01*
X708770Y38026D01*
X708785Y38071D01*
X708795Y38111D01*
X708810Y38151D01*
X708830Y38191D01*
X708845Y38226D01*
X708865Y38266D01*
X708965Y38406D01*
X708995Y38436D01*
Y41866D01*
X709005Y41991D01*
X709045Y42116D01*
X709105Y42226D01*
X709185Y42326D01*
X709285Y42406D01*
X709395Y42466D01*
X709520Y42506D01*
X709645Y42516D01*
X709770Y42506D01*
X709895Y42466D01*
X710005Y42406D01*
X710105Y42326D01*
X710185Y42226D01*
X710245Y42116D01*
X710285Y41991D01*
X710295Y41866D01*
Y38436D01*
X710325Y38406D01*
X710425Y38266D01*
X710445Y38226D01*
X710460Y38191D01*
X710480Y38151D01*
X710495Y38111D01*
X710505Y38071D01*
X710520Y38026D01*
X710525Y37986D01*
X710535Y37946D01*
X710540Y37901D01*
Y37861D01*
X710545Y37816D01*
X710540Y37771D01*
Y37731D01*
X710535Y37686D01*
X710525Y37646D01*
X710520Y37606D01*
X710505Y37561D01*
X710495Y37521D01*
X710480Y37481D01*
X710460Y37441D01*
X710445Y37406D01*
X710425Y37366D01*
X710325Y37226D01*
X710295Y37196D01*
Y36066D01*
X710285Y35941D01*
X710245Y35816D01*
X710185Y35706D01*
X710105Y35606D01*
X710005Y35526D01*
X709895Y35466D01*
X709770Y35426D01*
X709645Y35416D01*
G37*
G36*
G01X704921D02*
X704796Y35426D01*
X704671Y35466D01*
X704561Y35526D01*
X704461Y35606D01*
X704381Y35706D01*
X704321Y35816D01*
X704281Y35941D01*
X704271Y36066D01*
Y37196D01*
X704241Y37226D01*
X704141Y37366D01*
X704121Y37406D01*
X704106Y37441D01*
X704086Y37481D01*
X704071Y37521D01*
X704061Y37561D01*
X704046Y37606D01*
X704041Y37646D01*
X704031Y37686D01*
X704026Y37731D01*
Y37771D01*
X704021Y37816D01*
X704026Y37861D01*
Y37901D01*
X704031Y37946D01*
X704041Y37986D01*
X704046Y38026D01*
X704061Y38071D01*
X704071Y38111D01*
X704086Y38151D01*
X704106Y38191D01*
X704121Y38226D01*
X704141Y38266D01*
X704241Y38406D01*
X704271Y38436D01*
Y41866D01*
X704281Y41991D01*
X704321Y42116D01*
X704381Y42226D01*
X704461Y42326D01*
X704561Y42406D01*
X704671Y42466D01*
X704796Y42506D01*
X704921Y42516D01*
X705046Y42506D01*
X705171Y42466D01*
X705281Y42406D01*
X705381Y42326D01*
X705461Y42226D01*
X705521Y42116D01*
X705561Y41991D01*
X705571Y41866D01*
Y38436D01*
X705601Y38406D01*
X705701Y38266D01*
X705721Y38226D01*
X705736Y38191D01*
X705756Y38151D01*
X705771Y38111D01*
X705781Y38071D01*
X705796Y38026D01*
X705801Y37986D01*
X705811Y37946D01*
X705816Y37901D01*
Y37861D01*
X705821Y37816D01*
X705816Y37771D01*
Y37731D01*
X705811Y37686D01*
X705801Y37646D01*
X705796Y37606D01*
X705781Y37561D01*
X705771Y37521D01*
X705756Y37481D01*
X705736Y37441D01*
X705721Y37406D01*
X705701Y37366D01*
X705601Y37226D01*
X705571Y37196D01*
Y36066D01*
X705561Y35941D01*
X705521Y35816D01*
X705461Y35706D01*
X705381Y35606D01*
X705281Y35526D01*
X705171Y35466D01*
X705046Y35426D01*
X704921Y35416D01*
G37*
G36*
G01X700197D02*
X700072Y35426D01*
X699947Y35466D01*
X699837Y35526D01*
X699737Y35606D01*
X699657Y35706D01*
X699597Y35816D01*
X699557Y35941D01*
X699547Y36066D01*
Y37196D01*
X699517Y37226D01*
X699417Y37366D01*
X699397Y37406D01*
X699382Y37441D01*
X699362Y37481D01*
X699347Y37521D01*
X699337Y37561D01*
X699322Y37606D01*
X699317Y37646D01*
X699307Y37686D01*
X699302Y37731D01*
Y37771D01*
X699297Y37816D01*
X699302Y37861D01*
Y37901D01*
X699307Y37946D01*
X699317Y37986D01*
X699322Y38026D01*
X699337Y38071D01*
X699347Y38111D01*
X699362Y38151D01*
X699382Y38191D01*
X699397Y38226D01*
X699417Y38266D01*
X699517Y38406D01*
X699547Y38436D01*
Y41866D01*
X699557Y41991D01*
X699597Y42116D01*
X699657Y42226D01*
X699737Y42326D01*
X699837Y42406D01*
X699947Y42466D01*
X700072Y42506D01*
X700197Y42516D01*
X700322Y42506D01*
X700447Y42466D01*
X700557Y42406D01*
X700657Y42326D01*
X700737Y42226D01*
X700797Y42116D01*
X700837Y41991D01*
X700847Y41866D01*
Y38436D01*
X700877Y38406D01*
X700977Y38266D01*
X700997Y38226D01*
X701012Y38191D01*
X701032Y38151D01*
X701047Y38111D01*
X701057Y38071D01*
X701072Y38026D01*
X701077Y37986D01*
X701087Y37946D01*
X701092Y37901D01*
Y37861D01*
X701097Y37816D01*
X701092Y37771D01*
Y37731D01*
X701087Y37686D01*
X701077Y37646D01*
X701072Y37606D01*
X701057Y37561D01*
X701047Y37521D01*
X701032Y37481D01*
X701012Y37441D01*
X700997Y37406D01*
X700977Y37366D01*
X700877Y37226D01*
X700847Y37196D01*
Y36066D01*
X700837Y35941D01*
X700797Y35816D01*
X700737Y35706D01*
X700657Y35606D01*
X700557Y35526D01*
X700447Y35466D01*
X700322Y35426D01*
X700197Y35416D01*
G37*
G36*
G01X723819D02*
X723694Y35426D01*
X723569Y35466D01*
X723459Y35526D01*
X723359Y35606D01*
X723279Y35706D01*
X723219Y35816D01*
X723179Y35941D01*
X723169Y36066D01*
Y37196D01*
X723139Y37226D01*
X723039Y37366D01*
X723019Y37406D01*
X723004Y37441D01*
X722984Y37481D01*
X722969Y37521D01*
X722959Y37561D01*
X722944Y37606D01*
X722939Y37646D01*
X722929Y37686D01*
X722924Y37731D01*
Y37771D01*
X722919Y37816D01*
X722924Y37861D01*
Y37901D01*
X722929Y37946D01*
X722939Y37986D01*
X722944Y38026D01*
X722959Y38071D01*
X722969Y38111D01*
X722984Y38151D01*
X723004Y38191D01*
X723019Y38226D01*
X723039Y38266D01*
X723139Y38406D01*
X723169Y38436D01*
Y41866D01*
X723179Y41991D01*
X723219Y42116D01*
X723279Y42226D01*
X723359Y42326D01*
X723459Y42406D01*
X723569Y42466D01*
X723694Y42506D01*
X723819Y42516D01*
X723944Y42506D01*
X724069Y42466D01*
X724179Y42406D01*
X724279Y42326D01*
X724359Y42226D01*
X724419Y42116D01*
X724459Y41991D01*
X724469Y41866D01*
Y38436D01*
X724499Y38406D01*
X724599Y38266D01*
X724619Y38226D01*
X724634Y38191D01*
X724654Y38151D01*
X724669Y38111D01*
X724679Y38071D01*
X724694Y38026D01*
X724699Y37986D01*
X724709Y37946D01*
X724714Y37901D01*
Y37861D01*
X724719Y37816D01*
X724714Y37771D01*
Y37731D01*
X724709Y37686D01*
X724699Y37646D01*
X724694Y37606D01*
X724679Y37561D01*
X724669Y37521D01*
X724654Y37481D01*
X724634Y37441D01*
X724619Y37406D01*
X724599Y37366D01*
X724499Y37226D01*
X724469Y37196D01*
Y36066D01*
X724459Y35941D01*
X724419Y35816D01*
X724359Y35706D01*
X724279Y35606D01*
X724179Y35526D01*
X724069Y35466D01*
X723944Y35426D01*
X723819Y35416D01*
G37*
G36*
G01X719094D02*
X718969Y35426D01*
X718844Y35466D01*
X718734Y35526D01*
X718634Y35606D01*
X718554Y35706D01*
X718494Y35816D01*
X718454Y35941D01*
X718444Y36066D01*
Y37196D01*
X718414Y37226D01*
X718314Y37366D01*
X718294Y37406D01*
X718279Y37441D01*
X718259Y37481D01*
X718244Y37521D01*
X718234Y37561D01*
X718219Y37606D01*
X718214Y37646D01*
X718204Y37686D01*
X718199Y37731D01*
Y37771D01*
X718194Y37816D01*
X718199Y37861D01*
Y37901D01*
X718204Y37946D01*
X718214Y37986D01*
X718219Y38026D01*
X718234Y38071D01*
X718244Y38111D01*
X718259Y38151D01*
X718279Y38191D01*
X718294Y38226D01*
X718314Y38266D01*
X718414Y38406D01*
X718444Y38436D01*
Y41866D01*
X718454Y41991D01*
X718494Y42116D01*
X718554Y42226D01*
X718634Y42326D01*
X718734Y42406D01*
X718844Y42466D01*
X718969Y42506D01*
X719094Y42516D01*
X719219Y42506D01*
X719344Y42466D01*
X719454Y42406D01*
X719554Y42326D01*
X719634Y42226D01*
X719694Y42116D01*
X719734Y41991D01*
X719744Y41866D01*
Y38436D01*
X719774Y38406D01*
X719874Y38266D01*
X719894Y38226D01*
X719909Y38191D01*
X719929Y38151D01*
X719944Y38111D01*
X719954Y38071D01*
X719969Y38026D01*
X719974Y37986D01*
X719984Y37946D01*
X719989Y37901D01*
Y37861D01*
X719994Y37816D01*
X719989Y37771D01*
Y37731D01*
X719984Y37686D01*
X719974Y37646D01*
X719969Y37606D01*
X719954Y37561D01*
X719944Y37521D01*
X719929Y37481D01*
X719909Y37441D01*
X719894Y37406D01*
X719874Y37366D01*
X719774Y37226D01*
X719744Y37196D01*
Y36066D01*
X719734Y35941D01*
X719694Y35816D01*
X719634Y35706D01*
X719554Y35606D01*
X719454Y35526D01*
X719344Y35466D01*
X719219Y35426D01*
X719094Y35416D01*
G37*
G36*
G01X714370D02*
X714245Y35426D01*
X714120Y35466D01*
X714010Y35526D01*
X713910Y35606D01*
X713830Y35706D01*
X713770Y35816D01*
X713730Y35941D01*
X713720Y36066D01*
Y37196D01*
X713690Y37226D01*
X713590Y37366D01*
X713570Y37406D01*
X713555Y37441D01*
X713535Y37481D01*
X713520Y37521D01*
X713510Y37561D01*
X713495Y37606D01*
X713490Y37646D01*
X713480Y37686D01*
X713475Y37731D01*
Y37771D01*
X713470Y37816D01*
X713475Y37861D01*
Y37901D01*
X713480Y37946D01*
X713490Y37986D01*
X713495Y38026D01*
X713510Y38071D01*
X713520Y38111D01*
X713535Y38151D01*
X713555Y38191D01*
X713570Y38226D01*
X713590Y38266D01*
X713690Y38406D01*
X713720Y38436D01*
Y41866D01*
X713730Y41991D01*
X713770Y42116D01*
X713830Y42226D01*
X713910Y42326D01*
X714010Y42406D01*
X714120Y42466D01*
X714245Y42506D01*
X714370Y42516D01*
X714495Y42506D01*
X714620Y42466D01*
X714730Y42406D01*
X714830Y42326D01*
X714910Y42226D01*
X714970Y42116D01*
X715010Y41991D01*
X715020Y41866D01*
Y38436D01*
X715050Y38406D01*
X715150Y38266D01*
X715170Y38226D01*
X715185Y38191D01*
X715205Y38151D01*
X715220Y38111D01*
X715230Y38071D01*
X715245Y38026D01*
X715250Y37986D01*
X715260Y37946D01*
X715265Y37901D01*
Y37861D01*
X715270Y37816D01*
X715265Y37771D01*
Y37731D01*
X715260Y37686D01*
X715250Y37646D01*
X715245Y37606D01*
X715230Y37561D01*
X715220Y37521D01*
X715205Y37481D01*
X715185Y37441D01*
X715170Y37406D01*
X715150Y37366D01*
X715050Y37226D01*
X715020Y37196D01*
Y36066D01*
X715010Y35941D01*
X714970Y35816D01*
X714910Y35706D01*
X714830Y35606D01*
X714730Y35526D01*
X714620Y35466D01*
X714495Y35426D01*
X714370Y35416D01*
G37*
G36*
G01X737992D02*
X737867Y35426D01*
X737742Y35466D01*
X737632Y35526D01*
X737532Y35606D01*
X737452Y35706D01*
X737392Y35816D01*
X737352Y35941D01*
X737342Y36066D01*
Y37196D01*
X737312Y37226D01*
X737212Y37366D01*
X737192Y37406D01*
X737177Y37441D01*
X737157Y37481D01*
X737142Y37521D01*
X737132Y37561D01*
X737117Y37606D01*
X737112Y37646D01*
X737102Y37686D01*
X737097Y37731D01*
Y37771D01*
X737092Y37816D01*
X737097Y37861D01*
Y37901D01*
X737102Y37946D01*
X737112Y37986D01*
X737117Y38026D01*
X737132Y38071D01*
X737142Y38111D01*
X737157Y38151D01*
X737177Y38191D01*
X737192Y38226D01*
X737212Y38266D01*
X737312Y38406D01*
X737342Y38436D01*
Y41866D01*
X737352Y41991D01*
X737392Y42116D01*
X737452Y42226D01*
X737532Y42326D01*
X737632Y42406D01*
X737742Y42466D01*
X737867Y42506D01*
X737992Y42516D01*
X738117Y42506D01*
X738242Y42466D01*
X738352Y42406D01*
X738452Y42326D01*
X738532Y42226D01*
X738592Y42116D01*
X738632Y41991D01*
X738642Y41866D01*
Y38436D01*
X738672Y38406D01*
X738772Y38266D01*
X738792Y38226D01*
X738807Y38191D01*
X738827Y38151D01*
X738842Y38111D01*
X738852Y38071D01*
X738867Y38026D01*
X738872Y37986D01*
X738882Y37946D01*
X738887Y37901D01*
Y37861D01*
X738892Y37816D01*
X738887Y37771D01*
Y37731D01*
X738882Y37686D01*
X738872Y37646D01*
X738867Y37606D01*
X738852Y37561D01*
X738842Y37521D01*
X738827Y37481D01*
X738807Y37441D01*
X738792Y37406D01*
X738772Y37366D01*
X738672Y37226D01*
X738642Y37196D01*
Y36066D01*
X738632Y35941D01*
X738592Y35816D01*
X738532Y35706D01*
X738452Y35606D01*
X738352Y35526D01*
X738242Y35466D01*
X738117Y35426D01*
X737992Y35416D01*
G37*
G36*
G01X733267D02*
X733142Y35426D01*
X733017Y35466D01*
X732907Y35526D01*
X732807Y35606D01*
X732727Y35706D01*
X732667Y35816D01*
X732627Y35941D01*
X732617Y36066D01*
Y37196D01*
X732587Y37226D01*
X732487Y37366D01*
X732467Y37406D01*
X732452Y37441D01*
X732432Y37481D01*
X732417Y37521D01*
X732407Y37561D01*
X732392Y37606D01*
X732387Y37646D01*
X732377Y37686D01*
X732372Y37731D01*
Y37771D01*
X732367Y37816D01*
X732372Y37861D01*
Y37901D01*
X732377Y37946D01*
X732387Y37986D01*
X732392Y38026D01*
X732407Y38071D01*
X732417Y38111D01*
X732432Y38151D01*
X732452Y38191D01*
X732467Y38226D01*
X732487Y38266D01*
X732587Y38406D01*
X732617Y38436D01*
Y41866D01*
X732627Y41991D01*
X732667Y42116D01*
X732727Y42226D01*
X732807Y42326D01*
X732907Y42406D01*
X733017Y42466D01*
X733142Y42506D01*
X733267Y42516D01*
X733392Y42506D01*
X733517Y42466D01*
X733627Y42406D01*
X733727Y42326D01*
X733807Y42226D01*
X733867Y42116D01*
X733907Y41991D01*
X733917Y41866D01*
Y38436D01*
X733947Y38406D01*
X734047Y38266D01*
X734067Y38226D01*
X734082Y38191D01*
X734102Y38151D01*
X734117Y38111D01*
X734127Y38071D01*
X734142Y38026D01*
X734147Y37986D01*
X734157Y37946D01*
X734162Y37901D01*
Y37861D01*
X734167Y37816D01*
X734162Y37771D01*
Y37731D01*
X734157Y37686D01*
X734147Y37646D01*
X734142Y37606D01*
X734127Y37561D01*
X734117Y37521D01*
X734102Y37481D01*
X734082Y37441D01*
X734067Y37406D01*
X734047Y37366D01*
X733947Y37226D01*
X733917Y37196D01*
Y36066D01*
X733907Y35941D01*
X733867Y35816D01*
X733807Y35706D01*
X733727Y35606D01*
X733627Y35526D01*
X733517Y35466D01*
X733392Y35426D01*
X733267Y35416D01*
G37*
G36*
G01X728543D02*
X728418Y35426D01*
X728293Y35466D01*
X728183Y35526D01*
X728083Y35606D01*
X728003Y35706D01*
X727943Y35816D01*
X727903Y35941D01*
X727893Y36066D01*
Y37196D01*
X727863Y37226D01*
X727763Y37366D01*
X727743Y37406D01*
X727728Y37441D01*
X727708Y37481D01*
X727693Y37521D01*
X727683Y37561D01*
X727668Y37606D01*
X727663Y37646D01*
X727653Y37686D01*
X727648Y37731D01*
Y37771D01*
X727643Y37816D01*
X727648Y37861D01*
Y37901D01*
X727653Y37946D01*
X727663Y37986D01*
X727668Y38026D01*
X727683Y38071D01*
X727693Y38111D01*
X727708Y38151D01*
X727728Y38191D01*
X727743Y38226D01*
X727763Y38266D01*
X727863Y38406D01*
X727893Y38436D01*
Y41866D01*
X727903Y41991D01*
X727943Y42116D01*
X728003Y42226D01*
X728083Y42326D01*
X728183Y42406D01*
X728293Y42466D01*
X728418Y42506D01*
X728543Y42516D01*
X728668Y42506D01*
X728793Y42466D01*
X728903Y42406D01*
X729003Y42326D01*
X729083Y42226D01*
X729143Y42116D01*
X729183Y41991D01*
X729193Y41866D01*
Y38436D01*
X729223Y38406D01*
X729323Y38266D01*
X729343Y38226D01*
X729358Y38191D01*
X729378Y38151D01*
X729393Y38111D01*
X729403Y38071D01*
X729418Y38026D01*
X729423Y37986D01*
X729433Y37946D01*
X729438Y37901D01*
Y37861D01*
X729443Y37816D01*
X729438Y37771D01*
Y37731D01*
X729433Y37686D01*
X729423Y37646D01*
X729418Y37606D01*
X729403Y37561D01*
X729393Y37521D01*
X729378Y37481D01*
X729358Y37441D01*
X729343Y37406D01*
X729323Y37366D01*
X729223Y37226D01*
X729193Y37196D01*
Y36066D01*
X729183Y35941D01*
X729143Y35816D01*
X729083Y35706D01*
X729003Y35606D01*
X728903Y35526D01*
X728793Y35466D01*
X728668Y35426D01*
X728543Y35416D01*
G37*
G36*
G01X752165D02*
X752040Y35426D01*
X751915Y35466D01*
X751805Y35526D01*
X751705Y35606D01*
X751625Y35706D01*
X751565Y35816D01*
X751525Y35941D01*
X751515Y36066D01*
Y37196D01*
X751485Y37226D01*
X751385Y37366D01*
X751365Y37406D01*
X751350Y37441D01*
X751330Y37481D01*
X751315Y37521D01*
X751305Y37561D01*
X751290Y37606D01*
X751285Y37646D01*
X751275Y37686D01*
X751270Y37731D01*
Y37771D01*
X751265Y37816D01*
X751270Y37861D01*
Y37901D01*
X751275Y37946D01*
X751285Y37986D01*
X751290Y38026D01*
X751305Y38071D01*
X751315Y38111D01*
X751330Y38151D01*
X751350Y38191D01*
X751365Y38226D01*
X751385Y38266D01*
X751485Y38406D01*
X751515Y38436D01*
Y41866D01*
X751525Y41991D01*
X751565Y42116D01*
X751625Y42226D01*
X751705Y42326D01*
X751805Y42406D01*
X751915Y42466D01*
X752040Y42506D01*
X752165Y42516D01*
X752290Y42506D01*
X752415Y42466D01*
X752525Y42406D01*
X752625Y42326D01*
X752705Y42226D01*
X752765Y42116D01*
X752805Y41991D01*
X752815Y41866D01*
Y38436D01*
X752845Y38406D01*
X752945Y38266D01*
X752965Y38226D01*
X752980Y38191D01*
X753000Y38151D01*
X753015Y38111D01*
X753025Y38071D01*
X753040Y38026D01*
X753045Y37986D01*
X753055Y37946D01*
X753060Y37901D01*
Y37861D01*
X753065Y37816D01*
X753060Y37771D01*
Y37731D01*
X753055Y37686D01*
X753045Y37646D01*
X753040Y37606D01*
X753025Y37561D01*
X753015Y37521D01*
X753000Y37481D01*
X752980Y37441D01*
X752965Y37406D01*
X752945Y37366D01*
X752845Y37226D01*
X752815Y37196D01*
Y36066D01*
X752805Y35941D01*
X752765Y35816D01*
X752705Y35706D01*
X752625Y35606D01*
X752525Y35526D01*
X752415Y35466D01*
X752290Y35426D01*
X752165Y35416D01*
G37*
G36*
G01X747441D02*
X747316Y35426D01*
X747191Y35466D01*
X747081Y35526D01*
X746981Y35606D01*
X746901Y35706D01*
X746841Y35816D01*
X746801Y35941D01*
X746791Y36066D01*
Y37196D01*
X746761Y37226D01*
X746661Y37366D01*
X746641Y37406D01*
X746626Y37441D01*
X746606Y37481D01*
X746591Y37521D01*
X746581Y37561D01*
X746566Y37606D01*
X746561Y37646D01*
X746551Y37686D01*
X746546Y37731D01*
Y37771D01*
X746541Y37816D01*
X746546Y37861D01*
Y37901D01*
X746551Y37946D01*
X746561Y37986D01*
X746566Y38026D01*
X746581Y38071D01*
X746591Y38111D01*
X746606Y38151D01*
X746626Y38191D01*
X746641Y38226D01*
X746661Y38266D01*
X746761Y38406D01*
X746791Y38436D01*
Y41866D01*
X746801Y41991D01*
X746841Y42116D01*
X746901Y42226D01*
X746981Y42326D01*
X747081Y42406D01*
X747191Y42466D01*
X747316Y42506D01*
X747441Y42516D01*
X747566Y42506D01*
X747691Y42466D01*
X747801Y42406D01*
X747901Y42326D01*
X747981Y42226D01*
X748041Y42116D01*
X748081Y41991D01*
X748091Y41866D01*
Y38436D01*
X748121Y38406D01*
X748221Y38266D01*
X748241Y38226D01*
X748256Y38191D01*
X748276Y38151D01*
X748291Y38111D01*
X748301Y38071D01*
X748316Y38026D01*
X748321Y37986D01*
X748331Y37946D01*
X748336Y37901D01*
Y37861D01*
X748341Y37816D01*
X748336Y37771D01*
Y37731D01*
X748331Y37686D01*
X748321Y37646D01*
X748316Y37606D01*
X748301Y37561D01*
X748291Y37521D01*
X748276Y37481D01*
X748256Y37441D01*
X748241Y37406D01*
X748221Y37366D01*
X748121Y37226D01*
X748091Y37196D01*
Y36066D01*
X748081Y35941D01*
X748041Y35816D01*
X747981Y35706D01*
X747901Y35606D01*
X747801Y35526D01*
X747691Y35466D01*
X747566Y35426D01*
X747441Y35416D01*
G37*
G36*
G01X742716D02*
X742591Y35426D01*
X742466Y35466D01*
X742356Y35526D01*
X742256Y35606D01*
X742176Y35706D01*
X742116Y35816D01*
X742076Y35941D01*
X742066Y36066D01*
Y37196D01*
X742036Y37226D01*
X741936Y37366D01*
X741916Y37406D01*
X741901Y37441D01*
X741881Y37481D01*
X741866Y37521D01*
X741856Y37561D01*
X741841Y37606D01*
X741836Y37646D01*
X741826Y37686D01*
X741821Y37731D01*
Y37771D01*
X741816Y37816D01*
X741821Y37861D01*
Y37901D01*
X741826Y37946D01*
X741836Y37986D01*
X741841Y38026D01*
X741856Y38071D01*
X741866Y38111D01*
X741881Y38151D01*
X741901Y38191D01*
X741916Y38226D01*
X741936Y38266D01*
X742036Y38406D01*
X742066Y38436D01*
Y41866D01*
X742076Y41991D01*
X742116Y42116D01*
X742176Y42226D01*
X742256Y42326D01*
X742356Y42406D01*
X742466Y42466D01*
X742591Y42506D01*
X742716Y42516D01*
X742841Y42506D01*
X742966Y42466D01*
X743076Y42406D01*
X743176Y42326D01*
X743256Y42226D01*
X743316Y42116D01*
X743356Y41991D01*
X743366Y41866D01*
Y38436D01*
X743396Y38406D01*
X743496Y38266D01*
X743516Y38226D01*
X743531Y38191D01*
X743551Y38151D01*
X743566Y38111D01*
X743576Y38071D01*
X743591Y38026D01*
X743596Y37986D01*
X743606Y37946D01*
X743611Y37901D01*
Y37861D01*
X743616Y37816D01*
X743611Y37771D01*
Y37731D01*
X743606Y37686D01*
X743596Y37646D01*
X743591Y37606D01*
X743576Y37561D01*
X743566Y37521D01*
X743551Y37481D01*
X743531Y37441D01*
X743516Y37406D01*
X743496Y37366D01*
X743396Y37226D01*
X743366Y37196D01*
Y36066D01*
X743356Y35941D01*
X743316Y35816D01*
X743256Y35706D01*
X743176Y35606D01*
X743076Y35526D01*
X742966Y35466D01*
X742841Y35426D01*
X742716Y35416D01*
G37*
G54D27*
X44150Y126000D03*
X208650Y210500D03*
G54D28*
X43500Y143500D03*
X55000Y101500D03*
G54D64*
X164500Y228500D03*
G54D55*
X136800Y255861D03*
G36*
G01X499410Y249980D02*
X499535Y249970D01*
X499660Y249930D01*
X499770Y249870D01*
X499870Y249790D01*
X499950Y249690D01*
X500010Y249580D01*
X500050Y249455D01*
X500060Y249330D01*
Y247205D01*
X500090Y247175D01*
X500115Y247140D01*
X500145Y247105D01*
X500165Y247070D01*
X500190Y247035D01*
X500230Y246955D01*
X500275Y246835D01*
X500285Y246795D01*
X500295Y246750D01*
X500300Y246710D01*
X500310Y246665D01*
Y246495D01*
X500300Y246450D01*
X500295Y246410D01*
X500285Y246365D01*
X500275Y246325D01*
X500230Y246205D01*
X500190Y246125D01*
X500165Y246090D01*
X500145Y246055D01*
X500115Y246020D01*
X500090Y245985D01*
X500060Y245955D01*
Y243530D01*
X500050Y243405D01*
X500010Y243280D01*
X499950Y243170D01*
X499870Y243070D01*
X499770Y242990D01*
X499660Y242930D01*
X499535Y242890D01*
X499410Y242880D01*
X499285Y242890D01*
X499160Y242930D01*
X499050Y242990D01*
X498950Y243070D01*
X498870Y243170D01*
X498810Y243280D01*
X498770Y243405D01*
X498760Y243530D01*
Y245960D01*
X498730Y245990D01*
X498630Y246130D01*
X498610Y246170D01*
X498595Y246205D01*
X498575Y246245D01*
X498560Y246285D01*
X498550Y246325D01*
X498535Y246370D01*
X498530Y246410D01*
X498520Y246450D01*
X498515Y246495D01*
Y246535D01*
X498510Y246580D01*
X498515Y246625D01*
Y246665D01*
X498520Y246710D01*
X498530Y246750D01*
X498535Y246790D01*
X498550Y246835D01*
X498560Y246875D01*
X498575Y246915D01*
X498595Y246955D01*
X498610Y246990D01*
X498630Y247030D01*
X498730Y247170D01*
X498760Y247200D01*
Y249330D01*
X498770Y249455D01*
X498810Y249580D01*
X498870Y249690D01*
X498950Y249790D01*
X499050Y249870D01*
X499160Y249930D01*
X499285Y249970D01*
X499410Y249980D01*
G37*
G36*
G01X504134D02*
X504259Y249970D01*
X504384Y249930D01*
X504494Y249870D01*
X504594Y249790D01*
X504674Y249690D01*
X504734Y249580D01*
X504774Y249455D01*
X504784Y249330D01*
Y247205D01*
X504814Y247175D01*
X504839Y247140D01*
X504869Y247105D01*
X504889Y247070D01*
X504914Y247035D01*
X504954Y246955D01*
X504999Y246835D01*
X505009Y246795D01*
X505019Y246750D01*
X505024Y246710D01*
X505034Y246665D01*
Y246495D01*
X505024Y246450D01*
X505019Y246410D01*
X505009Y246365D01*
X504999Y246325D01*
X504954Y246205D01*
X504914Y246125D01*
X504889Y246090D01*
X504869Y246055D01*
X504839Y246020D01*
X504814Y245985D01*
X504784Y245955D01*
Y243530D01*
X504774Y243405D01*
X504734Y243280D01*
X504674Y243170D01*
X504594Y243070D01*
X504494Y242990D01*
X504384Y242930D01*
X504259Y242890D01*
X504134Y242880D01*
X504009Y242890D01*
X503884Y242930D01*
X503774Y242990D01*
X503674Y243070D01*
X503594Y243170D01*
X503534Y243280D01*
X503494Y243405D01*
X503484Y243530D01*
Y245960D01*
X503454Y245990D01*
X503354Y246130D01*
X503334Y246170D01*
X503319Y246205D01*
X503299Y246245D01*
X503284Y246285D01*
X503274Y246325D01*
X503259Y246370D01*
X503254Y246410D01*
X503244Y246450D01*
X503239Y246495D01*
Y246535D01*
X503234Y246580D01*
X503239Y246625D01*
Y246665D01*
X503244Y246710D01*
X503254Y246750D01*
X503259Y246790D01*
X503274Y246835D01*
X503284Y246875D01*
X503299Y246915D01*
X503319Y246955D01*
X503334Y246990D01*
X503354Y247030D01*
X503454Y247170D01*
X503484Y247200D01*
Y249330D01*
X503494Y249455D01*
X503534Y249580D01*
X503594Y249690D01*
X503674Y249790D01*
X503774Y249870D01*
X503884Y249930D01*
X504009Y249970D01*
X504134Y249980D01*
G37*
G36*
G01X508859D02*
X508984Y249970D01*
X509109Y249930D01*
X509219Y249870D01*
X509319Y249790D01*
X509399Y249690D01*
X509459Y249580D01*
X509499Y249455D01*
X509509Y249330D01*
Y247205D01*
X509539Y247175D01*
X509564Y247140D01*
X509594Y247105D01*
X509614Y247070D01*
X509639Y247035D01*
X509679Y246955D01*
X509724Y246835D01*
X509734Y246795D01*
X509744Y246750D01*
X509749Y246710D01*
X509759Y246665D01*
Y246495D01*
X509749Y246450D01*
X509744Y246410D01*
X509734Y246365D01*
X509724Y246325D01*
X509679Y246205D01*
X509639Y246125D01*
X509614Y246090D01*
X509594Y246055D01*
X509564Y246020D01*
X509539Y245985D01*
X509509Y245955D01*
Y243530D01*
X509499Y243405D01*
X509459Y243280D01*
X509399Y243170D01*
X509319Y243070D01*
X509219Y242990D01*
X509109Y242930D01*
X508984Y242890D01*
X508859Y242880D01*
X508734Y242890D01*
X508609Y242930D01*
X508499Y242990D01*
X508399Y243070D01*
X508319Y243170D01*
X508259Y243280D01*
X508219Y243405D01*
X508209Y243530D01*
Y245960D01*
X508179Y245990D01*
X508079Y246130D01*
X508059Y246170D01*
X508044Y246205D01*
X508024Y246245D01*
X508009Y246285D01*
X507999Y246325D01*
X507984Y246370D01*
X507979Y246410D01*
X507969Y246450D01*
X507964Y246495D01*
Y246535D01*
X507959Y246580D01*
X507964Y246625D01*
Y246665D01*
X507969Y246710D01*
X507979Y246750D01*
X507984Y246790D01*
X507999Y246835D01*
X508009Y246875D01*
X508024Y246915D01*
X508044Y246955D01*
X508059Y246990D01*
X508079Y247030D01*
X508179Y247170D01*
X508209Y247200D01*
Y249330D01*
X508219Y249455D01*
X508259Y249580D01*
X508319Y249690D01*
X508399Y249790D01*
X508499Y249870D01*
X508609Y249930D01*
X508734Y249970D01*
X508859Y249980D01*
G37*
G36*
G01X513583D02*
X513708Y249970D01*
X513833Y249930D01*
X513943Y249870D01*
X514043Y249790D01*
X514123Y249690D01*
X514183Y249580D01*
X514223Y249455D01*
X514233Y249330D01*
Y247205D01*
X514263Y247175D01*
X514288Y247140D01*
X514318Y247105D01*
X514338Y247070D01*
X514363Y247035D01*
X514403Y246955D01*
X514448Y246835D01*
X514458Y246795D01*
X514468Y246750D01*
X514473Y246710D01*
X514483Y246665D01*
Y246495D01*
X514473Y246450D01*
X514468Y246410D01*
X514458Y246365D01*
X514448Y246325D01*
X514403Y246205D01*
X514363Y246125D01*
X514338Y246090D01*
X514318Y246055D01*
X514288Y246020D01*
X514263Y245985D01*
X514233Y245955D01*
Y243530D01*
X514223Y243405D01*
X514183Y243280D01*
X514123Y243170D01*
X514043Y243070D01*
X513943Y242990D01*
X513833Y242930D01*
X513708Y242890D01*
X513583Y242880D01*
X513458Y242890D01*
X513333Y242930D01*
X513223Y242990D01*
X513123Y243070D01*
X513043Y243170D01*
X512983Y243280D01*
X512943Y243405D01*
X512933Y243530D01*
Y245960D01*
X512903Y245990D01*
X512803Y246130D01*
X512783Y246170D01*
X512768Y246205D01*
X512748Y246245D01*
X512733Y246285D01*
X512723Y246325D01*
X512708Y246370D01*
X512703Y246410D01*
X512693Y246450D01*
X512688Y246495D01*
Y246535D01*
X512683Y246580D01*
X512688Y246625D01*
Y246665D01*
X512693Y246710D01*
X512703Y246750D01*
X512708Y246790D01*
X512723Y246835D01*
X512733Y246875D01*
X512748Y246915D01*
X512768Y246955D01*
X512783Y246990D01*
X512803Y247030D01*
X512903Y247170D01*
X512933Y247200D01*
Y249330D01*
X512943Y249455D01*
X512983Y249580D01*
X513043Y249690D01*
X513123Y249790D01*
X513223Y249870D01*
X513333Y249930D01*
X513458Y249970D01*
X513583Y249980D01*
G37*
G36*
G01X518307D02*
X518432Y249970D01*
X518557Y249930D01*
X518667Y249870D01*
X518767Y249790D01*
X518847Y249690D01*
X518907Y249580D01*
X518947Y249455D01*
X518957Y249330D01*
Y247205D01*
X518987Y247175D01*
X519012Y247140D01*
X519042Y247105D01*
X519062Y247070D01*
X519087Y247035D01*
X519127Y246955D01*
X519172Y246835D01*
X519182Y246795D01*
X519192Y246750D01*
X519197Y246710D01*
X519207Y246665D01*
Y246495D01*
X519197Y246450D01*
X519192Y246410D01*
X519182Y246365D01*
X519172Y246325D01*
X519127Y246205D01*
X519087Y246125D01*
X519062Y246090D01*
X519042Y246055D01*
X519012Y246020D01*
X518987Y245985D01*
X518957Y245955D01*
Y243530D01*
X518947Y243405D01*
X518907Y243280D01*
X518847Y243170D01*
X518767Y243070D01*
X518667Y242990D01*
X518557Y242930D01*
X518432Y242890D01*
X518307Y242880D01*
X518182Y242890D01*
X518057Y242930D01*
X517947Y242990D01*
X517847Y243070D01*
X517767Y243170D01*
X517707Y243280D01*
X517667Y243405D01*
X517657Y243530D01*
Y245960D01*
X517627Y245990D01*
X517527Y246130D01*
X517507Y246170D01*
X517492Y246205D01*
X517472Y246245D01*
X517457Y246285D01*
X517447Y246325D01*
X517432Y246370D01*
X517427Y246410D01*
X517417Y246450D01*
X517412Y246495D01*
Y246535D01*
X517407Y246580D01*
X517412Y246625D01*
Y246665D01*
X517417Y246710D01*
X517427Y246750D01*
X517432Y246790D01*
X517447Y246835D01*
X517457Y246875D01*
X517472Y246915D01*
X517492Y246955D01*
X517507Y246990D01*
X517527Y247030D01*
X517627Y247170D01*
X517657Y247200D01*
Y249330D01*
X517667Y249455D01*
X517707Y249580D01*
X517767Y249690D01*
X517847Y249790D01*
X517947Y249870D01*
X518057Y249930D01*
X518182Y249970D01*
X518307Y249980D01*
G37*
G36*
G01X523032D02*
X523157Y249970D01*
X523282Y249930D01*
X523392Y249870D01*
X523492Y249790D01*
X523572Y249690D01*
X523632Y249580D01*
X523672Y249455D01*
X523682Y249330D01*
Y247205D01*
X523712Y247175D01*
X523737Y247140D01*
X523767Y247105D01*
X523787Y247070D01*
X523812Y247035D01*
X523852Y246955D01*
X523897Y246835D01*
X523907Y246795D01*
X523917Y246750D01*
X523922Y246710D01*
X523932Y246665D01*
Y246495D01*
X523922Y246450D01*
X523917Y246410D01*
X523907Y246365D01*
X523897Y246325D01*
X523852Y246205D01*
X523812Y246125D01*
X523787Y246090D01*
X523767Y246055D01*
X523737Y246020D01*
X523712Y245985D01*
X523682Y245955D01*
Y243530D01*
X523672Y243405D01*
X523632Y243280D01*
X523572Y243170D01*
X523492Y243070D01*
X523392Y242990D01*
X523282Y242930D01*
X523157Y242890D01*
X523032Y242880D01*
X522907Y242890D01*
X522782Y242930D01*
X522672Y242990D01*
X522572Y243070D01*
X522492Y243170D01*
X522432Y243280D01*
X522392Y243405D01*
X522382Y243530D01*
Y245960D01*
X522352Y245990D01*
X522252Y246130D01*
X522232Y246170D01*
X522217Y246205D01*
X522197Y246245D01*
X522182Y246285D01*
X522172Y246325D01*
X522157Y246370D01*
X522152Y246410D01*
X522142Y246450D01*
X522137Y246495D01*
Y246535D01*
X522132Y246580D01*
X522137Y246625D01*
Y246665D01*
X522142Y246710D01*
X522152Y246750D01*
X522157Y246790D01*
X522172Y246835D01*
X522182Y246875D01*
X522197Y246915D01*
X522217Y246955D01*
X522232Y246990D01*
X522252Y247030D01*
X522352Y247170D01*
X522382Y247200D01*
Y249330D01*
X522392Y249455D01*
X522432Y249580D01*
X522492Y249690D01*
X522572Y249790D01*
X522672Y249870D01*
X522782Y249930D01*
X522907Y249970D01*
X523032Y249980D01*
G37*
G36*
G01X527756D02*
X527881Y249970D01*
X528006Y249930D01*
X528116Y249870D01*
X528216Y249790D01*
X528296Y249690D01*
X528356Y249580D01*
X528396Y249455D01*
X528406Y249330D01*
Y247205D01*
X528436Y247175D01*
X528461Y247140D01*
X528491Y247105D01*
X528511Y247070D01*
X528536Y247035D01*
X528576Y246955D01*
X528621Y246835D01*
X528631Y246795D01*
X528641Y246750D01*
X528646Y246710D01*
X528656Y246665D01*
Y246495D01*
X528646Y246450D01*
X528641Y246410D01*
X528631Y246365D01*
X528621Y246325D01*
X528576Y246205D01*
X528536Y246125D01*
X528511Y246090D01*
X528491Y246055D01*
X528461Y246020D01*
X528436Y245985D01*
X528406Y245955D01*
Y243530D01*
X528396Y243405D01*
X528356Y243280D01*
X528296Y243170D01*
X528216Y243070D01*
X528116Y242990D01*
X528006Y242930D01*
X527881Y242890D01*
X527756Y242880D01*
X527631Y242890D01*
X527506Y242930D01*
X527396Y242990D01*
X527296Y243070D01*
X527216Y243170D01*
X527156Y243280D01*
X527116Y243405D01*
X527106Y243530D01*
Y245960D01*
X527076Y245990D01*
X526976Y246130D01*
X526956Y246170D01*
X526941Y246205D01*
X526921Y246245D01*
X526906Y246285D01*
X526896Y246325D01*
X526881Y246370D01*
X526876Y246410D01*
X526866Y246450D01*
X526861Y246495D01*
Y246535D01*
X526856Y246580D01*
X526861Y246625D01*
Y246665D01*
X526866Y246710D01*
X526876Y246750D01*
X526881Y246790D01*
X526896Y246835D01*
X526906Y246875D01*
X526921Y246915D01*
X526941Y246955D01*
X526956Y246990D01*
X526976Y247030D01*
X527076Y247170D01*
X527106Y247200D01*
Y249330D01*
X527116Y249455D01*
X527156Y249580D01*
X527216Y249690D01*
X527296Y249790D01*
X527396Y249870D01*
X527506Y249930D01*
X527631Y249970D01*
X527756Y249980D01*
G37*
G36*
G01X532481D02*
X532606Y249970D01*
X532731Y249930D01*
X532841Y249870D01*
X532941Y249790D01*
X533021Y249690D01*
X533081Y249580D01*
X533121Y249455D01*
X533131Y249330D01*
Y247205D01*
X533161Y247175D01*
X533186Y247140D01*
X533216Y247105D01*
X533236Y247070D01*
X533261Y247035D01*
X533301Y246955D01*
X533346Y246835D01*
X533356Y246795D01*
X533366Y246750D01*
X533371Y246710D01*
X533381Y246665D01*
Y246495D01*
X533371Y246450D01*
X533366Y246410D01*
X533356Y246365D01*
X533346Y246325D01*
X533301Y246205D01*
X533261Y246125D01*
X533236Y246090D01*
X533216Y246055D01*
X533186Y246020D01*
X533161Y245985D01*
X533131Y245955D01*
Y243530D01*
X533121Y243405D01*
X533081Y243280D01*
X533021Y243170D01*
X532941Y243070D01*
X532841Y242990D01*
X532731Y242930D01*
X532606Y242890D01*
X532481Y242880D01*
X532356Y242890D01*
X532231Y242930D01*
X532121Y242990D01*
X532021Y243070D01*
X531941Y243170D01*
X531881Y243280D01*
X531841Y243405D01*
X531831Y243530D01*
Y245960D01*
X531801Y245990D01*
X531701Y246130D01*
X531681Y246170D01*
X531666Y246205D01*
X531646Y246245D01*
X531631Y246285D01*
X531621Y246325D01*
X531606Y246370D01*
X531601Y246410D01*
X531591Y246450D01*
X531586Y246495D01*
Y246535D01*
X531581Y246580D01*
X531586Y246625D01*
Y246665D01*
X531591Y246710D01*
X531601Y246750D01*
X531606Y246790D01*
X531621Y246835D01*
X531631Y246875D01*
X531646Y246915D01*
X531666Y246955D01*
X531681Y246990D01*
X531701Y247030D01*
X531801Y247170D01*
X531831Y247200D01*
Y249330D01*
X531841Y249455D01*
X531881Y249580D01*
X531941Y249690D01*
X532021Y249790D01*
X532121Y249870D01*
X532231Y249930D01*
X532356Y249970D01*
X532481Y249980D01*
G37*
G36*
G01X537205D02*
X537330Y249970D01*
X537455Y249930D01*
X537565Y249870D01*
X537665Y249790D01*
X537745Y249690D01*
X537805Y249580D01*
X537845Y249455D01*
X537855Y249330D01*
Y247205D01*
X537885Y247175D01*
X537910Y247140D01*
X537940Y247105D01*
X537960Y247070D01*
X537985Y247035D01*
X538025Y246955D01*
X538070Y246835D01*
X538080Y246795D01*
X538090Y246750D01*
X538095Y246710D01*
X538105Y246665D01*
Y246495D01*
X538095Y246450D01*
X538090Y246410D01*
X538080Y246365D01*
X538070Y246325D01*
X538025Y246205D01*
X537985Y246125D01*
X537960Y246090D01*
X537940Y246055D01*
X537910Y246020D01*
X537885Y245985D01*
X537855Y245955D01*
Y243530D01*
X537845Y243405D01*
X537805Y243280D01*
X537745Y243170D01*
X537665Y243070D01*
X537565Y242990D01*
X537455Y242930D01*
X537330Y242890D01*
X537205Y242880D01*
X537080Y242890D01*
X536955Y242930D01*
X536845Y242990D01*
X536745Y243070D01*
X536665Y243170D01*
X536605Y243280D01*
X536565Y243405D01*
X536555Y243530D01*
Y245960D01*
X536525Y245990D01*
X536425Y246130D01*
X536405Y246170D01*
X536390Y246205D01*
X536370Y246245D01*
X536355Y246285D01*
X536345Y246325D01*
X536330Y246370D01*
X536325Y246410D01*
X536315Y246450D01*
X536310Y246495D01*
Y246535D01*
X536305Y246580D01*
X536310Y246625D01*
Y246665D01*
X536315Y246710D01*
X536325Y246750D01*
X536330Y246790D01*
X536345Y246835D01*
X536355Y246875D01*
X536370Y246915D01*
X536390Y246955D01*
X536405Y246990D01*
X536425Y247030D01*
X536525Y247170D01*
X536555Y247200D01*
Y249330D01*
X536565Y249455D01*
X536605Y249580D01*
X536665Y249690D01*
X536745Y249790D01*
X536845Y249870D01*
X536955Y249930D01*
X537080Y249970D01*
X537205Y249980D01*
G37*
G36*
G01X541929D02*
X542054Y249970D01*
X542179Y249930D01*
X542289Y249870D01*
X542389Y249790D01*
X542469Y249690D01*
X542529Y249580D01*
X542569Y249455D01*
X542579Y249330D01*
Y247205D01*
X542609Y247175D01*
X542634Y247140D01*
X542664Y247105D01*
X542684Y247070D01*
X542709Y247035D01*
X542749Y246955D01*
X542794Y246835D01*
X542804Y246795D01*
X542814Y246750D01*
X542819Y246710D01*
X542829Y246665D01*
Y246495D01*
X542819Y246450D01*
X542814Y246410D01*
X542804Y246365D01*
X542794Y246325D01*
X542749Y246205D01*
X542709Y246125D01*
X542684Y246090D01*
X542664Y246055D01*
X542634Y246020D01*
X542609Y245985D01*
X542579Y245955D01*
Y243530D01*
X542569Y243405D01*
X542529Y243280D01*
X542469Y243170D01*
X542389Y243070D01*
X542289Y242990D01*
X542179Y242930D01*
X542054Y242890D01*
X541929Y242880D01*
X541804Y242890D01*
X541679Y242930D01*
X541569Y242990D01*
X541469Y243070D01*
X541389Y243170D01*
X541329Y243280D01*
X541289Y243405D01*
X541279Y243530D01*
Y245960D01*
X541249Y245990D01*
X541149Y246130D01*
X541129Y246170D01*
X541114Y246205D01*
X541094Y246245D01*
X541079Y246285D01*
X541069Y246325D01*
X541054Y246370D01*
X541049Y246410D01*
X541039Y246450D01*
X541034Y246495D01*
Y246535D01*
X541029Y246580D01*
X541034Y246625D01*
Y246665D01*
X541039Y246710D01*
X541049Y246750D01*
X541054Y246790D01*
X541069Y246835D01*
X541079Y246875D01*
X541094Y246915D01*
X541114Y246955D01*
X541129Y246990D01*
X541149Y247030D01*
X541249Y247170D01*
X541279Y247200D01*
Y249330D01*
X541289Y249455D01*
X541329Y249580D01*
X541389Y249690D01*
X541469Y249790D01*
X541569Y249870D01*
X541679Y249930D01*
X541804Y249970D01*
X541929Y249980D01*
G37*
G36*
G01X546654D02*
X546779Y249970D01*
X546904Y249930D01*
X547014Y249870D01*
X547114Y249790D01*
X547194Y249690D01*
X547254Y249580D01*
X547294Y249455D01*
X547304Y249330D01*
Y247205D01*
X547334Y247175D01*
X547359Y247140D01*
X547389Y247105D01*
X547409Y247070D01*
X547434Y247035D01*
X547474Y246955D01*
X547519Y246835D01*
X547529Y246795D01*
X547539Y246750D01*
X547544Y246710D01*
X547554Y246665D01*
Y246495D01*
X547544Y246450D01*
X547539Y246410D01*
X547529Y246365D01*
X547519Y246325D01*
X547474Y246205D01*
X547434Y246125D01*
X547409Y246090D01*
X547389Y246055D01*
X547359Y246020D01*
X547334Y245985D01*
X547304Y245955D01*
Y243530D01*
X547294Y243405D01*
X547254Y243280D01*
X547194Y243170D01*
X547114Y243070D01*
X547014Y242990D01*
X546904Y242930D01*
X546779Y242890D01*
X546654Y242880D01*
X546529Y242890D01*
X546404Y242930D01*
X546294Y242990D01*
X546194Y243070D01*
X546114Y243170D01*
X546054Y243280D01*
X546014Y243405D01*
X546004Y243530D01*
Y245960D01*
X545974Y245990D01*
X545874Y246130D01*
X545854Y246170D01*
X545839Y246205D01*
X545819Y246245D01*
X545804Y246285D01*
X545794Y246325D01*
X545779Y246370D01*
X545774Y246410D01*
X545764Y246450D01*
X545759Y246495D01*
Y246535D01*
X545754Y246580D01*
X545759Y246625D01*
Y246665D01*
X545764Y246710D01*
X545774Y246750D01*
X545779Y246790D01*
X545794Y246835D01*
X545804Y246875D01*
X545819Y246915D01*
X545839Y246955D01*
X545854Y246990D01*
X545874Y247030D01*
X545974Y247170D01*
X546004Y247200D01*
Y249330D01*
X546014Y249455D01*
X546054Y249580D01*
X546114Y249690D01*
X546194Y249790D01*
X546294Y249870D01*
X546404Y249930D01*
X546529Y249970D01*
X546654Y249980D01*
G37*
G36*
G01X551378D02*
X551503Y249970D01*
X551628Y249930D01*
X551738Y249870D01*
X551838Y249790D01*
X551918Y249690D01*
X551978Y249580D01*
X552018Y249455D01*
X552028Y249330D01*
Y247205D01*
X552058Y247175D01*
X552083Y247140D01*
X552113Y247105D01*
X552133Y247070D01*
X552158Y247035D01*
X552198Y246955D01*
X552243Y246835D01*
X552253Y246795D01*
X552263Y246750D01*
X552268Y246710D01*
X552278Y246665D01*
Y246495D01*
X552268Y246450D01*
X552263Y246410D01*
X552253Y246365D01*
X552243Y246325D01*
X552198Y246205D01*
X552158Y246125D01*
X552133Y246090D01*
X552113Y246055D01*
X552083Y246020D01*
X552058Y245985D01*
X552028Y245955D01*
Y243530D01*
X552018Y243405D01*
X551978Y243280D01*
X551918Y243170D01*
X551838Y243070D01*
X551738Y242990D01*
X551628Y242930D01*
X551503Y242890D01*
X551378Y242880D01*
X551253Y242890D01*
X551128Y242930D01*
X551018Y242990D01*
X550918Y243070D01*
X550838Y243170D01*
X550778Y243280D01*
X550738Y243405D01*
X550728Y243530D01*
Y245960D01*
X550698Y245990D01*
X550598Y246130D01*
X550578Y246170D01*
X550563Y246205D01*
X550543Y246245D01*
X550528Y246285D01*
X550518Y246325D01*
X550503Y246370D01*
X550498Y246410D01*
X550488Y246450D01*
X550483Y246495D01*
Y246535D01*
X550478Y246580D01*
X550483Y246625D01*
Y246665D01*
X550488Y246710D01*
X550498Y246750D01*
X550503Y246790D01*
X550518Y246835D01*
X550528Y246875D01*
X550543Y246915D01*
X550563Y246955D01*
X550578Y246990D01*
X550598Y247030D01*
X550698Y247170D01*
X550728Y247200D01*
Y249330D01*
X550738Y249455D01*
X550778Y249580D01*
X550838Y249690D01*
X550918Y249790D01*
X551018Y249870D01*
X551128Y249930D01*
X551253Y249970D01*
X551378Y249980D01*
G37*
G36*
G01X556103D02*
X556228Y249970D01*
X556353Y249930D01*
X556463Y249870D01*
X556563Y249790D01*
X556643Y249690D01*
X556703Y249580D01*
X556743Y249455D01*
X556753Y249330D01*
Y247205D01*
X556783Y247175D01*
X556808Y247140D01*
X556838Y247105D01*
X556858Y247070D01*
X556883Y247035D01*
X556923Y246955D01*
X556968Y246835D01*
X556978Y246795D01*
X556988Y246750D01*
X556993Y246710D01*
X557003Y246665D01*
Y246495D01*
X556993Y246450D01*
X556988Y246410D01*
X556978Y246365D01*
X556968Y246325D01*
X556923Y246205D01*
X556883Y246125D01*
X556858Y246090D01*
X556838Y246055D01*
X556808Y246020D01*
X556783Y245985D01*
X556753Y245955D01*
Y243530D01*
X556743Y243405D01*
X556703Y243280D01*
X556643Y243170D01*
X556563Y243070D01*
X556463Y242990D01*
X556353Y242930D01*
X556228Y242890D01*
X556103Y242880D01*
X555978Y242890D01*
X555853Y242930D01*
X555743Y242990D01*
X555643Y243070D01*
X555563Y243170D01*
X555503Y243280D01*
X555463Y243405D01*
X555453Y243530D01*
Y245960D01*
X555423Y245990D01*
X555323Y246130D01*
X555303Y246170D01*
X555288Y246205D01*
X555268Y246245D01*
X555253Y246285D01*
X555243Y246325D01*
X555228Y246370D01*
X555223Y246410D01*
X555213Y246450D01*
X555208Y246495D01*
Y246535D01*
X555203Y246580D01*
X555208Y246625D01*
Y246665D01*
X555213Y246710D01*
X555223Y246750D01*
X555228Y246790D01*
X555243Y246835D01*
X555253Y246875D01*
X555268Y246915D01*
X555288Y246955D01*
X555303Y246990D01*
X555323Y247030D01*
X555423Y247170D01*
X555453Y247200D01*
Y249330D01*
X555463Y249455D01*
X555503Y249580D01*
X555563Y249690D01*
X555643Y249790D01*
X555743Y249870D01*
X555853Y249930D01*
X555978Y249970D01*
X556103Y249980D01*
G37*
G36*
G01X560827D02*
X560952Y249970D01*
X561077Y249930D01*
X561187Y249870D01*
X561287Y249790D01*
X561367Y249690D01*
X561427Y249580D01*
X561467Y249455D01*
X561477Y249330D01*
Y247205D01*
X561507Y247175D01*
X561532Y247140D01*
X561562Y247105D01*
X561582Y247070D01*
X561607Y247035D01*
X561647Y246955D01*
X561692Y246835D01*
X561702Y246795D01*
X561712Y246750D01*
X561717Y246710D01*
X561727Y246665D01*
Y246495D01*
X561717Y246450D01*
X561712Y246410D01*
X561702Y246365D01*
X561692Y246325D01*
X561647Y246205D01*
X561607Y246125D01*
X561582Y246090D01*
X561562Y246055D01*
X561532Y246020D01*
X561507Y245985D01*
X561477Y245955D01*
Y243530D01*
X561467Y243405D01*
X561427Y243280D01*
X561367Y243170D01*
X561287Y243070D01*
X561187Y242990D01*
X561077Y242930D01*
X560952Y242890D01*
X560827Y242880D01*
X560702Y242890D01*
X560577Y242930D01*
X560467Y242990D01*
X560367Y243070D01*
X560287Y243170D01*
X560227Y243280D01*
X560187Y243405D01*
X560177Y243530D01*
Y245960D01*
X560147Y245990D01*
X560047Y246130D01*
X560027Y246170D01*
X560012Y246205D01*
X559992Y246245D01*
X559977Y246285D01*
X559967Y246325D01*
X559952Y246370D01*
X559947Y246410D01*
X559937Y246450D01*
X559932Y246495D01*
Y246535D01*
X559927Y246580D01*
X559932Y246625D01*
Y246665D01*
X559937Y246710D01*
X559947Y246750D01*
X559952Y246790D01*
X559967Y246835D01*
X559977Y246875D01*
X559992Y246915D01*
X560012Y246955D01*
X560027Y246990D01*
X560047Y247030D01*
X560147Y247170D01*
X560177Y247200D01*
Y249330D01*
X560187Y249455D01*
X560227Y249580D01*
X560287Y249690D01*
X560367Y249790D01*
X560467Y249870D01*
X560577Y249930D01*
X560702Y249970D01*
X560827Y249980D01*
G37*
G36*
G01X565551D02*
X565676Y249970D01*
X565801Y249930D01*
X565911Y249870D01*
X566011Y249790D01*
X566091Y249690D01*
X566151Y249580D01*
X566191Y249455D01*
X566201Y249330D01*
Y247205D01*
X566231Y247175D01*
X566256Y247140D01*
X566286Y247105D01*
X566306Y247070D01*
X566331Y247035D01*
X566371Y246955D01*
X566416Y246835D01*
X566426Y246795D01*
X566436Y246750D01*
X566441Y246710D01*
X566451Y246665D01*
Y246495D01*
X566441Y246450D01*
X566436Y246410D01*
X566426Y246365D01*
X566416Y246325D01*
X566371Y246205D01*
X566331Y246125D01*
X566306Y246090D01*
X566286Y246055D01*
X566256Y246020D01*
X566231Y245985D01*
X566201Y245955D01*
Y243530D01*
X566191Y243405D01*
X566151Y243280D01*
X566091Y243170D01*
X566011Y243070D01*
X565911Y242990D01*
X565801Y242930D01*
X565676Y242890D01*
X565551Y242880D01*
X565426Y242890D01*
X565301Y242930D01*
X565191Y242990D01*
X565091Y243070D01*
X565011Y243170D01*
X564951Y243280D01*
X564911Y243405D01*
X564901Y243530D01*
Y245960D01*
X564871Y245990D01*
X564771Y246130D01*
X564751Y246170D01*
X564736Y246205D01*
X564716Y246245D01*
X564701Y246285D01*
X564691Y246325D01*
X564676Y246370D01*
X564671Y246410D01*
X564661Y246450D01*
X564656Y246495D01*
Y246535D01*
X564651Y246580D01*
X564656Y246625D01*
Y246665D01*
X564661Y246710D01*
X564671Y246750D01*
X564676Y246790D01*
X564691Y246835D01*
X564701Y246875D01*
X564716Y246915D01*
X564736Y246955D01*
X564751Y246990D01*
X564771Y247030D01*
X564871Y247170D01*
X564901Y247200D01*
Y249330D01*
X564911Y249455D01*
X564951Y249580D01*
X565011Y249690D01*
X565091Y249790D01*
X565191Y249870D01*
X565301Y249930D01*
X565426Y249970D01*
X565551Y249980D01*
G37*
G36*
G01X570276D02*
X570401Y249970D01*
X570526Y249930D01*
X570636Y249870D01*
X570736Y249790D01*
X570816Y249690D01*
X570876Y249580D01*
X570916Y249455D01*
X570926Y249330D01*
Y247205D01*
X570956Y247175D01*
X570981Y247140D01*
X571011Y247105D01*
X571031Y247070D01*
X571056Y247035D01*
X571096Y246955D01*
X571141Y246835D01*
X571151Y246795D01*
X571161Y246750D01*
X571166Y246710D01*
X571176Y246665D01*
Y246495D01*
X571166Y246450D01*
X571161Y246410D01*
X571151Y246365D01*
X571141Y246325D01*
X571096Y246205D01*
X571056Y246125D01*
X571031Y246090D01*
X571011Y246055D01*
X570981Y246020D01*
X570956Y245985D01*
X570926Y245955D01*
Y243530D01*
X570916Y243405D01*
X570876Y243280D01*
X570816Y243170D01*
X570736Y243070D01*
X570636Y242990D01*
X570526Y242930D01*
X570401Y242890D01*
X570276Y242880D01*
X570151Y242890D01*
X570026Y242930D01*
X569916Y242990D01*
X569816Y243070D01*
X569736Y243170D01*
X569676Y243280D01*
X569636Y243405D01*
X569626Y243530D01*
Y245960D01*
X569596Y245990D01*
X569496Y246130D01*
X569476Y246170D01*
X569461Y246205D01*
X569441Y246245D01*
X569426Y246285D01*
X569416Y246325D01*
X569401Y246370D01*
X569396Y246410D01*
X569386Y246450D01*
X569381Y246495D01*
Y246535D01*
X569376Y246580D01*
X569381Y246625D01*
Y246665D01*
X569386Y246710D01*
X569396Y246750D01*
X569401Y246790D01*
X569416Y246835D01*
X569426Y246875D01*
X569441Y246915D01*
X569461Y246955D01*
X569476Y246990D01*
X569496Y247030D01*
X569596Y247170D01*
X569626Y247200D01*
Y249330D01*
X569636Y249455D01*
X569676Y249580D01*
X569736Y249690D01*
X569816Y249790D01*
X569916Y249870D01*
X570026Y249930D01*
X570151Y249970D01*
X570276Y249980D01*
G37*
G36*
G01X575000D02*
X575125Y249970D01*
X575250Y249930D01*
X575360Y249870D01*
X575460Y249790D01*
X575540Y249690D01*
X575600Y249580D01*
X575640Y249455D01*
X575650Y249330D01*
Y247205D01*
X575680Y247175D01*
X575705Y247140D01*
X575735Y247105D01*
X575755Y247070D01*
X575780Y247035D01*
X575820Y246955D01*
X575865Y246835D01*
X575875Y246795D01*
X575885Y246750D01*
X575890Y246710D01*
X575900Y246665D01*
Y246495D01*
X575890Y246450D01*
X575885Y246410D01*
X575875Y246365D01*
X575865Y246325D01*
X575820Y246205D01*
X575780Y246125D01*
X575755Y246090D01*
X575735Y246055D01*
X575705Y246020D01*
X575680Y245985D01*
X575650Y245955D01*
Y243530D01*
X575640Y243405D01*
X575600Y243280D01*
X575540Y243170D01*
X575460Y243070D01*
X575360Y242990D01*
X575250Y242930D01*
X575125Y242890D01*
X575000Y242880D01*
X574875Y242890D01*
X574750Y242930D01*
X574640Y242990D01*
X574540Y243070D01*
X574460Y243170D01*
X574400Y243280D01*
X574360Y243405D01*
X574350Y243530D01*
Y245960D01*
X574320Y245990D01*
X574220Y246130D01*
X574200Y246170D01*
X574185Y246205D01*
X574165Y246245D01*
X574150Y246285D01*
X574140Y246325D01*
X574125Y246370D01*
X574120Y246410D01*
X574110Y246450D01*
X574105Y246495D01*
Y246535D01*
X574100Y246580D01*
X574105Y246625D01*
Y246665D01*
X574110Y246710D01*
X574120Y246750D01*
X574125Y246790D01*
X574140Y246835D01*
X574150Y246875D01*
X574165Y246915D01*
X574185Y246955D01*
X574200Y246990D01*
X574220Y247030D01*
X574320Y247170D01*
X574350Y247200D01*
Y249330D01*
X574360Y249455D01*
X574400Y249580D01*
X574460Y249690D01*
X574540Y249790D01*
X574640Y249870D01*
X574750Y249930D01*
X574875Y249970D01*
X575000Y249980D01*
G37*
G36*
G01X579725D02*
X579850Y249970D01*
X579975Y249930D01*
X580085Y249870D01*
X580185Y249790D01*
X580265Y249690D01*
X580325Y249580D01*
X580365Y249455D01*
X580375Y249330D01*
Y247205D01*
X580405Y247175D01*
X580430Y247140D01*
X580460Y247105D01*
X580480Y247070D01*
X580505Y247035D01*
X580545Y246955D01*
X580590Y246835D01*
X580600Y246795D01*
X580610Y246750D01*
X580615Y246710D01*
X580625Y246665D01*
Y246495D01*
X580615Y246450D01*
X580610Y246410D01*
X580600Y246365D01*
X580590Y246325D01*
X580545Y246205D01*
X580505Y246125D01*
X580480Y246090D01*
X580460Y246055D01*
X580430Y246020D01*
X580405Y245985D01*
X580375Y245955D01*
Y243530D01*
X580365Y243405D01*
X580325Y243280D01*
X580265Y243170D01*
X580185Y243070D01*
X580085Y242990D01*
X579975Y242930D01*
X579850Y242890D01*
X579725Y242880D01*
X579600Y242890D01*
X579475Y242930D01*
X579365Y242990D01*
X579265Y243070D01*
X579185Y243170D01*
X579125Y243280D01*
X579085Y243405D01*
X579075Y243530D01*
Y245960D01*
X579045Y245990D01*
X578945Y246130D01*
X578925Y246170D01*
X578910Y246205D01*
X578890Y246245D01*
X578875Y246285D01*
X578865Y246325D01*
X578850Y246370D01*
X578845Y246410D01*
X578835Y246450D01*
X578830Y246495D01*
Y246535D01*
X578825Y246580D01*
X578830Y246625D01*
Y246665D01*
X578835Y246710D01*
X578845Y246750D01*
X578850Y246790D01*
X578865Y246835D01*
X578875Y246875D01*
X578890Y246915D01*
X578910Y246955D01*
X578925Y246990D01*
X578945Y247030D01*
X579045Y247170D01*
X579075Y247200D01*
Y249330D01*
X579085Y249455D01*
X579125Y249580D01*
X579185Y249690D01*
X579265Y249790D01*
X579365Y249870D01*
X579475Y249930D01*
X579600Y249970D01*
X579725Y249980D01*
G37*
G36*
G01X584449D02*
X584574Y249970D01*
X584699Y249930D01*
X584809Y249870D01*
X584909Y249790D01*
X584989Y249690D01*
X585049Y249580D01*
X585089Y249455D01*
X585099Y249330D01*
Y247205D01*
X585129Y247175D01*
X585154Y247140D01*
X585184Y247105D01*
X585204Y247070D01*
X585229Y247035D01*
X585269Y246955D01*
X585314Y246835D01*
X585324Y246795D01*
X585334Y246750D01*
X585339Y246710D01*
X585349Y246665D01*
Y246495D01*
X585339Y246450D01*
X585334Y246410D01*
X585324Y246365D01*
X585314Y246325D01*
X585269Y246205D01*
X585229Y246125D01*
X585204Y246090D01*
X585184Y246055D01*
X585154Y246020D01*
X585129Y245985D01*
X585099Y245955D01*
Y243530D01*
X585089Y243405D01*
X585049Y243280D01*
X584989Y243170D01*
X584909Y243070D01*
X584809Y242990D01*
X584699Y242930D01*
X584574Y242890D01*
X584449Y242880D01*
X584324Y242890D01*
X584199Y242930D01*
X584089Y242990D01*
X583989Y243070D01*
X583909Y243170D01*
X583849Y243280D01*
X583809Y243405D01*
X583799Y243530D01*
Y245960D01*
X583769Y245990D01*
X583669Y246130D01*
X583649Y246170D01*
X583634Y246205D01*
X583614Y246245D01*
X583599Y246285D01*
X583589Y246325D01*
X583574Y246370D01*
X583569Y246410D01*
X583559Y246450D01*
X583554Y246495D01*
Y246535D01*
X583549Y246580D01*
X583554Y246625D01*
Y246665D01*
X583559Y246710D01*
X583569Y246750D01*
X583574Y246790D01*
X583589Y246835D01*
X583599Y246875D01*
X583614Y246915D01*
X583634Y246955D01*
X583649Y246990D01*
X583669Y247030D01*
X583769Y247170D01*
X583799Y247200D01*
Y249330D01*
X583809Y249455D01*
X583849Y249580D01*
X583909Y249690D01*
X583989Y249790D01*
X584089Y249870D01*
X584199Y249930D01*
X584324Y249970D01*
X584449Y249980D01*
G37*
G36*
G01X589173D02*
X589298Y249970D01*
X589423Y249930D01*
X589533Y249870D01*
X589633Y249790D01*
X589713Y249690D01*
X589773Y249580D01*
X589813Y249455D01*
X589823Y249330D01*
Y247205D01*
X589853Y247175D01*
X589878Y247140D01*
X589908Y247105D01*
X589928Y247070D01*
X589953Y247035D01*
X589993Y246955D01*
X590038Y246835D01*
X590048Y246795D01*
X590058Y246750D01*
X590063Y246710D01*
X590073Y246665D01*
Y246495D01*
X590063Y246450D01*
X590058Y246410D01*
X590048Y246365D01*
X590038Y246325D01*
X589993Y246205D01*
X589953Y246125D01*
X589928Y246090D01*
X589908Y246055D01*
X589878Y246020D01*
X589853Y245985D01*
X589823Y245955D01*
Y243530D01*
X589813Y243405D01*
X589773Y243280D01*
X589713Y243170D01*
X589633Y243070D01*
X589533Y242990D01*
X589423Y242930D01*
X589298Y242890D01*
X589173Y242880D01*
X589048Y242890D01*
X588923Y242930D01*
X588813Y242990D01*
X588713Y243070D01*
X588633Y243170D01*
X588573Y243280D01*
X588533Y243405D01*
X588523Y243530D01*
Y245960D01*
X588493Y245990D01*
X588393Y246130D01*
X588373Y246170D01*
X588358Y246205D01*
X588338Y246245D01*
X588323Y246285D01*
X588313Y246325D01*
X588298Y246370D01*
X588293Y246410D01*
X588283Y246450D01*
X588278Y246495D01*
Y246535D01*
X588273Y246580D01*
X588278Y246625D01*
Y246665D01*
X588283Y246710D01*
X588293Y246750D01*
X588298Y246790D01*
X588313Y246835D01*
X588323Y246875D01*
X588338Y246915D01*
X588358Y246955D01*
X588373Y246990D01*
X588393Y247030D01*
X588493Y247170D01*
X588523Y247200D01*
Y249330D01*
X588533Y249455D01*
X588573Y249580D01*
X588633Y249690D01*
X588713Y249790D01*
X588813Y249870D01*
X588923Y249930D01*
X589048Y249970D01*
X589173Y249980D01*
G37*
G36*
G01X593898D02*
X594023Y249970D01*
X594148Y249930D01*
X594258Y249870D01*
X594358Y249790D01*
X594438Y249690D01*
X594498Y249580D01*
X594538Y249455D01*
X594548Y249330D01*
Y247205D01*
X594578Y247175D01*
X594603Y247140D01*
X594633Y247105D01*
X594653Y247070D01*
X594678Y247035D01*
X594718Y246955D01*
X594763Y246835D01*
X594773Y246795D01*
X594783Y246750D01*
X594788Y246710D01*
X594798Y246665D01*
Y246495D01*
X594788Y246450D01*
X594783Y246410D01*
X594773Y246365D01*
X594763Y246325D01*
X594718Y246205D01*
X594678Y246125D01*
X594653Y246090D01*
X594633Y246055D01*
X594603Y246020D01*
X594578Y245985D01*
X594548Y245955D01*
Y243530D01*
X594538Y243405D01*
X594498Y243280D01*
X594438Y243170D01*
X594358Y243070D01*
X594258Y242990D01*
X594148Y242930D01*
X594023Y242890D01*
X593898Y242880D01*
X593773Y242890D01*
X593648Y242930D01*
X593538Y242990D01*
X593438Y243070D01*
X593358Y243170D01*
X593298Y243280D01*
X593258Y243405D01*
X593248Y243530D01*
Y245960D01*
X593218Y245990D01*
X593118Y246130D01*
X593098Y246170D01*
X593083Y246205D01*
X593063Y246245D01*
X593048Y246285D01*
X593038Y246325D01*
X593023Y246370D01*
X593018Y246410D01*
X593008Y246450D01*
X593003Y246495D01*
Y246535D01*
X592998Y246580D01*
X593003Y246625D01*
Y246665D01*
X593008Y246710D01*
X593018Y246750D01*
X593023Y246790D01*
X593038Y246835D01*
X593048Y246875D01*
X593063Y246915D01*
X593083Y246955D01*
X593098Y246990D01*
X593118Y247030D01*
X593218Y247170D01*
X593248Y247200D01*
Y249330D01*
X593258Y249455D01*
X593298Y249580D01*
X593358Y249690D01*
X593438Y249790D01*
X593538Y249870D01*
X593648Y249930D01*
X593773Y249970D01*
X593898Y249980D01*
G37*
G36*
G01X598622D02*
X598747Y249970D01*
X598872Y249930D01*
X598982Y249870D01*
X599082Y249790D01*
X599162Y249690D01*
X599222Y249580D01*
X599262Y249455D01*
X599272Y249330D01*
Y247205D01*
X599302Y247175D01*
X599327Y247140D01*
X599357Y247105D01*
X599377Y247070D01*
X599402Y247035D01*
X599442Y246955D01*
X599487Y246835D01*
X599497Y246795D01*
X599507Y246750D01*
X599512Y246710D01*
X599522Y246665D01*
Y246495D01*
X599512Y246450D01*
X599507Y246410D01*
X599497Y246365D01*
X599487Y246325D01*
X599442Y246205D01*
X599402Y246125D01*
X599377Y246090D01*
X599357Y246055D01*
X599327Y246020D01*
X599302Y245985D01*
X599272Y245955D01*
Y243530D01*
X599262Y243405D01*
X599222Y243280D01*
X599162Y243170D01*
X599082Y243070D01*
X598982Y242990D01*
X598872Y242930D01*
X598747Y242890D01*
X598622Y242880D01*
X598497Y242890D01*
X598372Y242930D01*
X598262Y242990D01*
X598162Y243070D01*
X598082Y243170D01*
X598022Y243280D01*
X597982Y243405D01*
X597972Y243530D01*
Y245960D01*
X597942Y245990D01*
X597842Y246130D01*
X597822Y246170D01*
X597807Y246205D01*
X597787Y246245D01*
X597772Y246285D01*
X597762Y246325D01*
X597747Y246370D01*
X597742Y246410D01*
X597732Y246450D01*
X597727Y246495D01*
Y246535D01*
X597722Y246580D01*
X597727Y246625D01*
Y246665D01*
X597732Y246710D01*
X597742Y246750D01*
X597747Y246790D01*
X597762Y246835D01*
X597772Y246875D01*
X597787Y246915D01*
X597807Y246955D01*
X597822Y246990D01*
X597842Y247030D01*
X597942Y247170D01*
X597972Y247200D01*
Y249330D01*
X597982Y249455D01*
X598022Y249580D01*
X598082Y249690D01*
X598162Y249790D01*
X598262Y249870D01*
X598372Y249930D01*
X598497Y249970D01*
X598622Y249980D01*
G37*
G36*
G01X603347D02*
X603472Y249970D01*
X603597Y249930D01*
X603707Y249870D01*
X603807Y249790D01*
X603887Y249690D01*
X603947Y249580D01*
X603987Y249455D01*
X603997Y249330D01*
Y247205D01*
X604027Y247175D01*
X604052Y247140D01*
X604082Y247105D01*
X604102Y247070D01*
X604127Y247035D01*
X604167Y246955D01*
X604212Y246835D01*
X604222Y246795D01*
X604232Y246750D01*
X604237Y246710D01*
X604247Y246665D01*
Y246495D01*
X604237Y246450D01*
X604232Y246410D01*
X604222Y246365D01*
X604212Y246325D01*
X604167Y246205D01*
X604127Y246125D01*
X604102Y246090D01*
X604082Y246055D01*
X604052Y246020D01*
X604027Y245985D01*
X603997Y245955D01*
Y243530D01*
X603987Y243405D01*
X603947Y243280D01*
X603887Y243170D01*
X603807Y243070D01*
X603707Y242990D01*
X603597Y242930D01*
X603472Y242890D01*
X603347Y242880D01*
X603222Y242890D01*
X603097Y242930D01*
X602987Y242990D01*
X602887Y243070D01*
X602807Y243170D01*
X602747Y243280D01*
X602707Y243405D01*
X602697Y243530D01*
Y245960D01*
X602667Y245990D01*
X602567Y246130D01*
X602547Y246170D01*
X602532Y246205D01*
X602512Y246245D01*
X602497Y246285D01*
X602487Y246325D01*
X602472Y246370D01*
X602467Y246410D01*
X602457Y246450D01*
X602452Y246495D01*
Y246535D01*
X602447Y246580D01*
X602452Y246625D01*
Y246665D01*
X602457Y246710D01*
X602467Y246750D01*
X602472Y246790D01*
X602487Y246835D01*
X602497Y246875D01*
X602512Y246915D01*
X602532Y246955D01*
X602547Y246990D01*
X602567Y247030D01*
X602667Y247170D01*
X602697Y247200D01*
Y249330D01*
X602707Y249455D01*
X602747Y249580D01*
X602807Y249690D01*
X602887Y249790D01*
X602987Y249870D01*
X603097Y249930D01*
X603222Y249970D01*
X603347Y249980D01*
G37*
G36*
G01X608071D02*
X608196Y249970D01*
X608321Y249930D01*
X608431Y249870D01*
X608531Y249790D01*
X608611Y249690D01*
X608671Y249580D01*
X608711Y249455D01*
X608721Y249330D01*
Y247205D01*
X608751Y247175D01*
X608776Y247140D01*
X608806Y247105D01*
X608826Y247070D01*
X608851Y247035D01*
X608891Y246955D01*
X608936Y246835D01*
X608946Y246795D01*
X608956Y246750D01*
X608961Y246710D01*
X608971Y246665D01*
Y246495D01*
X608961Y246450D01*
X608956Y246410D01*
X608946Y246365D01*
X608936Y246325D01*
X608891Y246205D01*
X608851Y246125D01*
X608826Y246090D01*
X608806Y246055D01*
X608776Y246020D01*
X608751Y245985D01*
X608721Y245955D01*
Y243530D01*
X608711Y243405D01*
X608671Y243280D01*
X608611Y243170D01*
X608531Y243070D01*
X608431Y242990D01*
X608321Y242930D01*
X608196Y242890D01*
X608071Y242880D01*
X607946Y242890D01*
X607821Y242930D01*
X607711Y242990D01*
X607611Y243070D01*
X607531Y243170D01*
X607471Y243280D01*
X607431Y243405D01*
X607421Y243530D01*
Y245960D01*
X607391Y245990D01*
X607291Y246130D01*
X607271Y246170D01*
X607256Y246205D01*
X607236Y246245D01*
X607221Y246285D01*
X607211Y246325D01*
X607196Y246370D01*
X607191Y246410D01*
X607181Y246450D01*
X607176Y246495D01*
Y246535D01*
X607171Y246580D01*
X607176Y246625D01*
Y246665D01*
X607181Y246710D01*
X607191Y246750D01*
X607196Y246790D01*
X607211Y246835D01*
X607221Y246875D01*
X607236Y246915D01*
X607256Y246955D01*
X607271Y246990D01*
X607291Y247030D01*
X607391Y247170D01*
X607421Y247200D01*
Y249330D01*
X607431Y249455D01*
X607471Y249580D01*
X607531Y249690D01*
X607611Y249790D01*
X607711Y249870D01*
X607821Y249930D01*
X607946Y249970D01*
X608071Y249980D01*
G37*
G36*
G01X612796D02*
X612921Y249970D01*
X613046Y249930D01*
X613156Y249870D01*
X613256Y249790D01*
X613336Y249690D01*
X613396Y249580D01*
X613436Y249455D01*
X613446Y249330D01*
Y247205D01*
X613476Y247175D01*
X613501Y247140D01*
X613531Y247105D01*
X613551Y247070D01*
X613576Y247035D01*
X613616Y246955D01*
X613661Y246835D01*
X613671Y246795D01*
X613681Y246750D01*
X613686Y246710D01*
X613696Y246665D01*
Y246495D01*
X613686Y246450D01*
X613681Y246410D01*
X613671Y246365D01*
X613661Y246325D01*
X613616Y246205D01*
X613576Y246125D01*
X613551Y246090D01*
X613531Y246055D01*
X613501Y246020D01*
X613476Y245985D01*
X613446Y245955D01*
Y243530D01*
X613436Y243405D01*
X613396Y243280D01*
X613336Y243170D01*
X613256Y243070D01*
X613156Y242990D01*
X613046Y242930D01*
X612921Y242890D01*
X612796Y242880D01*
X612671Y242890D01*
X612546Y242930D01*
X612436Y242990D01*
X612336Y243070D01*
X612256Y243170D01*
X612196Y243280D01*
X612156Y243405D01*
X612146Y243530D01*
Y245960D01*
X612116Y245990D01*
X612016Y246130D01*
X611996Y246170D01*
X611981Y246205D01*
X611961Y246245D01*
X611946Y246285D01*
X611936Y246325D01*
X611921Y246370D01*
X611916Y246410D01*
X611906Y246450D01*
X611901Y246495D01*
Y246535D01*
X611896Y246580D01*
X611901Y246625D01*
Y246665D01*
X611906Y246710D01*
X611916Y246750D01*
X611921Y246790D01*
X611936Y246835D01*
X611946Y246875D01*
X611961Y246915D01*
X611981Y246955D01*
X611996Y246990D01*
X612016Y247030D01*
X612116Y247170D01*
X612146Y247200D01*
Y249330D01*
X612156Y249455D01*
X612196Y249580D01*
X612256Y249690D01*
X612336Y249790D01*
X612436Y249870D01*
X612546Y249930D01*
X612671Y249970D01*
X612796Y249980D01*
G37*
G36*
G01X617520D02*
X617645Y249970D01*
X617770Y249930D01*
X617880Y249870D01*
X617980Y249790D01*
X618060Y249690D01*
X618120Y249580D01*
X618160Y249455D01*
X618170Y249330D01*
Y247205D01*
X618200Y247175D01*
X618225Y247140D01*
X618255Y247105D01*
X618275Y247070D01*
X618300Y247035D01*
X618340Y246955D01*
X618385Y246835D01*
X618395Y246795D01*
X618405Y246750D01*
X618410Y246710D01*
X618420Y246665D01*
Y246495D01*
X618410Y246450D01*
X618405Y246410D01*
X618395Y246365D01*
X618385Y246325D01*
X618340Y246205D01*
X618300Y246125D01*
X618275Y246090D01*
X618255Y246055D01*
X618225Y246020D01*
X618200Y245985D01*
X618170Y245955D01*
Y243530D01*
X618160Y243405D01*
X618120Y243280D01*
X618060Y243170D01*
X617980Y243070D01*
X617880Y242990D01*
X617770Y242930D01*
X617645Y242890D01*
X617520Y242880D01*
X617395Y242890D01*
X617270Y242930D01*
X617160Y242990D01*
X617060Y243070D01*
X616980Y243170D01*
X616920Y243280D01*
X616880Y243405D01*
X616870Y243530D01*
Y245960D01*
X616840Y245990D01*
X616740Y246130D01*
X616720Y246170D01*
X616705Y246205D01*
X616685Y246245D01*
X616670Y246285D01*
X616660Y246325D01*
X616645Y246370D01*
X616640Y246410D01*
X616630Y246450D01*
X616625Y246495D01*
Y246535D01*
X616620Y246580D01*
X616625Y246625D01*
Y246665D01*
X616630Y246710D01*
X616640Y246750D01*
X616645Y246790D01*
X616660Y246835D01*
X616670Y246875D01*
X616685Y246915D01*
X616705Y246955D01*
X616720Y246990D01*
X616740Y247030D01*
X616840Y247170D01*
X616870Y247200D01*
Y249330D01*
X616880Y249455D01*
X616920Y249580D01*
X616980Y249690D01*
X617060Y249790D01*
X617160Y249870D01*
X617270Y249930D01*
X617395Y249970D01*
X617520Y249980D01*
G37*
G36*
G01X622244D02*
X622369Y249970D01*
X622494Y249930D01*
X622604Y249870D01*
X622704Y249790D01*
X622784Y249690D01*
X622844Y249580D01*
X622884Y249455D01*
X622894Y249330D01*
Y247205D01*
X622924Y247175D01*
X622949Y247140D01*
X622979Y247105D01*
X622999Y247070D01*
X623024Y247035D01*
X623064Y246955D01*
X623109Y246835D01*
X623119Y246795D01*
X623129Y246750D01*
X623134Y246710D01*
X623144Y246665D01*
Y246495D01*
X623134Y246450D01*
X623129Y246410D01*
X623119Y246365D01*
X623109Y246325D01*
X623064Y246205D01*
X623024Y246125D01*
X622999Y246090D01*
X622979Y246055D01*
X622949Y246020D01*
X622924Y245985D01*
X622894Y245955D01*
Y243530D01*
X622884Y243405D01*
X622844Y243280D01*
X622784Y243170D01*
X622704Y243070D01*
X622604Y242990D01*
X622494Y242930D01*
X622369Y242890D01*
X622244Y242880D01*
X622119Y242890D01*
X621994Y242930D01*
X621884Y242990D01*
X621784Y243070D01*
X621704Y243170D01*
X621644Y243280D01*
X621604Y243405D01*
X621594Y243530D01*
Y245960D01*
X621564Y245990D01*
X621464Y246130D01*
X621444Y246170D01*
X621429Y246205D01*
X621409Y246245D01*
X621394Y246285D01*
X621384Y246325D01*
X621369Y246370D01*
X621364Y246410D01*
X621354Y246450D01*
X621349Y246495D01*
Y246535D01*
X621344Y246580D01*
X621349Y246625D01*
Y246665D01*
X621354Y246710D01*
X621364Y246750D01*
X621369Y246790D01*
X621384Y246835D01*
X621394Y246875D01*
X621409Y246915D01*
X621429Y246955D01*
X621444Y246990D01*
X621464Y247030D01*
X621564Y247170D01*
X621594Y247200D01*
Y249330D01*
X621604Y249455D01*
X621644Y249580D01*
X621704Y249690D01*
X621784Y249790D01*
X621884Y249870D01*
X621994Y249930D01*
X622119Y249970D01*
X622244Y249980D01*
G37*
G36*
G01X626969D02*
X627094Y249970D01*
X627219Y249930D01*
X627329Y249870D01*
X627429Y249790D01*
X627509Y249690D01*
X627569Y249580D01*
X627609Y249455D01*
X627619Y249330D01*
Y247205D01*
X627649Y247175D01*
X627674Y247140D01*
X627704Y247105D01*
X627724Y247070D01*
X627749Y247035D01*
X627789Y246955D01*
X627834Y246835D01*
X627844Y246795D01*
X627854Y246750D01*
X627859Y246710D01*
X627869Y246665D01*
Y246495D01*
X627859Y246450D01*
X627854Y246410D01*
X627844Y246365D01*
X627834Y246325D01*
X627789Y246205D01*
X627749Y246125D01*
X627724Y246090D01*
X627704Y246055D01*
X627674Y246020D01*
X627649Y245985D01*
X627619Y245955D01*
Y243530D01*
X627609Y243405D01*
X627569Y243280D01*
X627509Y243170D01*
X627429Y243070D01*
X627329Y242990D01*
X627219Y242930D01*
X627094Y242890D01*
X626969Y242880D01*
X626844Y242890D01*
X626719Y242930D01*
X626609Y242990D01*
X626509Y243070D01*
X626429Y243170D01*
X626369Y243280D01*
X626329Y243405D01*
X626319Y243530D01*
Y245960D01*
X626289Y245990D01*
X626189Y246130D01*
X626169Y246170D01*
X626154Y246205D01*
X626134Y246245D01*
X626119Y246285D01*
X626109Y246325D01*
X626094Y246370D01*
X626089Y246410D01*
X626079Y246450D01*
X626074Y246495D01*
Y246535D01*
X626069Y246580D01*
X626074Y246625D01*
Y246665D01*
X626079Y246710D01*
X626089Y246750D01*
X626094Y246790D01*
X626109Y246835D01*
X626119Y246875D01*
X626134Y246915D01*
X626154Y246955D01*
X626169Y246990D01*
X626189Y247030D01*
X626289Y247170D01*
X626319Y247200D01*
Y249330D01*
X626329Y249455D01*
X626369Y249580D01*
X626429Y249690D01*
X626509Y249790D01*
X626609Y249870D01*
X626719Y249930D01*
X626844Y249970D01*
X626969Y249980D01*
G37*
G36*
G01X631693D02*
X631818Y249970D01*
X631943Y249930D01*
X632053Y249870D01*
X632153Y249790D01*
X632233Y249690D01*
X632293Y249580D01*
X632333Y249455D01*
X632343Y249330D01*
Y247205D01*
X632373Y247175D01*
X632398Y247140D01*
X632428Y247105D01*
X632448Y247070D01*
X632473Y247035D01*
X632513Y246955D01*
X632558Y246835D01*
X632568Y246795D01*
X632578Y246750D01*
X632583Y246710D01*
X632593Y246665D01*
Y246495D01*
X632583Y246450D01*
X632578Y246410D01*
X632568Y246365D01*
X632558Y246325D01*
X632513Y246205D01*
X632473Y246125D01*
X632448Y246090D01*
X632428Y246055D01*
X632398Y246020D01*
X632373Y245985D01*
X632343Y245955D01*
Y243530D01*
X632333Y243405D01*
X632293Y243280D01*
X632233Y243170D01*
X632153Y243070D01*
X632053Y242990D01*
X631943Y242930D01*
X631818Y242890D01*
X631693Y242880D01*
X631568Y242890D01*
X631443Y242930D01*
X631333Y242990D01*
X631233Y243070D01*
X631153Y243170D01*
X631093Y243280D01*
X631053Y243405D01*
X631043Y243530D01*
Y245960D01*
X631013Y245990D01*
X630913Y246130D01*
X630893Y246170D01*
X630878Y246205D01*
X630858Y246245D01*
X630843Y246285D01*
X630833Y246325D01*
X630818Y246370D01*
X630813Y246410D01*
X630803Y246450D01*
X630798Y246495D01*
Y246535D01*
X630793Y246580D01*
X630798Y246625D01*
Y246665D01*
X630803Y246710D01*
X630813Y246750D01*
X630818Y246790D01*
X630833Y246835D01*
X630843Y246875D01*
X630858Y246915D01*
X630878Y246955D01*
X630893Y246990D01*
X630913Y247030D01*
X631013Y247170D01*
X631043Y247200D01*
Y249330D01*
X631053Y249455D01*
X631093Y249580D01*
X631153Y249690D01*
X631233Y249790D01*
X631333Y249870D01*
X631443Y249930D01*
X631568Y249970D01*
X631693Y249980D01*
G37*
G36*
G01X636418D02*
X636543Y249970D01*
X636668Y249930D01*
X636778Y249870D01*
X636878Y249790D01*
X636958Y249690D01*
X637018Y249580D01*
X637058Y249455D01*
X637068Y249330D01*
Y247205D01*
X637098Y247175D01*
X637123Y247140D01*
X637153Y247105D01*
X637173Y247070D01*
X637198Y247035D01*
X637238Y246955D01*
X637283Y246835D01*
X637293Y246795D01*
X637303Y246750D01*
X637308Y246710D01*
X637318Y246665D01*
Y246495D01*
X637308Y246450D01*
X637303Y246410D01*
X637293Y246365D01*
X637283Y246325D01*
X637238Y246205D01*
X637198Y246125D01*
X637173Y246090D01*
X637153Y246055D01*
X637123Y246020D01*
X637098Y245985D01*
X637068Y245955D01*
Y243530D01*
X637058Y243405D01*
X637018Y243280D01*
X636958Y243170D01*
X636878Y243070D01*
X636778Y242990D01*
X636668Y242930D01*
X636543Y242890D01*
X636418Y242880D01*
X636293Y242890D01*
X636168Y242930D01*
X636058Y242990D01*
X635958Y243070D01*
X635878Y243170D01*
X635818Y243280D01*
X635778Y243405D01*
X635768Y243530D01*
Y245960D01*
X635738Y245990D01*
X635638Y246130D01*
X635618Y246170D01*
X635603Y246205D01*
X635583Y246245D01*
X635568Y246285D01*
X635558Y246325D01*
X635543Y246370D01*
X635538Y246410D01*
X635528Y246450D01*
X635523Y246495D01*
Y246535D01*
X635518Y246580D01*
X635523Y246625D01*
Y246665D01*
X635528Y246710D01*
X635538Y246750D01*
X635543Y246790D01*
X635558Y246835D01*
X635568Y246875D01*
X635583Y246915D01*
X635603Y246955D01*
X635618Y246990D01*
X635638Y247030D01*
X635738Y247170D01*
X635768Y247200D01*
Y249330D01*
X635778Y249455D01*
X635818Y249580D01*
X635878Y249690D01*
X635958Y249790D01*
X636058Y249870D01*
X636168Y249930D01*
X636293Y249970D01*
X636418Y249980D01*
G37*
G36*
G01X641142D02*
X641267Y249970D01*
X641392Y249930D01*
X641502Y249870D01*
X641602Y249790D01*
X641682Y249690D01*
X641742Y249580D01*
X641782Y249455D01*
X641792Y249330D01*
Y247205D01*
X641822Y247175D01*
X641847Y247140D01*
X641877Y247105D01*
X641897Y247070D01*
X641922Y247035D01*
X641962Y246955D01*
X642007Y246835D01*
X642017Y246795D01*
X642027Y246750D01*
X642032Y246710D01*
X642042Y246665D01*
Y246495D01*
X642032Y246450D01*
X642027Y246410D01*
X642017Y246365D01*
X642007Y246325D01*
X641962Y246205D01*
X641922Y246125D01*
X641897Y246090D01*
X641877Y246055D01*
X641847Y246020D01*
X641822Y245985D01*
X641792Y245955D01*
Y243530D01*
X641782Y243405D01*
X641742Y243280D01*
X641682Y243170D01*
X641602Y243070D01*
X641502Y242990D01*
X641392Y242930D01*
X641267Y242890D01*
X641142Y242880D01*
X641017Y242890D01*
X640892Y242930D01*
X640782Y242990D01*
X640682Y243070D01*
X640602Y243170D01*
X640542Y243280D01*
X640502Y243405D01*
X640492Y243530D01*
Y245960D01*
X640462Y245990D01*
X640362Y246130D01*
X640342Y246170D01*
X640327Y246205D01*
X640307Y246245D01*
X640292Y246285D01*
X640282Y246325D01*
X640267Y246370D01*
X640262Y246410D01*
X640252Y246450D01*
X640247Y246495D01*
Y246535D01*
X640242Y246580D01*
X640247Y246625D01*
Y246665D01*
X640252Y246710D01*
X640262Y246750D01*
X640267Y246790D01*
X640282Y246835D01*
X640292Y246875D01*
X640307Y246915D01*
X640327Y246955D01*
X640342Y246990D01*
X640362Y247030D01*
X640462Y247170D01*
X640492Y247200D01*
Y249330D01*
X640502Y249455D01*
X640542Y249580D01*
X640602Y249690D01*
X640682Y249790D01*
X640782Y249870D01*
X640892Y249930D01*
X641017Y249970D01*
X641142Y249980D01*
G37*
G36*
G01X645866D02*
X645991Y249970D01*
X646116Y249930D01*
X646226Y249870D01*
X646326Y249790D01*
X646406Y249690D01*
X646466Y249580D01*
X646506Y249455D01*
X646516Y249330D01*
Y247205D01*
X646546Y247175D01*
X646571Y247140D01*
X646601Y247105D01*
X646621Y247070D01*
X646646Y247035D01*
X646686Y246955D01*
X646731Y246835D01*
X646741Y246795D01*
X646751Y246750D01*
X646756Y246710D01*
X646766Y246665D01*
Y246495D01*
X646756Y246450D01*
X646751Y246410D01*
X646741Y246365D01*
X646731Y246325D01*
X646686Y246205D01*
X646646Y246125D01*
X646621Y246090D01*
X646601Y246055D01*
X646571Y246020D01*
X646546Y245985D01*
X646516Y245955D01*
Y243530D01*
X646506Y243405D01*
X646466Y243280D01*
X646406Y243170D01*
X646326Y243070D01*
X646226Y242990D01*
X646116Y242930D01*
X645991Y242890D01*
X645866Y242880D01*
X645741Y242890D01*
X645616Y242930D01*
X645506Y242990D01*
X645406Y243070D01*
X645326Y243170D01*
X645266Y243280D01*
X645226Y243405D01*
X645216Y243530D01*
Y245960D01*
X645186Y245990D01*
X645086Y246130D01*
X645066Y246170D01*
X645051Y246205D01*
X645031Y246245D01*
X645016Y246285D01*
X645006Y246325D01*
X644991Y246370D01*
X644986Y246410D01*
X644976Y246450D01*
X644971Y246495D01*
Y246535D01*
X644966Y246580D01*
X644971Y246625D01*
Y246665D01*
X644976Y246710D01*
X644986Y246750D01*
X644991Y246790D01*
X645006Y246835D01*
X645016Y246875D01*
X645031Y246915D01*
X645051Y246955D01*
X645066Y246990D01*
X645086Y247030D01*
X645186Y247170D01*
X645216Y247200D01*
Y249330D01*
X645226Y249455D01*
X645266Y249580D01*
X645326Y249690D01*
X645406Y249790D01*
X645506Y249870D01*
X645616Y249930D01*
X645741Y249970D01*
X645866Y249980D01*
G37*
G36*
G01X650591D02*
X650716Y249970D01*
X650841Y249930D01*
X650951Y249870D01*
X651051Y249790D01*
X651131Y249690D01*
X651191Y249580D01*
X651231Y249455D01*
X651241Y249330D01*
Y247205D01*
X651271Y247175D01*
X651296Y247140D01*
X651326Y247105D01*
X651346Y247070D01*
X651371Y247035D01*
X651411Y246955D01*
X651456Y246835D01*
X651466Y246795D01*
X651476Y246750D01*
X651481Y246710D01*
X651491Y246665D01*
Y246495D01*
X651481Y246450D01*
X651476Y246410D01*
X651466Y246365D01*
X651456Y246325D01*
X651411Y246205D01*
X651371Y246125D01*
X651346Y246090D01*
X651326Y246055D01*
X651296Y246020D01*
X651271Y245985D01*
X651241Y245955D01*
Y243530D01*
X651231Y243405D01*
X651191Y243280D01*
X651131Y243170D01*
X651051Y243070D01*
X650951Y242990D01*
X650841Y242930D01*
X650716Y242890D01*
X650591Y242880D01*
X650466Y242890D01*
X650341Y242930D01*
X650231Y242990D01*
X650131Y243070D01*
X650051Y243170D01*
X649991Y243280D01*
X649951Y243405D01*
X649941Y243530D01*
Y245960D01*
X649911Y245990D01*
X649811Y246130D01*
X649791Y246170D01*
X649776Y246205D01*
X649756Y246245D01*
X649741Y246285D01*
X649731Y246325D01*
X649716Y246370D01*
X649711Y246410D01*
X649701Y246450D01*
X649696Y246495D01*
Y246535D01*
X649691Y246580D01*
X649696Y246625D01*
Y246665D01*
X649701Y246710D01*
X649711Y246750D01*
X649716Y246790D01*
X649731Y246835D01*
X649741Y246875D01*
X649756Y246915D01*
X649776Y246955D01*
X649791Y246990D01*
X649811Y247030D01*
X649911Y247170D01*
X649941Y247200D01*
Y249330D01*
X649951Y249455D01*
X649991Y249580D01*
X650051Y249690D01*
X650131Y249790D01*
X650231Y249870D01*
X650341Y249930D01*
X650466Y249970D01*
X650591Y249980D01*
G37*
G36*
G01X664764D02*
X664889Y249970D01*
X665014Y249930D01*
X665124Y249870D01*
X665224Y249790D01*
X665304Y249690D01*
X665364Y249580D01*
X665404Y249455D01*
X665414Y249330D01*
Y247205D01*
X665444Y247175D01*
X665469Y247140D01*
X665499Y247105D01*
X665519Y247070D01*
X665544Y247035D01*
X665584Y246955D01*
X665629Y246835D01*
X665639Y246795D01*
X665649Y246750D01*
X665654Y246710D01*
X665664Y246665D01*
Y246495D01*
X665654Y246450D01*
X665649Y246410D01*
X665639Y246365D01*
X665629Y246325D01*
X665584Y246205D01*
X665544Y246125D01*
X665519Y246090D01*
X665499Y246055D01*
X665469Y246020D01*
X665444Y245985D01*
X665414Y245955D01*
Y243530D01*
X665404Y243405D01*
X665364Y243280D01*
X665304Y243170D01*
X665224Y243070D01*
X665124Y242990D01*
X665014Y242930D01*
X664889Y242890D01*
X664764Y242880D01*
X664639Y242890D01*
X664514Y242930D01*
X664404Y242990D01*
X664304Y243070D01*
X664224Y243170D01*
X664164Y243280D01*
X664124Y243405D01*
X664114Y243530D01*
Y245960D01*
X664084Y245990D01*
X663984Y246130D01*
X663964Y246170D01*
X663949Y246205D01*
X663929Y246245D01*
X663914Y246285D01*
X663904Y246325D01*
X663889Y246370D01*
X663884Y246410D01*
X663874Y246450D01*
X663869Y246495D01*
Y246535D01*
X663864Y246580D01*
X663869Y246625D01*
Y246665D01*
X663874Y246710D01*
X663884Y246750D01*
X663889Y246790D01*
X663904Y246835D01*
X663914Y246875D01*
X663929Y246915D01*
X663949Y246955D01*
X663964Y246990D01*
X663984Y247030D01*
X664084Y247170D01*
X664114Y247200D01*
Y249330D01*
X664124Y249455D01*
X664164Y249580D01*
X664224Y249690D01*
X664304Y249790D01*
X664404Y249870D01*
X664514Y249930D01*
X664639Y249970D01*
X664764Y249980D01*
G37*
G36*
G01X669488D02*
X669613Y249970D01*
X669738Y249930D01*
X669848Y249870D01*
X669948Y249790D01*
X670028Y249690D01*
X670088Y249580D01*
X670128Y249455D01*
X670138Y249330D01*
Y247205D01*
X670168Y247175D01*
X670193Y247140D01*
X670223Y247105D01*
X670243Y247070D01*
X670268Y247035D01*
X670308Y246955D01*
X670353Y246835D01*
X670363Y246795D01*
X670373Y246750D01*
X670378Y246710D01*
X670388Y246665D01*
Y246495D01*
X670378Y246450D01*
X670373Y246410D01*
X670363Y246365D01*
X670353Y246325D01*
X670308Y246205D01*
X670268Y246125D01*
X670243Y246090D01*
X670223Y246055D01*
X670193Y246020D01*
X670168Y245985D01*
X670138Y245955D01*
Y243530D01*
X670128Y243405D01*
X670088Y243280D01*
X670028Y243170D01*
X669948Y243070D01*
X669848Y242990D01*
X669738Y242930D01*
X669613Y242890D01*
X669488Y242880D01*
X669363Y242890D01*
X669238Y242930D01*
X669128Y242990D01*
X669028Y243070D01*
X668948Y243170D01*
X668888Y243280D01*
X668848Y243405D01*
X668838Y243530D01*
Y245960D01*
X668808Y245990D01*
X668708Y246130D01*
X668688Y246170D01*
X668673Y246205D01*
X668653Y246245D01*
X668638Y246285D01*
X668628Y246325D01*
X668613Y246370D01*
X668608Y246410D01*
X668598Y246450D01*
X668593Y246495D01*
Y246535D01*
X668588Y246580D01*
X668593Y246625D01*
Y246665D01*
X668598Y246710D01*
X668608Y246750D01*
X668613Y246790D01*
X668628Y246835D01*
X668638Y246875D01*
X668653Y246915D01*
X668673Y246955D01*
X668688Y246990D01*
X668708Y247030D01*
X668808Y247170D01*
X668838Y247200D01*
Y249330D01*
X668848Y249455D01*
X668888Y249580D01*
X668948Y249690D01*
X669028Y249790D01*
X669128Y249870D01*
X669238Y249930D01*
X669363Y249970D01*
X669488Y249980D01*
G37*
G36*
G01X674213D02*
X674338Y249970D01*
X674463Y249930D01*
X674573Y249870D01*
X674673Y249790D01*
X674753Y249690D01*
X674813Y249580D01*
X674853Y249455D01*
X674863Y249330D01*
Y247205D01*
X674893Y247175D01*
X674918Y247140D01*
X674948Y247105D01*
X674968Y247070D01*
X674993Y247035D01*
X675033Y246955D01*
X675078Y246835D01*
X675088Y246795D01*
X675098Y246750D01*
X675103Y246710D01*
X675113Y246665D01*
Y246495D01*
X675103Y246450D01*
X675098Y246410D01*
X675088Y246365D01*
X675078Y246325D01*
X675033Y246205D01*
X674993Y246125D01*
X674968Y246090D01*
X674948Y246055D01*
X674918Y246020D01*
X674893Y245985D01*
X674863Y245955D01*
Y243530D01*
X674853Y243405D01*
X674813Y243280D01*
X674753Y243170D01*
X674673Y243070D01*
X674573Y242990D01*
X674463Y242930D01*
X674338Y242890D01*
X674213Y242880D01*
X674088Y242890D01*
X673963Y242930D01*
X673853Y242990D01*
X673753Y243070D01*
X673673Y243170D01*
X673613Y243280D01*
X673573Y243405D01*
X673563Y243530D01*
Y245960D01*
X673533Y245990D01*
X673433Y246130D01*
X673413Y246170D01*
X673398Y246205D01*
X673378Y246245D01*
X673363Y246285D01*
X673353Y246325D01*
X673338Y246370D01*
X673333Y246410D01*
X673323Y246450D01*
X673318Y246495D01*
Y246535D01*
X673313Y246580D01*
X673318Y246625D01*
Y246665D01*
X673323Y246710D01*
X673333Y246750D01*
X673338Y246790D01*
X673353Y246835D01*
X673363Y246875D01*
X673378Y246915D01*
X673398Y246955D01*
X673413Y246990D01*
X673433Y247030D01*
X673533Y247170D01*
X673563Y247200D01*
Y249330D01*
X673573Y249455D01*
X673613Y249580D01*
X673673Y249690D01*
X673753Y249790D01*
X673853Y249870D01*
X673963Y249930D01*
X674088Y249970D01*
X674213Y249980D01*
G37*
G36*
G01X678937D02*
X679062Y249970D01*
X679187Y249930D01*
X679297Y249870D01*
X679397Y249790D01*
X679477Y249690D01*
X679537Y249580D01*
X679577Y249455D01*
X679587Y249330D01*
Y247205D01*
X679617Y247175D01*
X679642Y247140D01*
X679672Y247105D01*
X679692Y247070D01*
X679717Y247035D01*
X679757Y246955D01*
X679802Y246835D01*
X679812Y246795D01*
X679822Y246750D01*
X679827Y246710D01*
X679837Y246665D01*
Y246495D01*
X679827Y246450D01*
X679822Y246410D01*
X679812Y246365D01*
X679802Y246325D01*
X679757Y246205D01*
X679717Y246125D01*
X679692Y246090D01*
X679672Y246055D01*
X679642Y246020D01*
X679617Y245985D01*
X679587Y245955D01*
Y243530D01*
X679577Y243405D01*
X679537Y243280D01*
X679477Y243170D01*
X679397Y243070D01*
X679297Y242990D01*
X679187Y242930D01*
X679062Y242890D01*
X678937Y242880D01*
X678812Y242890D01*
X678687Y242930D01*
X678577Y242990D01*
X678477Y243070D01*
X678397Y243170D01*
X678337Y243280D01*
X678297Y243405D01*
X678287Y243530D01*
Y245960D01*
X678257Y245990D01*
X678157Y246130D01*
X678137Y246170D01*
X678122Y246205D01*
X678102Y246245D01*
X678087Y246285D01*
X678077Y246325D01*
X678062Y246370D01*
X678057Y246410D01*
X678047Y246450D01*
X678042Y246495D01*
Y246535D01*
X678037Y246580D01*
X678042Y246625D01*
Y246665D01*
X678047Y246710D01*
X678057Y246750D01*
X678062Y246790D01*
X678077Y246835D01*
X678087Y246875D01*
X678102Y246915D01*
X678122Y246955D01*
X678137Y246990D01*
X678157Y247030D01*
X678257Y247170D01*
X678287Y247200D01*
Y249330D01*
X678297Y249455D01*
X678337Y249580D01*
X678397Y249690D01*
X678477Y249790D01*
X678577Y249870D01*
X678687Y249930D01*
X678812Y249970D01*
X678937Y249980D01*
G37*
G36*
G01X683662D02*
X683787Y249970D01*
X683912Y249930D01*
X684022Y249870D01*
X684122Y249790D01*
X684202Y249690D01*
X684262Y249580D01*
X684302Y249455D01*
X684312Y249330D01*
Y247205D01*
X684342Y247175D01*
X684367Y247140D01*
X684397Y247105D01*
X684417Y247070D01*
X684442Y247035D01*
X684482Y246955D01*
X684527Y246835D01*
X684537Y246795D01*
X684547Y246750D01*
X684552Y246710D01*
X684562Y246665D01*
Y246495D01*
X684552Y246450D01*
X684547Y246410D01*
X684537Y246365D01*
X684527Y246325D01*
X684482Y246205D01*
X684442Y246125D01*
X684417Y246090D01*
X684397Y246055D01*
X684367Y246020D01*
X684342Y245985D01*
X684312Y245955D01*
Y243530D01*
X684302Y243405D01*
X684262Y243280D01*
X684202Y243170D01*
X684122Y243070D01*
X684022Y242990D01*
X683912Y242930D01*
X683787Y242890D01*
X683662Y242880D01*
X683537Y242890D01*
X683412Y242930D01*
X683302Y242990D01*
X683202Y243070D01*
X683122Y243170D01*
X683062Y243280D01*
X683022Y243405D01*
X683012Y243530D01*
Y245960D01*
X682982Y245990D01*
X682882Y246130D01*
X682862Y246170D01*
X682847Y246205D01*
X682827Y246245D01*
X682812Y246285D01*
X682802Y246325D01*
X682787Y246370D01*
X682782Y246410D01*
X682772Y246450D01*
X682767Y246495D01*
Y246535D01*
X682762Y246580D01*
X682767Y246625D01*
Y246665D01*
X682772Y246710D01*
X682782Y246750D01*
X682787Y246790D01*
X682802Y246835D01*
X682812Y246875D01*
X682827Y246915D01*
X682847Y246955D01*
X682862Y246990D01*
X682882Y247030D01*
X682982Y247170D01*
X683012Y247200D01*
Y249330D01*
X683022Y249455D01*
X683062Y249580D01*
X683122Y249690D01*
X683202Y249790D01*
X683302Y249870D01*
X683412Y249930D01*
X683537Y249970D01*
X683662Y249980D01*
G37*
G36*
G01X688386D02*
X688511Y249970D01*
X688636Y249930D01*
X688746Y249870D01*
X688846Y249790D01*
X688926Y249690D01*
X688986Y249580D01*
X689026Y249455D01*
X689036Y249330D01*
Y247205D01*
X689066Y247175D01*
X689091Y247140D01*
X689121Y247105D01*
X689141Y247070D01*
X689166Y247035D01*
X689206Y246955D01*
X689251Y246835D01*
X689261Y246795D01*
X689271Y246750D01*
X689276Y246710D01*
X689286Y246665D01*
Y246495D01*
X689276Y246450D01*
X689271Y246410D01*
X689261Y246365D01*
X689251Y246325D01*
X689206Y246205D01*
X689166Y246125D01*
X689141Y246090D01*
X689121Y246055D01*
X689091Y246020D01*
X689066Y245985D01*
X689036Y245955D01*
Y243530D01*
X689026Y243405D01*
X688986Y243280D01*
X688926Y243170D01*
X688846Y243070D01*
X688746Y242990D01*
X688636Y242930D01*
X688511Y242890D01*
X688386Y242880D01*
X688261Y242890D01*
X688136Y242930D01*
X688026Y242990D01*
X687926Y243070D01*
X687846Y243170D01*
X687786Y243280D01*
X687746Y243405D01*
X687736Y243530D01*
Y245960D01*
X687706Y245990D01*
X687606Y246130D01*
X687586Y246170D01*
X687571Y246205D01*
X687551Y246245D01*
X687536Y246285D01*
X687526Y246325D01*
X687511Y246370D01*
X687506Y246410D01*
X687496Y246450D01*
X687491Y246495D01*
Y246535D01*
X687486Y246580D01*
X687491Y246625D01*
Y246665D01*
X687496Y246710D01*
X687506Y246750D01*
X687511Y246790D01*
X687526Y246835D01*
X687536Y246875D01*
X687551Y246915D01*
X687571Y246955D01*
X687586Y246990D01*
X687606Y247030D01*
X687706Y247170D01*
X687736Y247200D01*
Y249330D01*
X687746Y249455D01*
X687786Y249580D01*
X687846Y249690D01*
X687926Y249790D01*
X688026Y249870D01*
X688136Y249930D01*
X688261Y249970D01*
X688386Y249980D01*
G37*
G36*
G01X693110D02*
X693235Y249970D01*
X693360Y249930D01*
X693470Y249870D01*
X693570Y249790D01*
X693650Y249690D01*
X693710Y249580D01*
X693750Y249455D01*
X693760Y249330D01*
Y247205D01*
X693790Y247175D01*
X693815Y247140D01*
X693845Y247105D01*
X693865Y247070D01*
X693890Y247035D01*
X693930Y246955D01*
X693975Y246835D01*
X693985Y246795D01*
X693995Y246750D01*
X694000Y246710D01*
X694010Y246665D01*
Y246495D01*
X694000Y246450D01*
X693995Y246410D01*
X693985Y246365D01*
X693975Y246325D01*
X693930Y246205D01*
X693890Y246125D01*
X693865Y246090D01*
X693845Y246055D01*
X693815Y246020D01*
X693790Y245985D01*
X693760Y245955D01*
Y243530D01*
X693750Y243405D01*
X693710Y243280D01*
X693650Y243170D01*
X693570Y243070D01*
X693470Y242990D01*
X693360Y242930D01*
X693235Y242890D01*
X693110Y242880D01*
X692985Y242890D01*
X692860Y242930D01*
X692750Y242990D01*
X692650Y243070D01*
X692570Y243170D01*
X692510Y243280D01*
X692470Y243405D01*
X692460Y243530D01*
Y245960D01*
X692430Y245990D01*
X692330Y246130D01*
X692310Y246170D01*
X692295Y246205D01*
X692275Y246245D01*
X692260Y246285D01*
X692250Y246325D01*
X692235Y246370D01*
X692230Y246410D01*
X692220Y246450D01*
X692215Y246495D01*
Y246535D01*
X692210Y246580D01*
X692215Y246625D01*
Y246665D01*
X692220Y246710D01*
X692230Y246750D01*
X692235Y246790D01*
X692250Y246835D01*
X692260Y246875D01*
X692275Y246915D01*
X692295Y246955D01*
X692310Y246990D01*
X692330Y247030D01*
X692430Y247170D01*
X692460Y247200D01*
Y249330D01*
X692470Y249455D01*
X692510Y249580D01*
X692570Y249690D01*
X692650Y249790D01*
X692750Y249870D01*
X692860Y249930D01*
X692985Y249970D01*
X693110Y249980D01*
G37*
G36*
G01X697835D02*
X697960Y249970D01*
X698085Y249930D01*
X698195Y249870D01*
X698295Y249790D01*
X698375Y249690D01*
X698435Y249580D01*
X698475Y249455D01*
X698485Y249330D01*
Y247205D01*
X698515Y247175D01*
X698540Y247140D01*
X698570Y247105D01*
X698590Y247070D01*
X698615Y247035D01*
X698655Y246955D01*
X698700Y246835D01*
X698710Y246795D01*
X698720Y246750D01*
X698725Y246710D01*
X698735Y246665D01*
Y246495D01*
X698725Y246450D01*
X698720Y246410D01*
X698710Y246365D01*
X698700Y246325D01*
X698655Y246205D01*
X698615Y246125D01*
X698590Y246090D01*
X698570Y246055D01*
X698540Y246020D01*
X698515Y245985D01*
X698485Y245955D01*
Y243530D01*
X698475Y243405D01*
X698435Y243280D01*
X698375Y243170D01*
X698295Y243070D01*
X698195Y242990D01*
X698085Y242930D01*
X697960Y242890D01*
X697835Y242880D01*
X697710Y242890D01*
X697585Y242930D01*
X697475Y242990D01*
X697375Y243070D01*
X697295Y243170D01*
X697235Y243280D01*
X697195Y243405D01*
X697185Y243530D01*
Y245960D01*
X697155Y245990D01*
X697055Y246130D01*
X697035Y246170D01*
X697020Y246205D01*
X697000Y246245D01*
X696985Y246285D01*
X696975Y246325D01*
X696960Y246370D01*
X696955Y246410D01*
X696945Y246450D01*
X696940Y246495D01*
Y246535D01*
X696935Y246580D01*
X696940Y246625D01*
Y246665D01*
X696945Y246710D01*
X696955Y246750D01*
X696960Y246790D01*
X696975Y246835D01*
X696985Y246875D01*
X697000Y246915D01*
X697020Y246955D01*
X697035Y246990D01*
X697055Y247030D01*
X697155Y247170D01*
X697185Y247200D01*
Y249330D01*
X697195Y249455D01*
X697235Y249580D01*
X697295Y249690D01*
X697375Y249790D01*
X697475Y249870D01*
X697585Y249930D01*
X697710Y249970D01*
X697835Y249980D01*
G37*
G36*
G01X702559D02*
X702684Y249970D01*
X702809Y249930D01*
X702919Y249870D01*
X703019Y249790D01*
X703099Y249690D01*
X703159Y249580D01*
X703199Y249455D01*
X703209Y249330D01*
Y247205D01*
X703239Y247175D01*
X703264Y247140D01*
X703294Y247105D01*
X703314Y247070D01*
X703339Y247035D01*
X703379Y246955D01*
X703424Y246835D01*
X703434Y246795D01*
X703444Y246750D01*
X703449Y246710D01*
X703459Y246665D01*
Y246495D01*
X703449Y246450D01*
X703444Y246410D01*
X703434Y246365D01*
X703424Y246325D01*
X703379Y246205D01*
X703339Y246125D01*
X703314Y246090D01*
X703294Y246055D01*
X703264Y246020D01*
X703239Y245985D01*
X703209Y245955D01*
Y243530D01*
X703199Y243405D01*
X703159Y243280D01*
X703099Y243170D01*
X703019Y243070D01*
X702919Y242990D01*
X702809Y242930D01*
X702684Y242890D01*
X702559Y242880D01*
X702434Y242890D01*
X702309Y242930D01*
X702199Y242990D01*
X702099Y243070D01*
X702019Y243170D01*
X701959Y243280D01*
X701919Y243405D01*
X701909Y243530D01*
Y245960D01*
X701879Y245990D01*
X701779Y246130D01*
X701759Y246170D01*
X701744Y246205D01*
X701724Y246245D01*
X701709Y246285D01*
X701699Y246325D01*
X701684Y246370D01*
X701679Y246410D01*
X701669Y246450D01*
X701664Y246495D01*
Y246535D01*
X701659Y246580D01*
X701664Y246625D01*
Y246665D01*
X701669Y246710D01*
X701679Y246750D01*
X701684Y246790D01*
X701699Y246835D01*
X701709Y246875D01*
X701724Y246915D01*
X701744Y246955D01*
X701759Y246990D01*
X701779Y247030D01*
X701879Y247170D01*
X701909Y247200D01*
Y249330D01*
X701919Y249455D01*
X701959Y249580D01*
X702019Y249690D01*
X702099Y249790D01*
X702199Y249870D01*
X702309Y249930D01*
X702434Y249970D01*
X702559Y249980D01*
G37*
G36*
G01X707284D02*
X707409Y249970D01*
X707534Y249930D01*
X707644Y249870D01*
X707744Y249790D01*
X707824Y249690D01*
X707884Y249580D01*
X707924Y249455D01*
X707934Y249330D01*
Y247205D01*
X707964Y247175D01*
X707989Y247140D01*
X708019Y247105D01*
X708039Y247070D01*
X708064Y247035D01*
X708104Y246955D01*
X708149Y246835D01*
X708159Y246795D01*
X708169Y246750D01*
X708174Y246710D01*
X708184Y246665D01*
Y246495D01*
X708174Y246450D01*
X708169Y246410D01*
X708159Y246365D01*
X708149Y246325D01*
X708104Y246205D01*
X708064Y246125D01*
X708039Y246090D01*
X708019Y246055D01*
X707989Y246020D01*
X707964Y245985D01*
X707934Y245955D01*
Y243530D01*
X707924Y243405D01*
X707884Y243280D01*
X707824Y243170D01*
X707744Y243070D01*
X707644Y242990D01*
X707534Y242930D01*
X707409Y242890D01*
X707284Y242880D01*
X707159Y242890D01*
X707034Y242930D01*
X706924Y242990D01*
X706824Y243070D01*
X706744Y243170D01*
X706684Y243280D01*
X706644Y243405D01*
X706634Y243530D01*
Y245960D01*
X706604Y245990D01*
X706504Y246130D01*
X706484Y246170D01*
X706469Y246205D01*
X706449Y246245D01*
X706434Y246285D01*
X706424Y246325D01*
X706409Y246370D01*
X706404Y246410D01*
X706394Y246450D01*
X706389Y246495D01*
Y246535D01*
X706384Y246580D01*
X706389Y246625D01*
Y246665D01*
X706394Y246710D01*
X706404Y246750D01*
X706409Y246790D01*
X706424Y246835D01*
X706434Y246875D01*
X706449Y246915D01*
X706469Y246955D01*
X706484Y246990D01*
X706504Y247030D01*
X706604Y247170D01*
X706634Y247200D01*
Y249330D01*
X706644Y249455D01*
X706684Y249580D01*
X706744Y249690D01*
X706824Y249790D01*
X706924Y249870D01*
X707034Y249930D01*
X707159Y249970D01*
X707284Y249980D01*
G37*
G36*
G01X712008D02*
X712133Y249970D01*
X712258Y249930D01*
X712368Y249870D01*
X712468Y249790D01*
X712548Y249690D01*
X712608Y249580D01*
X712648Y249455D01*
X712658Y249330D01*
Y247205D01*
X712688Y247175D01*
X712713Y247140D01*
X712743Y247105D01*
X712763Y247070D01*
X712788Y247035D01*
X712828Y246955D01*
X712873Y246835D01*
X712883Y246795D01*
X712893Y246750D01*
X712898Y246710D01*
X712908Y246665D01*
Y246495D01*
X712898Y246450D01*
X712893Y246410D01*
X712883Y246365D01*
X712873Y246325D01*
X712828Y246205D01*
X712788Y246125D01*
X712763Y246090D01*
X712743Y246055D01*
X712713Y246020D01*
X712688Y245985D01*
X712658Y245955D01*
Y243530D01*
X712648Y243405D01*
X712608Y243280D01*
X712548Y243170D01*
X712468Y243070D01*
X712368Y242990D01*
X712258Y242930D01*
X712133Y242890D01*
X712008Y242880D01*
X711883Y242890D01*
X711758Y242930D01*
X711648Y242990D01*
X711548Y243070D01*
X711468Y243170D01*
X711408Y243280D01*
X711368Y243405D01*
X711358Y243530D01*
Y245960D01*
X711328Y245990D01*
X711228Y246130D01*
X711208Y246170D01*
X711193Y246205D01*
X711173Y246245D01*
X711158Y246285D01*
X711148Y246325D01*
X711133Y246370D01*
X711128Y246410D01*
X711118Y246450D01*
X711113Y246495D01*
Y246535D01*
X711108Y246580D01*
X711113Y246625D01*
Y246665D01*
X711118Y246710D01*
X711128Y246750D01*
X711133Y246790D01*
X711148Y246835D01*
X711158Y246875D01*
X711173Y246915D01*
X711193Y246955D01*
X711208Y246990D01*
X711228Y247030D01*
X711328Y247170D01*
X711358Y247200D01*
Y249330D01*
X711368Y249455D01*
X711408Y249580D01*
X711468Y249690D01*
X711548Y249790D01*
X711648Y249870D01*
X711758Y249930D01*
X711883Y249970D01*
X712008Y249980D01*
G37*
G36*
G01X716733D02*
X716858Y249970D01*
X716983Y249930D01*
X717093Y249870D01*
X717193Y249790D01*
X717273Y249690D01*
X717333Y249580D01*
X717373Y249455D01*
X717383Y249330D01*
Y247205D01*
X717413Y247175D01*
X717438Y247140D01*
X717468Y247105D01*
X717488Y247070D01*
X717513Y247035D01*
X717553Y246955D01*
X717598Y246835D01*
X717608Y246795D01*
X717618Y246750D01*
X717623Y246710D01*
X717633Y246665D01*
Y246495D01*
X717623Y246450D01*
X717618Y246410D01*
X717608Y246365D01*
X717598Y246325D01*
X717553Y246205D01*
X717513Y246125D01*
X717488Y246090D01*
X717468Y246055D01*
X717438Y246020D01*
X717413Y245985D01*
X717383Y245955D01*
Y243530D01*
X717373Y243405D01*
X717333Y243280D01*
X717273Y243170D01*
X717193Y243070D01*
X717093Y242990D01*
X716983Y242930D01*
X716858Y242890D01*
X716733Y242880D01*
X716608Y242890D01*
X716483Y242930D01*
X716373Y242990D01*
X716273Y243070D01*
X716193Y243170D01*
X716133Y243280D01*
X716093Y243405D01*
X716083Y243530D01*
Y245960D01*
X716053Y245990D01*
X715953Y246130D01*
X715933Y246170D01*
X715918Y246205D01*
X715898Y246245D01*
X715883Y246285D01*
X715873Y246325D01*
X715858Y246370D01*
X715853Y246410D01*
X715843Y246450D01*
X715838Y246495D01*
Y246535D01*
X715833Y246580D01*
X715838Y246625D01*
Y246665D01*
X715843Y246710D01*
X715853Y246750D01*
X715858Y246790D01*
X715873Y246835D01*
X715883Y246875D01*
X715898Y246915D01*
X715918Y246955D01*
X715933Y246990D01*
X715953Y247030D01*
X716053Y247170D01*
X716083Y247200D01*
Y249330D01*
X716093Y249455D01*
X716133Y249580D01*
X716193Y249690D01*
X716273Y249790D01*
X716373Y249870D01*
X716483Y249930D01*
X716608Y249970D01*
X716733Y249980D01*
G37*
G36*
G01X721457D02*
X721582Y249970D01*
X721707Y249930D01*
X721817Y249870D01*
X721917Y249790D01*
X721997Y249690D01*
X722057Y249580D01*
X722097Y249455D01*
X722107Y249330D01*
Y247205D01*
X722137Y247175D01*
X722162Y247140D01*
X722192Y247105D01*
X722212Y247070D01*
X722237Y247035D01*
X722277Y246955D01*
X722322Y246835D01*
X722332Y246795D01*
X722342Y246750D01*
X722347Y246710D01*
X722357Y246665D01*
Y246495D01*
X722347Y246450D01*
X722342Y246410D01*
X722332Y246365D01*
X722322Y246325D01*
X722277Y246205D01*
X722237Y246125D01*
X722212Y246090D01*
X722192Y246055D01*
X722162Y246020D01*
X722137Y245985D01*
X722107Y245955D01*
Y243530D01*
X722097Y243405D01*
X722057Y243280D01*
X721997Y243170D01*
X721917Y243070D01*
X721817Y242990D01*
X721707Y242930D01*
X721582Y242890D01*
X721457Y242880D01*
X721332Y242890D01*
X721207Y242930D01*
X721097Y242990D01*
X720997Y243070D01*
X720917Y243170D01*
X720857Y243280D01*
X720817Y243405D01*
X720807Y243530D01*
Y245960D01*
X720777Y245990D01*
X720677Y246130D01*
X720657Y246170D01*
X720642Y246205D01*
X720622Y246245D01*
X720607Y246285D01*
X720597Y246325D01*
X720582Y246370D01*
X720577Y246410D01*
X720567Y246450D01*
X720562Y246495D01*
Y246535D01*
X720557Y246580D01*
X720562Y246625D01*
Y246665D01*
X720567Y246710D01*
X720577Y246750D01*
X720582Y246790D01*
X720597Y246835D01*
X720607Y246875D01*
X720622Y246915D01*
X720642Y246955D01*
X720657Y246990D01*
X720677Y247030D01*
X720777Y247170D01*
X720807Y247200D01*
Y249330D01*
X720817Y249455D01*
X720857Y249580D01*
X720917Y249690D01*
X720997Y249790D01*
X721097Y249870D01*
X721207Y249930D01*
X721332Y249970D01*
X721457Y249980D01*
G37*
G36*
G01X726181D02*
X726306Y249970D01*
X726431Y249930D01*
X726541Y249870D01*
X726641Y249790D01*
X726721Y249690D01*
X726781Y249580D01*
X726821Y249455D01*
X726831Y249330D01*
Y247205D01*
X726861Y247175D01*
X726886Y247140D01*
X726916Y247105D01*
X726936Y247070D01*
X726961Y247035D01*
X727001Y246955D01*
X727046Y246835D01*
X727056Y246795D01*
X727066Y246750D01*
X727071Y246710D01*
X727081Y246665D01*
Y246495D01*
X727071Y246450D01*
X727066Y246410D01*
X727056Y246365D01*
X727046Y246325D01*
X727001Y246205D01*
X726961Y246125D01*
X726936Y246090D01*
X726916Y246055D01*
X726886Y246020D01*
X726861Y245985D01*
X726831Y245955D01*
Y243530D01*
X726821Y243405D01*
X726781Y243280D01*
X726721Y243170D01*
X726641Y243070D01*
X726541Y242990D01*
X726431Y242930D01*
X726306Y242890D01*
X726181Y242880D01*
X726056Y242890D01*
X725931Y242930D01*
X725821Y242990D01*
X725721Y243070D01*
X725641Y243170D01*
X725581Y243280D01*
X725541Y243405D01*
X725531Y243530D01*
Y245960D01*
X725501Y245990D01*
X725401Y246130D01*
X725381Y246170D01*
X725366Y246205D01*
X725346Y246245D01*
X725331Y246285D01*
X725321Y246325D01*
X725306Y246370D01*
X725301Y246410D01*
X725291Y246450D01*
X725286Y246495D01*
Y246535D01*
X725281Y246580D01*
X725286Y246625D01*
Y246665D01*
X725291Y246710D01*
X725301Y246750D01*
X725306Y246790D01*
X725321Y246835D01*
X725331Y246875D01*
X725346Y246915D01*
X725366Y246955D01*
X725381Y246990D01*
X725401Y247030D01*
X725501Y247170D01*
X725531Y247200D01*
Y249330D01*
X725541Y249455D01*
X725581Y249580D01*
X725641Y249690D01*
X725721Y249790D01*
X725821Y249870D01*
X725931Y249930D01*
X726056Y249970D01*
X726181Y249980D01*
G37*
G36*
G01X730906D02*
X731031Y249970D01*
X731156Y249930D01*
X731266Y249870D01*
X731366Y249790D01*
X731446Y249690D01*
X731506Y249580D01*
X731546Y249455D01*
X731556Y249330D01*
Y247205D01*
X731586Y247175D01*
X731611Y247140D01*
X731641Y247105D01*
X731661Y247070D01*
X731686Y247035D01*
X731726Y246955D01*
X731771Y246835D01*
X731781Y246795D01*
X731791Y246750D01*
X731796Y246710D01*
X731806Y246665D01*
Y246495D01*
X731796Y246450D01*
X731791Y246410D01*
X731781Y246365D01*
X731771Y246325D01*
X731726Y246205D01*
X731686Y246125D01*
X731661Y246090D01*
X731641Y246055D01*
X731611Y246020D01*
X731586Y245985D01*
X731556Y245955D01*
Y243530D01*
X731546Y243405D01*
X731506Y243280D01*
X731446Y243170D01*
X731366Y243070D01*
X731266Y242990D01*
X731156Y242930D01*
X731031Y242890D01*
X730906Y242880D01*
X730781Y242890D01*
X730656Y242930D01*
X730546Y242990D01*
X730446Y243070D01*
X730366Y243170D01*
X730306Y243280D01*
X730266Y243405D01*
X730256Y243530D01*
Y245960D01*
X730226Y245990D01*
X730126Y246130D01*
X730106Y246170D01*
X730091Y246205D01*
X730071Y246245D01*
X730056Y246285D01*
X730046Y246325D01*
X730031Y246370D01*
X730026Y246410D01*
X730016Y246450D01*
X730011Y246495D01*
Y246535D01*
X730006Y246580D01*
X730011Y246625D01*
Y246665D01*
X730016Y246710D01*
X730026Y246750D01*
X730031Y246790D01*
X730046Y246835D01*
X730056Y246875D01*
X730071Y246915D01*
X730091Y246955D01*
X730106Y246990D01*
X730126Y247030D01*
X730226Y247170D01*
X730256Y247200D01*
Y249330D01*
X730266Y249455D01*
X730306Y249580D01*
X730366Y249690D01*
X730446Y249790D01*
X730546Y249870D01*
X730656Y249930D01*
X730781Y249970D01*
X730906Y249980D01*
G37*
G36*
G01X735630D02*
X735755Y249970D01*
X735880Y249930D01*
X735990Y249870D01*
X736090Y249790D01*
X736170Y249690D01*
X736230Y249580D01*
X736270Y249455D01*
X736280Y249330D01*
Y247205D01*
X736310Y247175D01*
X736335Y247140D01*
X736365Y247105D01*
X736385Y247070D01*
X736410Y247035D01*
X736450Y246955D01*
X736495Y246835D01*
X736505Y246795D01*
X736515Y246750D01*
X736520Y246710D01*
X736530Y246665D01*
Y246495D01*
X736520Y246450D01*
X736515Y246410D01*
X736505Y246365D01*
X736495Y246325D01*
X736450Y246205D01*
X736410Y246125D01*
X736385Y246090D01*
X736365Y246055D01*
X736335Y246020D01*
X736310Y245985D01*
X736280Y245955D01*
Y243530D01*
X736270Y243405D01*
X736230Y243280D01*
X736170Y243170D01*
X736090Y243070D01*
X735990Y242990D01*
X735880Y242930D01*
X735755Y242890D01*
X735630Y242880D01*
X735505Y242890D01*
X735380Y242930D01*
X735270Y242990D01*
X735170Y243070D01*
X735090Y243170D01*
X735030Y243280D01*
X734990Y243405D01*
X734980Y243530D01*
Y245960D01*
X734950Y245990D01*
X734850Y246130D01*
X734830Y246170D01*
X734815Y246205D01*
X734795Y246245D01*
X734780Y246285D01*
X734770Y246325D01*
X734755Y246370D01*
X734750Y246410D01*
X734740Y246450D01*
X734735Y246495D01*
Y246535D01*
X734730Y246580D01*
X734735Y246625D01*
Y246665D01*
X734740Y246710D01*
X734750Y246750D01*
X734755Y246790D01*
X734770Y246835D01*
X734780Y246875D01*
X734795Y246915D01*
X734815Y246955D01*
X734830Y246990D01*
X734850Y247030D01*
X734950Y247170D01*
X734980Y247200D01*
Y249330D01*
X734990Y249455D01*
X735030Y249580D01*
X735090Y249690D01*
X735170Y249790D01*
X735270Y249870D01*
X735380Y249930D01*
X735505Y249970D01*
X735630Y249980D01*
G37*
G36*
G01X740355D02*
X740480Y249970D01*
X740605Y249930D01*
X740715Y249870D01*
X740815Y249790D01*
X740895Y249690D01*
X740955Y249580D01*
X740995Y249455D01*
X741005Y249330D01*
Y247205D01*
X741035Y247175D01*
X741060Y247140D01*
X741090Y247105D01*
X741110Y247070D01*
X741135Y247035D01*
X741175Y246955D01*
X741220Y246835D01*
X741230Y246795D01*
X741240Y246750D01*
X741245Y246710D01*
X741255Y246665D01*
Y246495D01*
X741245Y246450D01*
X741240Y246410D01*
X741230Y246365D01*
X741220Y246325D01*
X741175Y246205D01*
X741135Y246125D01*
X741110Y246090D01*
X741090Y246055D01*
X741060Y246020D01*
X741035Y245985D01*
X741005Y245955D01*
Y243530D01*
X740995Y243405D01*
X740955Y243280D01*
X740895Y243170D01*
X740815Y243070D01*
X740715Y242990D01*
X740605Y242930D01*
X740480Y242890D01*
X740355Y242880D01*
X740230Y242890D01*
X740105Y242930D01*
X739995Y242990D01*
X739895Y243070D01*
X739815Y243170D01*
X739755Y243280D01*
X739715Y243405D01*
X739705Y243530D01*
Y245960D01*
X739675Y245990D01*
X739575Y246130D01*
X739555Y246170D01*
X739540Y246205D01*
X739520Y246245D01*
X739505Y246285D01*
X739495Y246325D01*
X739480Y246370D01*
X739475Y246410D01*
X739465Y246450D01*
X739460Y246495D01*
Y246535D01*
X739455Y246580D01*
X739460Y246625D01*
Y246665D01*
X739465Y246710D01*
X739475Y246750D01*
X739480Y246790D01*
X739495Y246835D01*
X739505Y246875D01*
X739520Y246915D01*
X739540Y246955D01*
X739555Y246990D01*
X739575Y247030D01*
X739675Y247170D01*
X739705Y247200D01*
Y249330D01*
X739715Y249455D01*
X739755Y249580D01*
X739815Y249690D01*
X739895Y249790D01*
X739995Y249870D01*
X740105Y249930D01*
X740230Y249970D01*
X740355Y249980D01*
G37*
G36*
G01X745079D02*
X745204Y249970D01*
X745329Y249930D01*
X745439Y249870D01*
X745539Y249790D01*
X745619Y249690D01*
X745679Y249580D01*
X745719Y249455D01*
X745729Y249330D01*
Y247205D01*
X745759Y247175D01*
X745784Y247140D01*
X745814Y247105D01*
X745834Y247070D01*
X745859Y247035D01*
X745899Y246955D01*
X745944Y246835D01*
X745954Y246795D01*
X745964Y246750D01*
X745969Y246710D01*
X745979Y246665D01*
Y246495D01*
X745969Y246450D01*
X745964Y246410D01*
X745954Y246365D01*
X745944Y246325D01*
X745899Y246205D01*
X745859Y246125D01*
X745834Y246090D01*
X745814Y246055D01*
X745784Y246020D01*
X745759Y245985D01*
X745729Y245955D01*
Y243530D01*
X745719Y243405D01*
X745679Y243280D01*
X745619Y243170D01*
X745539Y243070D01*
X745439Y242990D01*
X745329Y242930D01*
X745204Y242890D01*
X745079Y242880D01*
X744954Y242890D01*
X744829Y242930D01*
X744719Y242990D01*
X744619Y243070D01*
X744539Y243170D01*
X744479Y243280D01*
X744439Y243405D01*
X744429Y243530D01*
Y245960D01*
X744399Y245990D01*
X744299Y246130D01*
X744279Y246170D01*
X744264Y246205D01*
X744244Y246245D01*
X744229Y246285D01*
X744219Y246325D01*
X744204Y246370D01*
X744199Y246410D01*
X744189Y246450D01*
X744184Y246495D01*
Y246535D01*
X744179Y246580D01*
X744184Y246625D01*
Y246665D01*
X744189Y246710D01*
X744199Y246750D01*
X744204Y246790D01*
X744219Y246835D01*
X744229Y246875D01*
X744244Y246915D01*
X744264Y246955D01*
X744279Y246990D01*
X744299Y247030D01*
X744399Y247170D01*
X744429Y247200D01*
Y249330D01*
X744439Y249455D01*
X744479Y249580D01*
X744539Y249690D01*
X744619Y249790D01*
X744719Y249870D01*
X744829Y249930D01*
X744954Y249970D01*
X745079Y249980D01*
G37*
G54D46*
X108550Y153000D03*
X109200Y165500D03*
X119150Y153000D03*
X119800Y165500D03*
G54D19*
X24000Y127700D03*
Y124300D03*
X27200Y127700D03*
Y124300D03*
X30200Y127700D03*
Y124300D03*
X24900Y197300D03*
Y200700D03*
X37500Y127700D03*
Y124300D03*
X57000Y127200D03*
Y123800D03*
X52500Y238200D03*
Y234800D03*
X49500Y238200D03*
Y234800D03*
X61300Y253300D03*
Y249900D03*
X79000Y132600D03*
Y129200D03*
X68000Y198300D03*
Y201700D03*
X77700Y256500D03*
Y253100D03*
X64400Y253300D03*
Y249900D03*
X89500Y258300D03*
Y254900D03*
X80200Y266200D03*
Y262800D03*
X118000Y54200D03*
Y50800D03*
X123700Y150900D03*
Y154300D03*
X129500Y81200D03*
Y77800D03*
X130600Y131800D03*
Y128400D03*
X126800Y144300D03*
Y140900D03*
X127000Y150800D03*
Y154200D03*
X150000Y167200D03*
Y163800D03*
X184500Y65000D03*
Y61600D03*
X187500Y65000D03*
Y61600D03*
X185500Y87800D03*
Y91200D03*
X190500Y65000D03*
Y61600D03*
X193500Y65000D03*
Y61600D03*
X194600Y88800D03*
X197600D03*
X194600Y92200D03*
X197600D03*
X197300Y135800D03*
X191300D03*
X194300D03*
X197300Y139200D03*
X191300D03*
X194300D03*
X221500Y212300D03*
Y215700D03*
X238000Y166700D03*
Y163300D03*
X246000Y193200D03*
Y189800D03*
X255500Y96700D03*
Y93300D03*
X270000Y84700D03*
Y81300D03*
X267000Y84700D03*
Y81300D03*
X276700Y182700D03*
Y186100D03*
X293000Y195700D03*
Y192300D03*
X289500Y218700D03*
Y215300D03*
X322000Y257800D03*
X311500D03*
X322000Y261200D03*
X311500D03*
X441600Y254800D03*
Y251400D03*
X449000Y281700D03*
Y278300D03*
X446000Y281700D03*
Y278300D03*
X462500Y255200D03*
Y251800D03*
X461000Y270700D03*
Y267300D03*
X465500Y143763D03*
Y140363D03*
Y255200D03*
Y251800D03*
X509200Y103200D03*
Y99800D03*
X523000Y74800D03*
Y78200D03*
X531500Y237200D03*
Y233800D03*
X555300Y214100D03*
Y217500D03*
X566500Y84700D03*
Y81300D03*
X595500Y202200D03*
Y198800D03*
X613000Y115700D03*
Y112300D03*
X616000Y115700D03*
Y112300D03*
X622500Y88700D03*
Y85300D03*
X623000Y115700D03*
Y112300D03*
X634000Y136300D03*
Y139700D03*
X628900Y178400D03*
Y175000D03*
X646500Y182200D03*
Y178800D03*
X667500Y164800D03*
Y168200D03*
X668000Y211500D03*
Y208100D03*
X694500Y226700D03*
Y223300D03*
X691500Y226700D03*
Y223300D03*
X682500Y226700D03*
Y223300D03*
X711000Y66700D03*
Y63300D03*
X714000Y71200D03*
Y67800D03*
X725200Y119900D03*
Y116500D03*
X718700Y126600D03*
Y123200D03*
X718000Y143700D03*
Y140300D03*
X723000Y183200D03*
Y179800D03*
X726000Y183200D03*
Y179800D03*
X725000Y213700D03*
Y210300D03*
X722000Y213700D03*
Y210300D03*
X718500Y220700D03*
Y217300D03*
X722000Y220700D03*
Y217300D03*
X728000Y104300D03*
X739500Y104600D03*
X728000Y107700D03*
X739500Y108000D03*
X728000Y158700D03*
Y155300D03*
X735500Y182700D03*
Y179300D03*
X740500Y197800D03*
Y201200D03*
X744000Y165200D03*
Y161800D03*
X754500Y158700D03*
Y155300D03*
X782500Y41800D03*
Y45200D03*
X779500Y148700D03*
Y145300D03*
X807500Y86200D03*
Y82800D03*
G54D73*
X236100Y114300D03*
X244100Y110560D03*
Y118040D03*
G54D37*
X62246Y154500D03*
X84754D03*
G54D82*
X318702Y111401D03*
X317132Y113711D03*
X319282Y115791D03*
X320112Y118471D03*
X317112Y118671D03*
X319112Y121101D03*
X324582Y108891D03*
X322572Y110771D03*
X322192Y113691D03*
X324822Y121201D03*
X321992Y116451D03*
Y120481D03*
X324582Y105891D03*
X318702Y129131D03*
X315782Y129151D03*
X317332Y131541D03*
X317112Y136391D03*
X320112Y136191D03*
X319282Y133521D03*
X315132Y133201D03*
X321442Y128751D03*
X322192Y131421D03*
X321992Y134181D03*
X315342Y121311D03*
X315792Y125511D03*
X318702Y125631D03*
X317352Y123221D03*
X324822Y123961D03*
X321442Y125991D03*
X321922Y123261D03*
X317332Y149271D03*
X318702Y146861D03*
X315782Y146881D03*
X319282Y151251D03*
X315132Y150931D03*
X321442Y146481D03*
X322192Y149151D03*
X321992Y151911D03*
X319112Y138831D03*
X315342Y139031D03*
X317352Y140951D03*
X318702Y143361D03*
X315792Y143231D03*
X321992Y138211D03*
X324822Y139601D03*
Y136841D03*
X321442Y143721D03*
X321922Y140991D03*
X317332Y166991D03*
X322192Y166871D03*
X317112Y154121D03*
X318702Y161091D03*
X317352Y158681D03*
X319112Y156551D03*
X315792Y160961D03*
X315342Y156761D03*
X318702Y164591D03*
X315782Y164611D03*
X320112Y153921D03*
X321442Y161451D03*
X321992Y155931D03*
X321922Y158721D03*
X324822Y152481D03*
Y155241D03*
X321442Y164201D03*
X319282Y168971D03*
X315132Y168661D03*
X317352Y176411D03*
X319112Y174281D03*
X315342Y174491D03*
X317112Y171851D03*
X318702Y178811D03*
X315792Y178691D03*
X318702Y182311D03*
X315782Y182341D03*
X320112Y171651D03*
X324822Y168121D03*
X321992Y169641D03*
X324822Y170881D03*
X321922Y176451D03*
X321992Y173661D03*
X321442Y179181D03*
Y181931D03*
X317332Y184721D03*
X315132Y186391D03*
X319282Y186701D03*
X317112Y189581D03*
X319282Y192051D03*
X317132Y194131D03*
X318702Y196441D03*
X320112Y189381D03*
X324822Y186521D03*
X322192Y184601D03*
X321992Y187371D03*
Y191391D03*
X325782Y197891D03*
X321442Y196901D03*
X321922Y194171D03*
X324822Y194341D03*
Y183761D03*
X323772Y199771D03*
Y202771D03*
X331622Y104561D03*
X335272Y104571D03*
X339472Y104121D03*
X334782Y110221D03*
X332032D03*
X332292Y113601D03*
Y116601D03*
X337522Y110711D03*
X340302Y110771D03*
X340112Y115101D03*
X337352D03*
X340112Y118101D03*
X337352D03*
Y121101D03*
X340112D03*
X330822Y121201D03*
X335152Y107481D03*
X331652D03*
X339682Y107891D03*
X337552Y106131D03*
X327262Y108061D03*
X329362Y110971D03*
X326592Y110771D03*
X327822Y113601D03*
X329322Y116141D03*
X326322D03*
X327822Y121201D03*
X329242Y106111D03*
X336822Y123961D03*
X332322Y129021D03*
X335322D03*
X332322Y131781D03*
X335322D03*
X338322Y129021D03*
Y131781D03*
X333822Y123961D03*
X340112Y124101D03*
X330822Y123961D03*
X329322Y129021D03*
X326322D03*
X329322Y131781D03*
X326322D03*
X327822Y123961D03*
X332322Y147421D03*
X335322D03*
X338322D03*
X329322D03*
X333822Y139601D03*
Y136841D03*
X332322Y144661D03*
X335322D03*
X336822Y139601D03*
X339822D03*
X336822Y136841D03*
X339822D03*
X338322Y144661D03*
X330822Y139601D03*
Y136841D03*
X329322Y144661D03*
X326322Y147421D03*
X327822Y139601D03*
Y136841D03*
X326322Y144661D03*
X332322Y160301D03*
X333822Y152481D03*
Y155241D03*
X335322Y160301D03*
X332322Y163061D03*
X335322D03*
X338322Y160301D03*
X339822Y152481D03*
X336822D03*
X339822Y155241D03*
X336822D03*
X338322Y163061D03*
X329322Y160301D03*
X330822Y152481D03*
Y155241D03*
X329322Y163061D03*
X326322Y160301D03*
X327822Y152481D03*
Y155241D03*
X326322Y163061D03*
X333822Y168121D03*
Y170881D03*
X332322Y175941D03*
X335322D03*
X332322Y178701D03*
X335322D03*
X336822Y168121D03*
X339822D03*
X336822Y170881D03*
X339822D03*
X338322Y175941D03*
Y178701D03*
X330822Y168121D03*
Y170881D03*
X329322Y175941D03*
Y178701D03*
X327822Y168121D03*
Y170881D03*
X326322Y175941D03*
Y178701D03*
X331352Y189061D03*
Y192061D03*
Y195061D03*
X336412Y190561D03*
Y187561D03*
X339172Y190561D03*
Y187561D03*
X336722Y197691D03*
X339492Y197891D03*
X336412Y193561D03*
X339172D03*
X333822Y183761D03*
X339822D03*
X336822D03*
X330822D03*
X328592Y192061D03*
X327822Y186521D03*
X328562Y197951D03*
X328592Y195061D03*
X327822Y183761D03*
X334462Y204101D03*
X338512Y204751D03*
X330812Y204091D03*
X331302Y198441D03*
X334052D03*
X334432Y201181D03*
X338822Y200601D03*
X336842Y202551D03*
X330932Y201181D03*
X326442Y200601D03*
X328532Y202531D03*
X353002Y104571D03*
X349352Y104561D03*
X345302Y103911D03*
X352512Y110221D03*
X355242Y110711D03*
X352992Y115101D03*
Y121101D03*
Y118101D03*
X355752Y115101D03*
Y121101D03*
Y118101D03*
X349762Y110221D03*
X352882Y107481D03*
X355282Y106131D03*
X349382Y107481D03*
X344992Y108061D03*
X342312Y108891D03*
X347092Y110971D03*
X344322Y110771D03*
X347932Y113601D03*
X345172D03*
X347932Y116601D03*
Y119601D03*
X345172Y116601D03*
Y119601D03*
X346972Y106111D03*
X342112Y105891D03*
X350582Y132671D03*
X352992Y130101D03*
Y127101D03*
X355752D03*
Y130101D03*
X354132Y132671D03*
X352992Y124101D03*
X355752D03*
X347932Y128601D03*
X345172D03*
X341322Y129021D03*
X347932Y131601D03*
X345172D03*
X341322Y131781D03*
X347932Y122601D03*
Y125601D03*
X345172Y122601D03*
Y125601D03*
X350082Y147421D03*
X350422Y150171D03*
X350082Y144661D03*
X350422Y141901D03*
X348822Y136841D03*
Y139601D03*
X347322Y147421D03*
X341322D03*
X344322D03*
X345822Y139601D03*
X342822D03*
X345822Y136841D03*
X342822D03*
X347322Y144661D03*
X341322D03*
X344322D03*
X350422Y165811D03*
X350082Y160301D03*
X350422Y157541D03*
X350082Y163061D03*
X348822Y155241D03*
Y152481D03*
X347322Y160301D03*
X345822Y152481D03*
Y155241D03*
X341322Y160301D03*
X342822Y155241D03*
Y152481D03*
X344322Y160301D03*
X347322Y163061D03*
X341322D03*
X344322D03*
X350982Y175991D03*
X350882Y173231D03*
X353742Y175991D03*
X354812Y181561D03*
X352052D03*
Y178561D03*
X354812D03*
X348822Y168121D03*
Y170881D03*
X345822Y168121D03*
X342822D03*
X346992Y177061D03*
X344232D03*
X345822Y170881D03*
X342822D03*
X341322Y175941D03*
X346992Y180061D03*
X344232D03*
X341322Y178701D03*
X352052Y190561D03*
Y187561D03*
X354812Y190561D03*
Y187561D03*
X352052Y184561D03*
X354812D03*
X354452Y197691D03*
X354812Y193561D03*
X352052D03*
X346992Y192061D03*
Y189061D03*
Y186061D03*
X344232D03*
Y189061D03*
Y192061D03*
X343512Y197891D03*
X346292Y197951D03*
X346992Y195061D03*
X344232D03*
X346992Y183061D03*
X344232D03*
X356242Y204751D03*
X352182Y204101D03*
X348542Y204091D03*
X351782Y198441D03*
X356552Y200601D03*
X352162Y201181D03*
X354572Y202551D03*
X349022Y198441D03*
X348662Y201181D03*
X344342Y204541D03*
X341502Y199771D03*
X344132Y200771D03*
X341702Y202771D03*
X346252Y202531D03*
X370732Y104571D03*
X357202Y104121D03*
X363032Y103911D03*
X367082Y104561D03*
X370242Y110221D03*
X371392Y118101D03*
Y121101D03*
Y115101D03*
X368632Y118101D03*
Y121101D03*
Y115101D03*
X370602Y107481D03*
X367482Y110221D03*
X360042Y108891D03*
X362722Y108061D03*
X363572Y113601D03*
X360812D03*
X358032Y110771D03*
X364822Y110971D03*
X362052Y110771D03*
X363572Y119601D03*
Y116601D03*
X360812Y119601D03*
Y116601D03*
X357412Y107891D03*
X364702Y106111D03*
X367102Y107481D03*
X359842Y105891D03*
X371392Y127101D03*
Y130101D03*
X368632Y127101D03*
Y130101D03*
X371392Y124101D03*
X368632D03*
X363572Y128601D03*
X360812D03*
X363572Y131601D03*
X360812D03*
X363572Y125601D03*
Y122601D03*
X360812Y125601D03*
Y122601D03*
X370452Y178561D03*
Y181561D03*
X367692Y178561D03*
Y181561D03*
X362632Y177061D03*
X359872D03*
Y180061D03*
X362632D03*
X370452Y187561D03*
Y190561D03*
Y184561D03*
Y193561D03*
X367692Y187561D03*
Y190561D03*
Y184561D03*
Y193561D03*
X359872Y186061D03*
Y189061D03*
Y192061D03*
X362632Y186061D03*
Y189061D03*
Y192061D03*
X361242Y197891D03*
X364022Y197931D03*
X359872Y195061D03*
X362632D03*
X357212Y197891D03*
X359872Y183061D03*
X362632D03*
X369912Y204101D03*
X369512Y198441D03*
X369892Y201181D03*
X362062Y204541D03*
X366262Y204091D03*
X366752Y198441D03*
X359222Y199771D03*
X359422Y202771D03*
X361862Y200771D03*
X363982Y202531D03*
X366392Y201181D03*
X374932Y104121D03*
X380762Y103911D03*
X384812Y104561D03*
X387032Y115101D03*
Y121101D03*
Y118101D03*
X377772Y108891D03*
X380442Y108061D03*
X376452Y113601D03*
X379212D03*
X372972Y110731D03*
X375762Y110771D03*
X379782D03*
X382542Y110971D03*
X376452Y116601D03*
Y119601D03*
X379212Y116601D03*
Y119601D03*
X385212Y110221D03*
X384272Y115101D03*
Y121101D03*
Y118101D03*
X373012Y106131D03*
X375142Y107891D03*
X377572Y105891D03*
X382422Y106111D03*
X384832Y107481D03*
X387032Y127101D03*
Y130101D03*
Y124101D03*
X376452Y128601D03*
X379212D03*
X376452Y131601D03*
X379212D03*
X384272Y130101D03*
Y127101D03*
X376452Y122601D03*
Y125601D03*
X379212Y122601D03*
Y125601D03*
X384272Y124101D03*
X386092Y181561D03*
Y178561D03*
X378272Y177061D03*
X375512D03*
X378272Y180061D03*
X375512D03*
X383332Y181561D03*
Y178561D03*
X386092Y190561D03*
Y187561D03*
Y184561D03*
Y193561D03*
X378272Y192061D03*
Y189061D03*
Y186061D03*
X375512Y192061D03*
Y189061D03*
Y186061D03*
X378962Y197891D03*
X378272Y195061D03*
X374942Y197891D03*
X372182Y197691D03*
X375512Y195061D03*
X381752Y197931D03*
X383332Y190561D03*
Y187561D03*
Y184561D03*
Y193561D03*
X378272Y183061D03*
X375512D03*
X387242Y198441D03*
X379792Y204541D03*
X373962Y204751D03*
X383992Y204091D03*
X376952Y199771D03*
X374282Y200601D03*
X379582Y200771D03*
X377152Y202771D03*
X372302Y202551D03*
X381712Y202531D03*
X384482Y198441D03*
X384122Y201181D03*
X388462Y104571D03*
X392662Y104121D03*
X398482Y103911D03*
X402542Y104561D03*
X395502Y108891D03*
X398172Y108061D03*
X392092Y113601D03*
X394852D03*
X393482Y110771D03*
X390702Y110711D03*
X397512Y110771D03*
X392092Y119601D03*
Y116601D03*
X394852Y119601D03*
Y116601D03*
X400272Y110971D03*
X402672Y118101D03*
Y121101D03*
X399912Y118101D03*
Y121101D03*
Y115101D03*
X402672D03*
X387972Y110221D03*
X395302Y105891D03*
X390742Y106131D03*
X388332Y107481D03*
X392862Y107891D03*
X402562Y107481D03*
X400152Y106111D03*
X392092Y128601D03*
X394852D03*
X392092Y131601D03*
X394852D03*
X399912Y127101D03*
X402672D03*
X399912Y130101D03*
X402672D03*
X400982Y132671D03*
X392092Y125601D03*
Y122601D03*
X394852Y125601D03*
Y122601D03*
X402672Y124101D03*
X399912D03*
X391152Y177061D03*
X393912D03*
X398972Y178561D03*
Y181561D03*
X393912Y180061D03*
X391152D03*
X400592Y175991D03*
X401732Y178561D03*
Y181561D03*
X398972Y187561D03*
Y190561D03*
Y184561D03*
X393912Y186061D03*
Y189061D03*
Y192061D03*
X391152Y186061D03*
Y189061D03*
Y192061D03*
X396692Y197891D03*
X398972Y193561D03*
X389902Y197691D03*
X392672Y197891D03*
X393912Y195061D03*
X391152D03*
X401732Y187561D03*
Y190561D03*
Y184561D03*
X399482Y197931D03*
X401732Y193561D03*
X393912Y183061D03*
X391152D03*
X397522Y204541D03*
X391692Y204751D03*
X401722Y204091D03*
X387642Y204101D03*
X392002Y200601D03*
X394682Y199771D03*
X397312Y200771D03*
X390022Y202551D03*
X394882Y202771D03*
X402212Y198441D03*
X401842Y201181D03*
X399442Y202531D03*
X387622Y201181D03*
X410382Y104121D03*
X416212Y103911D03*
X406182Y104571D03*
X407732Y113601D03*
X410492D03*
X408432Y110711D03*
X413222Y108891D03*
X411212Y110771D03*
X415232D03*
X407732Y116601D03*
Y119601D03*
X410492Y116601D03*
Y119601D03*
X415902Y108061D03*
X418002Y110971D03*
X418312Y115101D03*
X415552D03*
Y121101D03*
Y118101D03*
X418312Y121101D03*
Y118101D03*
X410592Y107891D03*
X408472Y106131D03*
X413022Y105891D03*
X417882Y106111D03*
X406062Y107481D03*
X402942Y110221D03*
X405702D03*
X403842Y135431D03*
X407732Y128601D03*
X410492D03*
X413402Y129961D03*
X410492Y131601D03*
X407732D03*
X413402Y132721D03*
X416402Y129961D03*
Y132721D03*
X407732Y122601D03*
Y125601D03*
X410492Y122601D03*
Y125601D03*
X414902Y124901D03*
X417902D03*
X403742Y132671D03*
X407402Y148361D03*
X413402D03*
X410402D03*
X416402D03*
X408902Y137781D03*
Y140541D03*
X407402Y145601D03*
X411902Y137781D03*
Y140541D03*
X414902Y137781D03*
Y140541D03*
X413402Y145601D03*
X410402D03*
X417902Y137781D03*
Y140541D03*
X416402Y145601D03*
X405902Y137781D03*
Y140541D03*
X404642Y148361D03*
X404302Y151121D03*
Y142851D03*
X404642Y145601D03*
X408902Y153421D03*
Y156181D03*
X407402Y161241D03*
X411902Y156181D03*
Y153421D03*
X413402Y161241D03*
X410402D03*
X407402Y164001D03*
X413402D03*
X410402D03*
X417902Y153421D03*
X414902D03*
X417902Y156181D03*
X414902D03*
X416402Y161241D03*
Y164001D03*
X405902Y153421D03*
Y156181D03*
X404302Y166761D03*
Y158491D03*
X404642Y161241D03*
Y164001D03*
X408902Y169061D03*
X409552Y177061D03*
X408902Y171821D03*
X411902Y169061D03*
Y171821D03*
X413402Y176881D03*
X409552Y180061D03*
X413402Y179641D03*
X414902Y169061D03*
X417902D03*
X414902Y171821D03*
X417902D03*
X416402Y176881D03*
Y179641D03*
X405902Y169061D03*
X406792Y177061D03*
X405902Y171821D03*
X406792Y180061D03*
X404142Y175991D03*
X409552Y192061D03*
Y189061D03*
Y186061D03*
X414612Y190561D03*
Y187561D03*
Y184561D03*
X407632Y197691D03*
X409552Y195061D03*
X414612Y193561D03*
X414422Y197891D03*
X410402D03*
X417372Y190561D03*
Y187561D03*
X417902Y184701D03*
X417202Y197931D03*
X417372Y193561D03*
X406792Y192061D03*
Y189061D03*
Y186061D03*
Y195061D03*
X409552Y183061D03*
X406792D03*
X409422Y204751D03*
X415252Y204541D03*
X405372Y204101D03*
X409732Y200601D03*
X407752Y202551D03*
X412412Y199771D03*
X412612Y202771D03*
X415042Y200771D03*
X417172Y202531D03*
X405342Y201181D03*
X404962Y198441D03*
X423912Y104571D03*
X420262Y104561D03*
X428282Y108061D03*
X430952Y108891D03*
X426132Y113601D03*
X428942Y110771D03*
X426162Y110711D03*
X426132Y116601D03*
X429902Y114321D03*
X433282Y111761D03*
X432802Y114491D03*
X432732Y117271D03*
X430952Y105891D03*
X426192Y106131D03*
X420672Y110221D03*
X423422D03*
X423372Y113601D03*
Y116601D03*
Y119601D03*
X420292Y107481D03*
X423792D03*
X428402Y129961D03*
Y132721D03*
X433282Y129481D03*
X432732Y135001D03*
X432802Y132211D03*
X426902Y124901D03*
X429902D03*
X426902Y122141D03*
X429902D03*
X432732Y121291D03*
X433282Y126731D03*
X432532Y124061D03*
X425402Y129961D03*
X419402D03*
X422402D03*
X425402Y132721D03*
X419402D03*
X422402D03*
X420902Y124901D03*
X423902D03*
X428402Y148361D03*
X433282Y147211D03*
X432802Y149941D03*
X425402Y148361D03*
X429902Y137781D03*
X426902D03*
X429902Y140541D03*
X426902D03*
X428402Y145601D03*
X432732Y139021D03*
X432532Y141791D03*
X433282Y144461D03*
X425402Y145601D03*
X422402Y148361D03*
X419402D03*
X420902Y137781D03*
Y140541D03*
X423902Y137781D03*
Y140541D03*
X422402Y145601D03*
X419402D03*
X426902Y153421D03*
X429902D03*
X426902Y156181D03*
X429902D03*
X428402Y161241D03*
Y164001D03*
X432732Y156751D03*
Y152731D03*
X432532Y159511D03*
X433282Y162181D03*
Y164941D03*
X425402Y161241D03*
Y164001D03*
X420902Y153421D03*
Y156181D03*
X423902Y153421D03*
Y156181D03*
X419402Y161241D03*
X422402D03*
X419402Y164001D03*
X422402D03*
X429902Y169061D03*
X426902D03*
X429902Y171821D03*
X426902D03*
X428402Y176881D03*
Y179641D03*
X432732Y170451D03*
X432802Y167671D03*
X432732Y174481D03*
X432532Y177241D03*
X433282Y179911D03*
Y182671D03*
X425402Y176881D03*
Y179641D03*
X420902Y169061D03*
X423902D03*
X420902Y171821D03*
X423902D03*
X422402Y176881D03*
X419402D03*
X422402Y179641D03*
X419402D03*
X426902Y184701D03*
X429902D03*
X426902Y187461D03*
X429902D03*
X428402Y192521D03*
X428132Y197891D03*
X426902Y195061D03*
X432802Y185401D03*
X432732Y188181D03*
Y192211D03*
X432152Y197891D03*
X432532Y194971D03*
X425402Y192521D03*
X425362Y197691D03*
X422432Y192061D03*
X423902Y184701D03*
Y187461D03*
X420902Y184701D03*
X422432Y195061D03*
X427462Y200601D03*
X430142Y199771D03*
Y202771D03*
X425482Y202551D03*
X419452Y204091D03*
X423102Y204101D03*
X419942Y198441D03*
X422692D03*
X419572Y201181D03*
X423072D03*
X436022Y112221D03*
X437592Y114531D03*
X435442Y116611D03*
X437612Y119081D03*
X434612Y119281D03*
X438932Y129971D03*
X436022Y129851D03*
X439382Y134171D03*
X435612Y134381D03*
X437372Y132251D03*
X435442Y121961D03*
X437392Y123941D03*
X436022Y126351D03*
X439592Y122271D03*
X438942Y126321D03*
X438932Y147701D03*
X436022Y147571D03*
X439382Y151901D03*
X437372Y149981D03*
X434612Y137011D03*
X437612Y136811D03*
X439592Y140001D03*
X435442Y139691D03*
X436022Y144071D03*
X437392Y141671D03*
X438942Y144051D03*
X438932Y165431D03*
X436022Y165301D03*
X435612Y152111D03*
X434612Y154741D03*
X437612Y154541D03*
X439592Y157731D03*
X435442Y157411D03*
X437392Y159391D03*
X436022Y161801D03*
X438942Y161781D03*
X435612Y169831D03*
X439382Y169631D03*
X437372Y167711D03*
X434612Y172471D03*
X437612Y172271D03*
X439592Y175461D03*
X435442Y175141D03*
X437392Y177121D03*
X438942Y179511D03*
X436022Y179531D03*
X437372Y185441D03*
X435612Y187561D03*
X439382Y187351D03*
X437612Y189991D03*
X434612Y190191D03*
X435442Y192871D03*
X437592Y194951D03*
X436022Y197261D03*
Y183031D03*
X438932Y183151D03*
G54D29*
X39000Y158000D03*
X46300Y212700D03*
Y207800D03*
X43500Y198800D03*
Y203700D03*
X46500D03*
Y198800D03*
X35000Y222500D03*
Y219000D03*
Y229500D03*
Y226000D03*
Y236500D03*
Y233000D03*
Y243500D03*
Y240000D03*
Y250500D03*
Y247000D03*
Y257500D03*
Y254000D03*
X49300Y212700D03*
Y207800D03*
X64700Y198300D03*
Y201800D03*
X73900Y207200D03*
X80000Y85000D03*
X92300Y207100D03*
X80500Y249800D03*
X89500Y261500D03*
X183000Y75500D03*
X225800Y89900D03*
X440000Y278000D03*
X538500Y234100D03*
X611500Y96000D03*
Y93000D03*
X705000Y192500D03*
X721700Y119700D03*
Y116400D03*
X739200Y111100D03*
X745800Y108100D03*
X748000Y155500D03*
X779500Y16000D03*
G54D65*
X170561Y236000D03*
G54D74*
X237000Y128600D03*
X241000D03*
X239000Y123400D03*
X518500Y193600D03*
X522500D03*
X520500Y188400D03*
G54D56*
X140639Y252500D03*
X138080D03*
X135520D03*
X132961D03*
Y264500D03*
X135520D03*
X138080D03*
X140639D03*
G36*
G01X501772Y249980D02*
X501897Y249970D01*
X502022Y249930D01*
X502132Y249870D01*
X502232Y249790D01*
X502312Y249690D01*
X502372Y249580D01*
X502412Y249455D01*
X502422Y249330D01*
Y248200D01*
X502452Y248170D01*
X502552Y248030D01*
X502572Y247990D01*
X502587Y247955D01*
X502607Y247915D01*
X502622Y247875D01*
X502632Y247835D01*
X502647Y247790D01*
X502652Y247750D01*
X502662Y247710D01*
X502667Y247665D01*
Y247625D01*
X502672Y247580D01*
X502667Y247535D01*
Y247495D01*
X502662Y247450D01*
X502652Y247410D01*
X502647Y247370D01*
X502632Y247325D01*
X502622Y247285D01*
X502607Y247245D01*
X502587Y247205D01*
X502572Y247170D01*
X502552Y247130D01*
X502452Y246990D01*
X502422Y246960D01*
Y243530D01*
X502412Y243405D01*
X502372Y243280D01*
X502312Y243170D01*
X502232Y243070D01*
X502132Y242990D01*
X502022Y242930D01*
X501897Y242890D01*
X501772Y242880D01*
X501647Y242890D01*
X501522Y242930D01*
X501412Y242990D01*
X501312Y243070D01*
X501232Y243170D01*
X501172Y243280D01*
X501132Y243405D01*
X501122Y243530D01*
Y246960D01*
X501092Y246990D01*
X500992Y247130D01*
X500972Y247170D01*
X500957Y247205D01*
X500937Y247245D01*
X500922Y247285D01*
X500912Y247325D01*
X500897Y247370D01*
X500892Y247410D01*
X500882Y247450D01*
X500877Y247495D01*
Y247535D01*
X500872Y247580D01*
X500877Y247625D01*
Y247665D01*
X500882Y247710D01*
X500892Y247750D01*
X500897Y247790D01*
X500912Y247835D01*
X500922Y247875D01*
X500937Y247915D01*
X500957Y247955D01*
X500972Y247990D01*
X500992Y248030D01*
X501092Y248170D01*
X501122Y248200D01*
Y249330D01*
X501132Y249455D01*
X501172Y249580D01*
X501232Y249690D01*
X501312Y249790D01*
X501412Y249870D01*
X501522Y249930D01*
X501647Y249970D01*
X501772Y249980D01*
G37*
G36*
G01X506496D02*
X506621Y249970D01*
X506746Y249930D01*
X506856Y249870D01*
X506956Y249790D01*
X507036Y249690D01*
X507096Y249580D01*
X507136Y249455D01*
X507146Y249330D01*
Y248200D01*
X507176Y248170D01*
X507276Y248030D01*
X507296Y247990D01*
X507311Y247955D01*
X507331Y247915D01*
X507346Y247875D01*
X507356Y247835D01*
X507371Y247790D01*
X507376Y247750D01*
X507386Y247710D01*
X507391Y247665D01*
Y247625D01*
X507396Y247580D01*
X507391Y247535D01*
Y247495D01*
X507386Y247450D01*
X507376Y247410D01*
X507371Y247370D01*
X507356Y247325D01*
X507346Y247285D01*
X507331Y247245D01*
X507311Y247205D01*
X507296Y247170D01*
X507276Y247130D01*
X507176Y246990D01*
X507146Y246960D01*
Y243530D01*
X507136Y243405D01*
X507096Y243280D01*
X507036Y243170D01*
X506956Y243070D01*
X506856Y242990D01*
X506746Y242930D01*
X506621Y242890D01*
X506496Y242880D01*
X506371Y242890D01*
X506246Y242930D01*
X506136Y242990D01*
X506036Y243070D01*
X505956Y243170D01*
X505896Y243280D01*
X505856Y243405D01*
X505846Y243530D01*
Y246960D01*
X505816Y246990D01*
X505716Y247130D01*
X505696Y247170D01*
X505681Y247205D01*
X505661Y247245D01*
X505646Y247285D01*
X505636Y247325D01*
X505621Y247370D01*
X505616Y247410D01*
X505606Y247450D01*
X505601Y247495D01*
Y247535D01*
X505596Y247580D01*
X505601Y247625D01*
Y247665D01*
X505606Y247710D01*
X505616Y247750D01*
X505621Y247790D01*
X505636Y247835D01*
X505646Y247875D01*
X505661Y247915D01*
X505681Y247955D01*
X505696Y247990D01*
X505716Y248030D01*
X505816Y248170D01*
X505846Y248200D01*
Y249330D01*
X505856Y249455D01*
X505896Y249580D01*
X505956Y249690D01*
X506036Y249790D01*
X506136Y249870D01*
X506246Y249930D01*
X506371Y249970D01*
X506496Y249980D01*
G37*
G36*
G01X511221D02*
X511346Y249970D01*
X511471Y249930D01*
X511581Y249870D01*
X511681Y249790D01*
X511761Y249690D01*
X511821Y249580D01*
X511861Y249455D01*
X511871Y249330D01*
Y248200D01*
X511901Y248170D01*
X512001Y248030D01*
X512021Y247990D01*
X512036Y247955D01*
X512056Y247915D01*
X512071Y247875D01*
X512081Y247835D01*
X512096Y247790D01*
X512101Y247750D01*
X512111Y247710D01*
X512116Y247665D01*
Y247625D01*
X512121Y247580D01*
X512116Y247535D01*
Y247495D01*
X512111Y247450D01*
X512101Y247410D01*
X512096Y247370D01*
X512081Y247325D01*
X512071Y247285D01*
X512056Y247245D01*
X512036Y247205D01*
X512021Y247170D01*
X512001Y247130D01*
X511901Y246990D01*
X511871Y246960D01*
Y243530D01*
X511861Y243405D01*
X511821Y243280D01*
X511761Y243170D01*
X511681Y243070D01*
X511581Y242990D01*
X511471Y242930D01*
X511346Y242890D01*
X511221Y242880D01*
X511096Y242890D01*
X510971Y242930D01*
X510861Y242990D01*
X510761Y243070D01*
X510681Y243170D01*
X510621Y243280D01*
X510581Y243405D01*
X510571Y243530D01*
Y246960D01*
X510541Y246990D01*
X510441Y247130D01*
X510421Y247170D01*
X510406Y247205D01*
X510386Y247245D01*
X510371Y247285D01*
X510361Y247325D01*
X510346Y247370D01*
X510341Y247410D01*
X510331Y247450D01*
X510326Y247495D01*
Y247535D01*
X510321Y247580D01*
X510326Y247625D01*
Y247665D01*
X510331Y247710D01*
X510341Y247750D01*
X510346Y247790D01*
X510361Y247835D01*
X510371Y247875D01*
X510386Y247915D01*
X510406Y247955D01*
X510421Y247990D01*
X510441Y248030D01*
X510541Y248170D01*
X510571Y248200D01*
Y249330D01*
X510581Y249455D01*
X510621Y249580D01*
X510681Y249690D01*
X510761Y249790D01*
X510861Y249870D01*
X510971Y249930D01*
X511096Y249970D01*
X511221Y249980D01*
G37*
G36*
G01X515945D02*
X516070Y249970D01*
X516195Y249930D01*
X516305Y249870D01*
X516405Y249790D01*
X516485Y249690D01*
X516545Y249580D01*
X516585Y249455D01*
X516595Y249330D01*
Y248200D01*
X516625Y248170D01*
X516725Y248030D01*
X516745Y247990D01*
X516760Y247955D01*
X516780Y247915D01*
X516795Y247875D01*
X516805Y247835D01*
X516820Y247790D01*
X516825Y247750D01*
X516835Y247710D01*
X516840Y247665D01*
Y247625D01*
X516845Y247580D01*
X516840Y247535D01*
Y247495D01*
X516835Y247450D01*
X516825Y247410D01*
X516820Y247370D01*
X516805Y247325D01*
X516795Y247285D01*
X516780Y247245D01*
X516760Y247205D01*
X516745Y247170D01*
X516725Y247130D01*
X516625Y246990D01*
X516595Y246960D01*
Y243530D01*
X516585Y243405D01*
X516545Y243280D01*
X516485Y243170D01*
X516405Y243070D01*
X516305Y242990D01*
X516195Y242930D01*
X516070Y242890D01*
X515945Y242880D01*
X515820Y242890D01*
X515695Y242930D01*
X515585Y242990D01*
X515485Y243070D01*
X515405Y243170D01*
X515345Y243280D01*
X515305Y243405D01*
X515295Y243530D01*
Y246960D01*
X515265Y246990D01*
X515165Y247130D01*
X515145Y247170D01*
X515130Y247205D01*
X515110Y247245D01*
X515095Y247285D01*
X515085Y247325D01*
X515070Y247370D01*
X515065Y247410D01*
X515055Y247450D01*
X515050Y247495D01*
Y247535D01*
X515045Y247580D01*
X515050Y247625D01*
Y247665D01*
X515055Y247710D01*
X515065Y247750D01*
X515070Y247790D01*
X515085Y247835D01*
X515095Y247875D01*
X515110Y247915D01*
X515130Y247955D01*
X515145Y247990D01*
X515165Y248030D01*
X515265Y248170D01*
X515295Y248200D01*
Y249330D01*
X515305Y249455D01*
X515345Y249580D01*
X515405Y249690D01*
X515485Y249790D01*
X515585Y249870D01*
X515695Y249930D01*
X515820Y249970D01*
X515945Y249980D01*
G37*
G36*
G01X520670D02*
X520795Y249970D01*
X520920Y249930D01*
X521030Y249870D01*
X521130Y249790D01*
X521210Y249690D01*
X521270Y249580D01*
X521310Y249455D01*
X521320Y249330D01*
Y248200D01*
X521350Y248170D01*
X521450Y248030D01*
X521470Y247990D01*
X521485Y247955D01*
X521505Y247915D01*
X521520Y247875D01*
X521530Y247835D01*
X521545Y247790D01*
X521550Y247750D01*
X521560Y247710D01*
X521565Y247665D01*
Y247625D01*
X521570Y247580D01*
X521565Y247535D01*
Y247495D01*
X521560Y247450D01*
X521550Y247410D01*
X521545Y247370D01*
X521530Y247325D01*
X521520Y247285D01*
X521505Y247245D01*
X521485Y247205D01*
X521470Y247170D01*
X521450Y247130D01*
X521350Y246990D01*
X521320Y246960D01*
Y243530D01*
X521310Y243405D01*
X521270Y243280D01*
X521210Y243170D01*
X521130Y243070D01*
X521030Y242990D01*
X520920Y242930D01*
X520795Y242890D01*
X520670Y242880D01*
X520545Y242890D01*
X520420Y242930D01*
X520310Y242990D01*
X520210Y243070D01*
X520130Y243170D01*
X520070Y243280D01*
X520030Y243405D01*
X520020Y243530D01*
Y246960D01*
X519990Y246990D01*
X519890Y247130D01*
X519870Y247170D01*
X519855Y247205D01*
X519835Y247245D01*
X519820Y247285D01*
X519810Y247325D01*
X519795Y247370D01*
X519790Y247410D01*
X519780Y247450D01*
X519775Y247495D01*
Y247535D01*
X519770Y247580D01*
X519775Y247625D01*
Y247665D01*
X519780Y247710D01*
X519790Y247750D01*
X519795Y247790D01*
X519810Y247835D01*
X519820Y247875D01*
X519835Y247915D01*
X519855Y247955D01*
X519870Y247990D01*
X519890Y248030D01*
X519990Y248170D01*
X520020Y248200D01*
Y249330D01*
X520030Y249455D01*
X520070Y249580D01*
X520130Y249690D01*
X520210Y249790D01*
X520310Y249870D01*
X520420Y249930D01*
X520545Y249970D01*
X520670Y249980D01*
G37*
G36*
G01X525394D02*
X525519Y249970D01*
X525644Y249930D01*
X525754Y249870D01*
X525854Y249790D01*
X525934Y249690D01*
X525994Y249580D01*
X526034Y249455D01*
X526044Y249330D01*
Y248200D01*
X526074Y248170D01*
X526174Y248030D01*
X526194Y247990D01*
X526209Y247955D01*
X526229Y247915D01*
X526244Y247875D01*
X526254Y247835D01*
X526269Y247790D01*
X526274Y247750D01*
X526284Y247710D01*
X526289Y247665D01*
Y247625D01*
X526294Y247580D01*
X526289Y247535D01*
Y247495D01*
X526284Y247450D01*
X526274Y247410D01*
X526269Y247370D01*
X526254Y247325D01*
X526244Y247285D01*
X526229Y247245D01*
X526209Y247205D01*
X526194Y247170D01*
X526174Y247130D01*
X526074Y246990D01*
X526044Y246960D01*
Y243530D01*
X526034Y243405D01*
X525994Y243280D01*
X525934Y243170D01*
X525854Y243070D01*
X525754Y242990D01*
X525644Y242930D01*
X525519Y242890D01*
X525394Y242880D01*
X525269Y242890D01*
X525144Y242930D01*
X525034Y242990D01*
X524934Y243070D01*
X524854Y243170D01*
X524794Y243280D01*
X524754Y243405D01*
X524744Y243530D01*
Y246960D01*
X524714Y246990D01*
X524614Y247130D01*
X524594Y247170D01*
X524579Y247205D01*
X524559Y247245D01*
X524544Y247285D01*
X524534Y247325D01*
X524519Y247370D01*
X524514Y247410D01*
X524504Y247450D01*
X524499Y247495D01*
Y247535D01*
X524494Y247580D01*
X524499Y247625D01*
Y247665D01*
X524504Y247710D01*
X524514Y247750D01*
X524519Y247790D01*
X524534Y247835D01*
X524544Y247875D01*
X524559Y247915D01*
X524579Y247955D01*
X524594Y247990D01*
X524614Y248030D01*
X524714Y248170D01*
X524744Y248200D01*
Y249330D01*
X524754Y249455D01*
X524794Y249580D01*
X524854Y249690D01*
X524934Y249790D01*
X525034Y249870D01*
X525144Y249930D01*
X525269Y249970D01*
X525394Y249980D01*
G37*
G36*
G01X530118D02*
X530243Y249970D01*
X530368Y249930D01*
X530478Y249870D01*
X530578Y249790D01*
X530658Y249690D01*
X530718Y249580D01*
X530758Y249455D01*
X530768Y249330D01*
Y248200D01*
X530798Y248170D01*
X530898Y248030D01*
X530918Y247990D01*
X530933Y247955D01*
X530953Y247915D01*
X530968Y247875D01*
X530978Y247835D01*
X530993Y247790D01*
X530998Y247750D01*
X531008Y247710D01*
X531013Y247665D01*
Y247625D01*
X531018Y247580D01*
X531013Y247535D01*
Y247495D01*
X531008Y247450D01*
X530998Y247410D01*
X530993Y247370D01*
X530978Y247325D01*
X530968Y247285D01*
X530953Y247245D01*
X530933Y247205D01*
X530918Y247170D01*
X530898Y247130D01*
X530798Y246990D01*
X530768Y246960D01*
Y243530D01*
X530758Y243405D01*
X530718Y243280D01*
X530658Y243170D01*
X530578Y243070D01*
X530478Y242990D01*
X530368Y242930D01*
X530243Y242890D01*
X530118Y242880D01*
X529993Y242890D01*
X529868Y242930D01*
X529758Y242990D01*
X529658Y243070D01*
X529578Y243170D01*
X529518Y243280D01*
X529478Y243405D01*
X529468Y243530D01*
Y246960D01*
X529438Y246990D01*
X529338Y247130D01*
X529318Y247170D01*
X529303Y247205D01*
X529283Y247245D01*
X529268Y247285D01*
X529258Y247325D01*
X529243Y247370D01*
X529238Y247410D01*
X529228Y247450D01*
X529223Y247495D01*
Y247535D01*
X529218Y247580D01*
X529223Y247625D01*
Y247665D01*
X529228Y247710D01*
X529238Y247750D01*
X529243Y247790D01*
X529258Y247835D01*
X529268Y247875D01*
X529283Y247915D01*
X529303Y247955D01*
X529318Y247990D01*
X529338Y248030D01*
X529438Y248170D01*
X529468Y248200D01*
Y249330D01*
X529478Y249455D01*
X529518Y249580D01*
X529578Y249690D01*
X529658Y249790D01*
X529758Y249870D01*
X529868Y249930D01*
X529993Y249970D01*
X530118Y249980D01*
G37*
G36*
G01X534843D02*
X534968Y249970D01*
X535093Y249930D01*
X535203Y249870D01*
X535303Y249790D01*
X535383Y249690D01*
X535443Y249580D01*
X535483Y249455D01*
X535493Y249330D01*
Y248200D01*
X535523Y248170D01*
X535623Y248030D01*
X535643Y247990D01*
X535658Y247955D01*
X535678Y247915D01*
X535693Y247875D01*
X535703Y247835D01*
X535718Y247790D01*
X535723Y247750D01*
X535733Y247710D01*
X535738Y247665D01*
Y247625D01*
X535743Y247580D01*
X535738Y247535D01*
Y247495D01*
X535733Y247450D01*
X535723Y247410D01*
X535718Y247370D01*
X535703Y247325D01*
X535693Y247285D01*
X535678Y247245D01*
X535658Y247205D01*
X535643Y247170D01*
X535623Y247130D01*
X535523Y246990D01*
X535493Y246960D01*
Y243530D01*
X535483Y243405D01*
X535443Y243280D01*
X535383Y243170D01*
X535303Y243070D01*
X535203Y242990D01*
X535093Y242930D01*
X534968Y242890D01*
X534843Y242880D01*
X534718Y242890D01*
X534593Y242930D01*
X534483Y242990D01*
X534383Y243070D01*
X534303Y243170D01*
X534243Y243280D01*
X534203Y243405D01*
X534193Y243530D01*
Y246960D01*
X534163Y246990D01*
X534063Y247130D01*
X534043Y247170D01*
X534028Y247205D01*
X534008Y247245D01*
X533993Y247285D01*
X533983Y247325D01*
X533968Y247370D01*
X533963Y247410D01*
X533953Y247450D01*
X533948Y247495D01*
Y247535D01*
X533943Y247580D01*
X533948Y247625D01*
Y247665D01*
X533953Y247710D01*
X533963Y247750D01*
X533968Y247790D01*
X533983Y247835D01*
X533993Y247875D01*
X534008Y247915D01*
X534028Y247955D01*
X534043Y247990D01*
X534063Y248030D01*
X534163Y248170D01*
X534193Y248200D01*
Y249330D01*
X534203Y249455D01*
X534243Y249580D01*
X534303Y249690D01*
X534383Y249790D01*
X534483Y249870D01*
X534593Y249930D01*
X534718Y249970D01*
X534843Y249980D01*
G37*
G36*
G01X539567D02*
X539692Y249970D01*
X539817Y249930D01*
X539927Y249870D01*
X540027Y249790D01*
X540107Y249690D01*
X540167Y249580D01*
X540207Y249455D01*
X540217Y249330D01*
Y248200D01*
X540247Y248170D01*
X540347Y248030D01*
X540367Y247990D01*
X540382Y247955D01*
X540402Y247915D01*
X540417Y247875D01*
X540427Y247835D01*
X540442Y247790D01*
X540447Y247750D01*
X540457Y247710D01*
X540462Y247665D01*
Y247625D01*
X540467Y247580D01*
X540462Y247535D01*
Y247495D01*
X540457Y247450D01*
X540447Y247410D01*
X540442Y247370D01*
X540427Y247325D01*
X540417Y247285D01*
X540402Y247245D01*
X540382Y247205D01*
X540367Y247170D01*
X540347Y247130D01*
X540247Y246990D01*
X540217Y246960D01*
Y243530D01*
X540207Y243405D01*
X540167Y243280D01*
X540107Y243170D01*
X540027Y243070D01*
X539927Y242990D01*
X539817Y242930D01*
X539692Y242890D01*
X539567Y242880D01*
X539442Y242890D01*
X539317Y242930D01*
X539207Y242990D01*
X539107Y243070D01*
X539027Y243170D01*
X538967Y243280D01*
X538927Y243405D01*
X538917Y243530D01*
Y246960D01*
X538887Y246990D01*
X538787Y247130D01*
X538767Y247170D01*
X538752Y247205D01*
X538732Y247245D01*
X538717Y247285D01*
X538707Y247325D01*
X538692Y247370D01*
X538687Y247410D01*
X538677Y247450D01*
X538672Y247495D01*
Y247535D01*
X538667Y247580D01*
X538672Y247625D01*
Y247665D01*
X538677Y247710D01*
X538687Y247750D01*
X538692Y247790D01*
X538707Y247835D01*
X538717Y247875D01*
X538732Y247915D01*
X538752Y247955D01*
X538767Y247990D01*
X538787Y248030D01*
X538887Y248170D01*
X538917Y248200D01*
Y249330D01*
X538927Y249455D01*
X538967Y249580D01*
X539027Y249690D01*
X539107Y249790D01*
X539207Y249870D01*
X539317Y249930D01*
X539442Y249970D01*
X539567Y249980D01*
G37*
G36*
G01X544292D02*
X544417Y249970D01*
X544542Y249930D01*
X544652Y249870D01*
X544752Y249790D01*
X544832Y249690D01*
X544892Y249580D01*
X544932Y249455D01*
X544942Y249330D01*
Y248200D01*
X544972Y248170D01*
X545072Y248030D01*
X545092Y247990D01*
X545107Y247955D01*
X545127Y247915D01*
X545142Y247875D01*
X545152Y247835D01*
X545167Y247790D01*
X545172Y247750D01*
X545182Y247710D01*
X545187Y247665D01*
Y247625D01*
X545192Y247580D01*
X545187Y247535D01*
Y247495D01*
X545182Y247450D01*
X545172Y247410D01*
X545167Y247370D01*
X545152Y247325D01*
X545142Y247285D01*
X545127Y247245D01*
X545107Y247205D01*
X545092Y247170D01*
X545072Y247130D01*
X544972Y246990D01*
X544942Y246960D01*
Y243530D01*
X544932Y243405D01*
X544892Y243280D01*
X544832Y243170D01*
X544752Y243070D01*
X544652Y242990D01*
X544542Y242930D01*
X544417Y242890D01*
X544292Y242880D01*
X544167Y242890D01*
X544042Y242930D01*
X543932Y242990D01*
X543832Y243070D01*
X543752Y243170D01*
X543692Y243280D01*
X543652Y243405D01*
X543642Y243530D01*
Y246960D01*
X543612Y246990D01*
X543512Y247130D01*
X543492Y247170D01*
X543477Y247205D01*
X543457Y247245D01*
X543442Y247285D01*
X543432Y247325D01*
X543417Y247370D01*
X543412Y247410D01*
X543402Y247450D01*
X543397Y247495D01*
Y247535D01*
X543392Y247580D01*
X543397Y247625D01*
Y247665D01*
X543402Y247710D01*
X543412Y247750D01*
X543417Y247790D01*
X543432Y247835D01*
X543442Y247875D01*
X543457Y247915D01*
X543477Y247955D01*
X543492Y247990D01*
X543512Y248030D01*
X543612Y248170D01*
X543642Y248200D01*
Y249330D01*
X543652Y249455D01*
X543692Y249580D01*
X543752Y249690D01*
X543832Y249790D01*
X543932Y249870D01*
X544042Y249930D01*
X544167Y249970D01*
X544292Y249980D01*
G37*
G36*
G01X549016D02*
X549141Y249970D01*
X549266Y249930D01*
X549376Y249870D01*
X549476Y249790D01*
X549556Y249690D01*
X549616Y249580D01*
X549656Y249455D01*
X549666Y249330D01*
Y248200D01*
X549696Y248170D01*
X549796Y248030D01*
X549816Y247990D01*
X549831Y247955D01*
X549851Y247915D01*
X549866Y247875D01*
X549876Y247835D01*
X549891Y247790D01*
X549896Y247750D01*
X549906Y247710D01*
X549911Y247665D01*
Y247625D01*
X549916Y247580D01*
X549911Y247535D01*
Y247495D01*
X549906Y247450D01*
X549896Y247410D01*
X549891Y247370D01*
X549876Y247325D01*
X549866Y247285D01*
X549851Y247245D01*
X549831Y247205D01*
X549816Y247170D01*
X549796Y247130D01*
X549696Y246990D01*
X549666Y246960D01*
Y243530D01*
X549656Y243405D01*
X549616Y243280D01*
X549556Y243170D01*
X549476Y243070D01*
X549376Y242990D01*
X549266Y242930D01*
X549141Y242890D01*
X549016Y242880D01*
X548891Y242890D01*
X548766Y242930D01*
X548656Y242990D01*
X548556Y243070D01*
X548476Y243170D01*
X548416Y243280D01*
X548376Y243405D01*
X548366Y243530D01*
Y246960D01*
X548336Y246990D01*
X548236Y247130D01*
X548216Y247170D01*
X548201Y247205D01*
X548181Y247245D01*
X548166Y247285D01*
X548156Y247325D01*
X548141Y247370D01*
X548136Y247410D01*
X548126Y247450D01*
X548121Y247495D01*
Y247535D01*
X548116Y247580D01*
X548121Y247625D01*
Y247665D01*
X548126Y247710D01*
X548136Y247750D01*
X548141Y247790D01*
X548156Y247835D01*
X548166Y247875D01*
X548181Y247915D01*
X548201Y247955D01*
X548216Y247990D01*
X548236Y248030D01*
X548336Y248170D01*
X548366Y248200D01*
Y249330D01*
X548376Y249455D01*
X548416Y249580D01*
X548476Y249690D01*
X548556Y249790D01*
X548656Y249870D01*
X548766Y249930D01*
X548891Y249970D01*
X549016Y249980D01*
G37*
G36*
G01X553740D02*
X553865Y249970D01*
X553990Y249930D01*
X554100Y249870D01*
X554200Y249790D01*
X554280Y249690D01*
X554340Y249580D01*
X554380Y249455D01*
X554390Y249330D01*
Y248200D01*
X554420Y248170D01*
X554520Y248030D01*
X554540Y247990D01*
X554555Y247955D01*
X554575Y247915D01*
X554590Y247875D01*
X554600Y247835D01*
X554615Y247790D01*
X554620Y247750D01*
X554630Y247710D01*
X554635Y247665D01*
Y247625D01*
X554640Y247580D01*
X554635Y247535D01*
Y247495D01*
X554630Y247450D01*
X554620Y247410D01*
X554615Y247370D01*
X554600Y247325D01*
X554590Y247285D01*
X554575Y247245D01*
X554555Y247205D01*
X554540Y247170D01*
X554520Y247130D01*
X554420Y246990D01*
X554390Y246960D01*
Y243530D01*
X554380Y243405D01*
X554340Y243280D01*
X554280Y243170D01*
X554200Y243070D01*
X554100Y242990D01*
X553990Y242930D01*
X553865Y242890D01*
X553740Y242880D01*
X553615Y242890D01*
X553490Y242930D01*
X553380Y242990D01*
X553280Y243070D01*
X553200Y243170D01*
X553140Y243280D01*
X553100Y243405D01*
X553090Y243530D01*
Y246960D01*
X553060Y246990D01*
X552960Y247130D01*
X552940Y247170D01*
X552925Y247205D01*
X552905Y247245D01*
X552890Y247285D01*
X552880Y247325D01*
X552865Y247370D01*
X552860Y247410D01*
X552850Y247450D01*
X552845Y247495D01*
Y247535D01*
X552840Y247580D01*
X552845Y247625D01*
Y247665D01*
X552850Y247710D01*
X552860Y247750D01*
X552865Y247790D01*
X552880Y247835D01*
X552890Y247875D01*
X552905Y247915D01*
X552925Y247955D01*
X552940Y247990D01*
X552960Y248030D01*
X553060Y248170D01*
X553090Y248200D01*
Y249330D01*
X553100Y249455D01*
X553140Y249580D01*
X553200Y249690D01*
X553280Y249790D01*
X553380Y249870D01*
X553490Y249930D01*
X553615Y249970D01*
X553740Y249980D01*
G37*
G36*
G01X558465D02*
X558590Y249970D01*
X558715Y249930D01*
X558825Y249870D01*
X558925Y249790D01*
X559005Y249690D01*
X559065Y249580D01*
X559105Y249455D01*
X559115Y249330D01*
Y248200D01*
X559145Y248170D01*
X559245Y248030D01*
X559265Y247990D01*
X559280Y247955D01*
X559300Y247915D01*
X559315Y247875D01*
X559325Y247835D01*
X559340Y247790D01*
X559345Y247750D01*
X559355Y247710D01*
X559360Y247665D01*
Y247625D01*
X559365Y247580D01*
X559360Y247535D01*
Y247495D01*
X559355Y247450D01*
X559345Y247410D01*
X559340Y247370D01*
X559325Y247325D01*
X559315Y247285D01*
X559300Y247245D01*
X559280Y247205D01*
X559265Y247170D01*
X559245Y247130D01*
X559145Y246990D01*
X559115Y246960D01*
Y243530D01*
X559105Y243405D01*
X559065Y243280D01*
X559005Y243170D01*
X558925Y243070D01*
X558825Y242990D01*
X558715Y242930D01*
X558590Y242890D01*
X558465Y242880D01*
X558340Y242890D01*
X558215Y242930D01*
X558105Y242990D01*
X558005Y243070D01*
X557925Y243170D01*
X557865Y243280D01*
X557825Y243405D01*
X557815Y243530D01*
Y246960D01*
X557785Y246990D01*
X557685Y247130D01*
X557665Y247170D01*
X557650Y247205D01*
X557630Y247245D01*
X557615Y247285D01*
X557605Y247325D01*
X557590Y247370D01*
X557585Y247410D01*
X557575Y247450D01*
X557570Y247495D01*
Y247535D01*
X557565Y247580D01*
X557570Y247625D01*
Y247665D01*
X557575Y247710D01*
X557585Y247750D01*
X557590Y247790D01*
X557605Y247835D01*
X557615Y247875D01*
X557630Y247915D01*
X557650Y247955D01*
X557665Y247990D01*
X557685Y248030D01*
X557785Y248170D01*
X557815Y248200D01*
Y249330D01*
X557825Y249455D01*
X557865Y249580D01*
X557925Y249690D01*
X558005Y249790D01*
X558105Y249870D01*
X558215Y249930D01*
X558340Y249970D01*
X558465Y249980D01*
G37*
G36*
G01X563189D02*
X563314Y249970D01*
X563439Y249930D01*
X563549Y249870D01*
X563649Y249790D01*
X563729Y249690D01*
X563789Y249580D01*
X563829Y249455D01*
X563839Y249330D01*
Y248200D01*
X563869Y248170D01*
X563969Y248030D01*
X563989Y247990D01*
X564004Y247955D01*
X564024Y247915D01*
X564039Y247875D01*
X564049Y247835D01*
X564064Y247790D01*
X564069Y247750D01*
X564079Y247710D01*
X564084Y247665D01*
Y247625D01*
X564089Y247580D01*
X564084Y247535D01*
Y247495D01*
X564079Y247450D01*
X564069Y247410D01*
X564064Y247370D01*
X564049Y247325D01*
X564039Y247285D01*
X564024Y247245D01*
X564004Y247205D01*
X563989Y247170D01*
X563969Y247130D01*
X563869Y246990D01*
X563839Y246960D01*
Y243530D01*
X563829Y243405D01*
X563789Y243280D01*
X563729Y243170D01*
X563649Y243070D01*
X563549Y242990D01*
X563439Y242930D01*
X563314Y242890D01*
X563189Y242880D01*
X563064Y242890D01*
X562939Y242930D01*
X562829Y242990D01*
X562729Y243070D01*
X562649Y243170D01*
X562589Y243280D01*
X562549Y243405D01*
X562539Y243530D01*
Y246960D01*
X562509Y246990D01*
X562409Y247130D01*
X562389Y247170D01*
X562374Y247205D01*
X562354Y247245D01*
X562339Y247285D01*
X562329Y247325D01*
X562314Y247370D01*
X562309Y247410D01*
X562299Y247450D01*
X562294Y247495D01*
Y247535D01*
X562289Y247580D01*
X562294Y247625D01*
Y247665D01*
X562299Y247710D01*
X562309Y247750D01*
X562314Y247790D01*
X562329Y247835D01*
X562339Y247875D01*
X562354Y247915D01*
X562374Y247955D01*
X562389Y247990D01*
X562409Y248030D01*
X562509Y248170D01*
X562539Y248200D01*
Y249330D01*
X562549Y249455D01*
X562589Y249580D01*
X562649Y249690D01*
X562729Y249790D01*
X562829Y249870D01*
X562939Y249930D01*
X563064Y249970D01*
X563189Y249980D01*
G37*
G36*
G01X567914D02*
X568039Y249970D01*
X568164Y249930D01*
X568274Y249870D01*
X568374Y249790D01*
X568454Y249690D01*
X568514Y249580D01*
X568554Y249455D01*
X568564Y249330D01*
Y248200D01*
X568594Y248170D01*
X568694Y248030D01*
X568714Y247990D01*
X568729Y247955D01*
X568749Y247915D01*
X568764Y247875D01*
X568774Y247835D01*
X568789Y247790D01*
X568794Y247750D01*
X568804Y247710D01*
X568809Y247665D01*
Y247625D01*
X568814Y247580D01*
X568809Y247535D01*
Y247495D01*
X568804Y247450D01*
X568794Y247410D01*
X568789Y247370D01*
X568774Y247325D01*
X568764Y247285D01*
X568749Y247245D01*
X568729Y247205D01*
X568714Y247170D01*
X568694Y247130D01*
X568594Y246990D01*
X568564Y246960D01*
Y243530D01*
X568554Y243405D01*
X568514Y243280D01*
X568454Y243170D01*
X568374Y243070D01*
X568274Y242990D01*
X568164Y242930D01*
X568039Y242890D01*
X567914Y242880D01*
X567789Y242890D01*
X567664Y242930D01*
X567554Y242990D01*
X567454Y243070D01*
X567374Y243170D01*
X567314Y243280D01*
X567274Y243405D01*
X567264Y243530D01*
Y246960D01*
X567234Y246990D01*
X567134Y247130D01*
X567114Y247170D01*
X567099Y247205D01*
X567079Y247245D01*
X567064Y247285D01*
X567054Y247325D01*
X567039Y247370D01*
X567034Y247410D01*
X567024Y247450D01*
X567019Y247495D01*
Y247535D01*
X567014Y247580D01*
X567019Y247625D01*
Y247665D01*
X567024Y247710D01*
X567034Y247750D01*
X567039Y247790D01*
X567054Y247835D01*
X567064Y247875D01*
X567079Y247915D01*
X567099Y247955D01*
X567114Y247990D01*
X567134Y248030D01*
X567234Y248170D01*
X567264Y248200D01*
Y249330D01*
X567274Y249455D01*
X567314Y249580D01*
X567374Y249690D01*
X567454Y249790D01*
X567554Y249870D01*
X567664Y249930D01*
X567789Y249970D01*
X567914Y249980D01*
G37*
G36*
G01X572638D02*
X572763Y249970D01*
X572888Y249930D01*
X572998Y249870D01*
X573098Y249790D01*
X573178Y249690D01*
X573238Y249580D01*
X573278Y249455D01*
X573288Y249330D01*
Y248200D01*
X573318Y248170D01*
X573418Y248030D01*
X573438Y247990D01*
X573453Y247955D01*
X573473Y247915D01*
X573488Y247875D01*
X573498Y247835D01*
X573513Y247790D01*
X573518Y247750D01*
X573528Y247710D01*
X573533Y247665D01*
Y247625D01*
X573538Y247580D01*
X573533Y247535D01*
Y247495D01*
X573528Y247450D01*
X573518Y247410D01*
X573513Y247370D01*
X573498Y247325D01*
X573488Y247285D01*
X573473Y247245D01*
X573453Y247205D01*
X573438Y247170D01*
X573418Y247130D01*
X573318Y246990D01*
X573288Y246960D01*
Y243530D01*
X573278Y243405D01*
X573238Y243280D01*
X573178Y243170D01*
X573098Y243070D01*
X572998Y242990D01*
X572888Y242930D01*
X572763Y242890D01*
X572638Y242880D01*
X572513Y242890D01*
X572388Y242930D01*
X572278Y242990D01*
X572178Y243070D01*
X572098Y243170D01*
X572038Y243280D01*
X571998Y243405D01*
X571988Y243530D01*
Y246960D01*
X571958Y246990D01*
X571858Y247130D01*
X571838Y247170D01*
X571823Y247205D01*
X571803Y247245D01*
X571788Y247285D01*
X571778Y247325D01*
X571763Y247370D01*
X571758Y247410D01*
X571748Y247450D01*
X571743Y247495D01*
Y247535D01*
X571738Y247580D01*
X571743Y247625D01*
Y247665D01*
X571748Y247710D01*
X571758Y247750D01*
X571763Y247790D01*
X571778Y247835D01*
X571788Y247875D01*
X571803Y247915D01*
X571823Y247955D01*
X571838Y247990D01*
X571858Y248030D01*
X571958Y248170D01*
X571988Y248200D01*
Y249330D01*
X571998Y249455D01*
X572038Y249580D01*
X572098Y249690D01*
X572178Y249790D01*
X572278Y249870D01*
X572388Y249930D01*
X572513Y249970D01*
X572638Y249980D01*
G37*
G36*
G01X577362D02*
X577487Y249970D01*
X577612Y249930D01*
X577722Y249870D01*
X577822Y249790D01*
X577902Y249690D01*
X577962Y249580D01*
X578002Y249455D01*
X578012Y249330D01*
Y248200D01*
X578042Y248170D01*
X578142Y248030D01*
X578162Y247990D01*
X578177Y247955D01*
X578197Y247915D01*
X578212Y247875D01*
X578222Y247835D01*
X578237Y247790D01*
X578242Y247750D01*
X578252Y247710D01*
X578257Y247665D01*
Y247625D01*
X578262Y247580D01*
X578257Y247535D01*
Y247495D01*
X578252Y247450D01*
X578242Y247410D01*
X578237Y247370D01*
X578222Y247325D01*
X578212Y247285D01*
X578197Y247245D01*
X578177Y247205D01*
X578162Y247170D01*
X578142Y247130D01*
X578042Y246990D01*
X578012Y246960D01*
Y243530D01*
X578002Y243405D01*
X577962Y243280D01*
X577902Y243170D01*
X577822Y243070D01*
X577722Y242990D01*
X577612Y242930D01*
X577487Y242890D01*
X577362Y242880D01*
X577237Y242890D01*
X577112Y242930D01*
X577002Y242990D01*
X576902Y243070D01*
X576822Y243170D01*
X576762Y243280D01*
X576722Y243405D01*
X576712Y243530D01*
Y246960D01*
X576682Y246990D01*
X576582Y247130D01*
X576562Y247170D01*
X576547Y247205D01*
X576527Y247245D01*
X576512Y247285D01*
X576502Y247325D01*
X576487Y247370D01*
X576482Y247410D01*
X576472Y247450D01*
X576467Y247495D01*
Y247535D01*
X576462Y247580D01*
X576467Y247625D01*
Y247665D01*
X576472Y247710D01*
X576482Y247750D01*
X576487Y247790D01*
X576502Y247835D01*
X576512Y247875D01*
X576527Y247915D01*
X576547Y247955D01*
X576562Y247990D01*
X576582Y248030D01*
X576682Y248170D01*
X576712Y248200D01*
Y249330D01*
X576722Y249455D01*
X576762Y249580D01*
X576822Y249690D01*
X576902Y249790D01*
X577002Y249870D01*
X577112Y249930D01*
X577237Y249970D01*
X577362Y249980D01*
G37*
G36*
G01X582087D02*
X582212Y249970D01*
X582337Y249930D01*
X582447Y249870D01*
X582547Y249790D01*
X582627Y249690D01*
X582687Y249580D01*
X582727Y249455D01*
X582737Y249330D01*
Y248200D01*
X582767Y248170D01*
X582867Y248030D01*
X582887Y247990D01*
X582902Y247955D01*
X582922Y247915D01*
X582937Y247875D01*
X582947Y247835D01*
X582962Y247790D01*
X582967Y247750D01*
X582977Y247710D01*
X582982Y247665D01*
Y247625D01*
X582987Y247580D01*
X582982Y247535D01*
Y247495D01*
X582977Y247450D01*
X582967Y247410D01*
X582962Y247370D01*
X582947Y247325D01*
X582937Y247285D01*
X582922Y247245D01*
X582902Y247205D01*
X582887Y247170D01*
X582867Y247130D01*
X582767Y246990D01*
X582737Y246960D01*
Y243530D01*
X582727Y243405D01*
X582687Y243280D01*
X582627Y243170D01*
X582547Y243070D01*
X582447Y242990D01*
X582337Y242930D01*
X582212Y242890D01*
X582087Y242880D01*
X581962Y242890D01*
X581837Y242930D01*
X581727Y242990D01*
X581627Y243070D01*
X581547Y243170D01*
X581487Y243280D01*
X581447Y243405D01*
X581437Y243530D01*
Y246960D01*
X581407Y246990D01*
X581307Y247130D01*
X581287Y247170D01*
X581272Y247205D01*
X581252Y247245D01*
X581237Y247285D01*
X581227Y247325D01*
X581212Y247370D01*
X581207Y247410D01*
X581197Y247450D01*
X581192Y247495D01*
Y247535D01*
X581187Y247580D01*
X581192Y247625D01*
Y247665D01*
X581197Y247710D01*
X581207Y247750D01*
X581212Y247790D01*
X581227Y247835D01*
X581237Y247875D01*
X581252Y247915D01*
X581272Y247955D01*
X581287Y247990D01*
X581307Y248030D01*
X581407Y248170D01*
X581437Y248200D01*
Y249330D01*
X581447Y249455D01*
X581487Y249580D01*
X581547Y249690D01*
X581627Y249790D01*
X581727Y249870D01*
X581837Y249930D01*
X581962Y249970D01*
X582087Y249980D01*
G37*
G36*
G01X586811D02*
X586936Y249970D01*
X587061Y249930D01*
X587171Y249870D01*
X587271Y249790D01*
X587351Y249690D01*
X587411Y249580D01*
X587451Y249455D01*
X587461Y249330D01*
Y248200D01*
X587491Y248170D01*
X587591Y248030D01*
X587611Y247990D01*
X587626Y247955D01*
X587646Y247915D01*
X587661Y247875D01*
X587671Y247835D01*
X587686Y247790D01*
X587691Y247750D01*
X587701Y247710D01*
X587706Y247665D01*
Y247625D01*
X587711Y247580D01*
X587706Y247535D01*
Y247495D01*
X587701Y247450D01*
X587691Y247410D01*
X587686Y247370D01*
X587671Y247325D01*
X587661Y247285D01*
X587646Y247245D01*
X587626Y247205D01*
X587611Y247170D01*
X587591Y247130D01*
X587491Y246990D01*
X587461Y246960D01*
Y243530D01*
X587451Y243405D01*
X587411Y243280D01*
X587351Y243170D01*
X587271Y243070D01*
X587171Y242990D01*
X587061Y242930D01*
X586936Y242890D01*
X586811Y242880D01*
X586686Y242890D01*
X586561Y242930D01*
X586451Y242990D01*
X586351Y243070D01*
X586271Y243170D01*
X586211Y243280D01*
X586171Y243405D01*
X586161Y243530D01*
Y246960D01*
X586131Y246990D01*
X586031Y247130D01*
X586011Y247170D01*
X585996Y247205D01*
X585976Y247245D01*
X585961Y247285D01*
X585951Y247325D01*
X585936Y247370D01*
X585931Y247410D01*
X585921Y247450D01*
X585916Y247495D01*
Y247535D01*
X585911Y247580D01*
X585916Y247625D01*
Y247665D01*
X585921Y247710D01*
X585931Y247750D01*
X585936Y247790D01*
X585951Y247835D01*
X585961Y247875D01*
X585976Y247915D01*
X585996Y247955D01*
X586011Y247990D01*
X586031Y248030D01*
X586131Y248170D01*
X586161Y248200D01*
Y249330D01*
X586171Y249455D01*
X586211Y249580D01*
X586271Y249690D01*
X586351Y249790D01*
X586451Y249870D01*
X586561Y249930D01*
X586686Y249970D01*
X586811Y249980D01*
G37*
G36*
G01X591536D02*
X591661Y249970D01*
X591786Y249930D01*
X591896Y249870D01*
X591996Y249790D01*
X592076Y249690D01*
X592136Y249580D01*
X592176Y249455D01*
X592186Y249330D01*
Y248200D01*
X592216Y248170D01*
X592316Y248030D01*
X592336Y247990D01*
X592351Y247955D01*
X592371Y247915D01*
X592386Y247875D01*
X592396Y247835D01*
X592411Y247790D01*
X592416Y247750D01*
X592426Y247710D01*
X592431Y247665D01*
Y247625D01*
X592436Y247580D01*
X592431Y247535D01*
Y247495D01*
X592426Y247450D01*
X592416Y247410D01*
X592411Y247370D01*
X592396Y247325D01*
X592386Y247285D01*
X592371Y247245D01*
X592351Y247205D01*
X592336Y247170D01*
X592316Y247130D01*
X592216Y246990D01*
X592186Y246960D01*
Y243530D01*
X592176Y243405D01*
X592136Y243280D01*
X592076Y243170D01*
X591996Y243070D01*
X591896Y242990D01*
X591786Y242930D01*
X591661Y242890D01*
X591536Y242880D01*
X591411Y242890D01*
X591286Y242930D01*
X591176Y242990D01*
X591076Y243070D01*
X590996Y243170D01*
X590936Y243280D01*
X590896Y243405D01*
X590886Y243530D01*
Y246960D01*
X590856Y246990D01*
X590756Y247130D01*
X590736Y247170D01*
X590721Y247205D01*
X590701Y247245D01*
X590686Y247285D01*
X590676Y247325D01*
X590661Y247370D01*
X590656Y247410D01*
X590646Y247450D01*
X590641Y247495D01*
Y247535D01*
X590636Y247580D01*
X590641Y247625D01*
Y247665D01*
X590646Y247710D01*
X590656Y247750D01*
X590661Y247790D01*
X590676Y247835D01*
X590686Y247875D01*
X590701Y247915D01*
X590721Y247955D01*
X590736Y247990D01*
X590756Y248030D01*
X590856Y248170D01*
X590886Y248200D01*
Y249330D01*
X590896Y249455D01*
X590936Y249580D01*
X590996Y249690D01*
X591076Y249790D01*
X591176Y249870D01*
X591286Y249930D01*
X591411Y249970D01*
X591536Y249980D01*
G37*
G36*
G01X596260D02*
X596385Y249970D01*
X596510Y249930D01*
X596620Y249870D01*
X596720Y249790D01*
X596800Y249690D01*
X596860Y249580D01*
X596900Y249455D01*
X596910Y249330D01*
Y248200D01*
X596940Y248170D01*
X597040Y248030D01*
X597060Y247990D01*
X597075Y247955D01*
X597095Y247915D01*
X597110Y247875D01*
X597120Y247835D01*
X597135Y247790D01*
X597140Y247750D01*
X597150Y247710D01*
X597155Y247665D01*
Y247625D01*
X597160Y247580D01*
X597155Y247535D01*
Y247495D01*
X597150Y247450D01*
X597140Y247410D01*
X597135Y247370D01*
X597120Y247325D01*
X597110Y247285D01*
X597095Y247245D01*
X597075Y247205D01*
X597060Y247170D01*
X597040Y247130D01*
X596940Y246990D01*
X596910Y246960D01*
Y243530D01*
X596900Y243405D01*
X596860Y243280D01*
X596800Y243170D01*
X596720Y243070D01*
X596620Y242990D01*
X596510Y242930D01*
X596385Y242890D01*
X596260Y242880D01*
X596135Y242890D01*
X596010Y242930D01*
X595900Y242990D01*
X595800Y243070D01*
X595720Y243170D01*
X595660Y243280D01*
X595620Y243405D01*
X595610Y243530D01*
Y246960D01*
X595580Y246990D01*
X595480Y247130D01*
X595460Y247170D01*
X595445Y247205D01*
X595425Y247245D01*
X595410Y247285D01*
X595400Y247325D01*
X595385Y247370D01*
X595380Y247410D01*
X595370Y247450D01*
X595365Y247495D01*
Y247535D01*
X595360Y247580D01*
X595365Y247625D01*
Y247665D01*
X595370Y247710D01*
X595380Y247750D01*
X595385Y247790D01*
X595400Y247835D01*
X595410Y247875D01*
X595425Y247915D01*
X595445Y247955D01*
X595460Y247990D01*
X595480Y248030D01*
X595580Y248170D01*
X595610Y248200D01*
Y249330D01*
X595620Y249455D01*
X595660Y249580D01*
X595720Y249690D01*
X595800Y249790D01*
X595900Y249870D01*
X596010Y249930D01*
X596135Y249970D01*
X596260Y249980D01*
G37*
G36*
G01X600985D02*
X601110Y249970D01*
X601235Y249930D01*
X601345Y249870D01*
X601445Y249790D01*
X601525Y249690D01*
X601585Y249580D01*
X601625Y249455D01*
X601635Y249330D01*
Y248200D01*
X601665Y248170D01*
X601765Y248030D01*
X601785Y247990D01*
X601800Y247955D01*
X601820Y247915D01*
X601835Y247875D01*
X601845Y247835D01*
X601860Y247790D01*
X601865Y247750D01*
X601875Y247710D01*
X601880Y247665D01*
Y247625D01*
X601885Y247580D01*
X601880Y247535D01*
Y247495D01*
X601875Y247450D01*
X601865Y247410D01*
X601860Y247370D01*
X601845Y247325D01*
X601835Y247285D01*
X601820Y247245D01*
X601800Y247205D01*
X601785Y247170D01*
X601765Y247130D01*
X601665Y246990D01*
X601635Y246960D01*
Y243530D01*
X601625Y243405D01*
X601585Y243280D01*
X601525Y243170D01*
X601445Y243070D01*
X601345Y242990D01*
X601235Y242930D01*
X601110Y242890D01*
X600985Y242880D01*
X600860Y242890D01*
X600735Y242930D01*
X600625Y242990D01*
X600525Y243070D01*
X600445Y243170D01*
X600385Y243280D01*
X600345Y243405D01*
X600335Y243530D01*
Y246960D01*
X600305Y246990D01*
X600205Y247130D01*
X600185Y247170D01*
X600170Y247205D01*
X600150Y247245D01*
X600135Y247285D01*
X600125Y247325D01*
X600110Y247370D01*
X600105Y247410D01*
X600095Y247450D01*
X600090Y247495D01*
Y247535D01*
X600085Y247580D01*
X600090Y247625D01*
Y247665D01*
X600095Y247710D01*
X600105Y247750D01*
X600110Y247790D01*
X600125Y247835D01*
X600135Y247875D01*
X600150Y247915D01*
X600170Y247955D01*
X600185Y247990D01*
X600205Y248030D01*
X600305Y248170D01*
X600335Y248200D01*
Y249330D01*
X600345Y249455D01*
X600385Y249580D01*
X600445Y249690D01*
X600525Y249790D01*
X600625Y249870D01*
X600735Y249930D01*
X600860Y249970D01*
X600985Y249980D01*
G37*
G36*
G01X605709D02*
X605834Y249970D01*
X605959Y249930D01*
X606069Y249870D01*
X606169Y249790D01*
X606249Y249690D01*
X606309Y249580D01*
X606349Y249455D01*
X606359Y249330D01*
Y248200D01*
X606389Y248170D01*
X606489Y248030D01*
X606509Y247990D01*
X606524Y247955D01*
X606544Y247915D01*
X606559Y247875D01*
X606569Y247835D01*
X606584Y247790D01*
X606589Y247750D01*
X606599Y247710D01*
X606604Y247665D01*
Y247625D01*
X606609Y247580D01*
X606604Y247535D01*
Y247495D01*
X606599Y247450D01*
X606589Y247410D01*
X606584Y247370D01*
X606569Y247325D01*
X606559Y247285D01*
X606544Y247245D01*
X606524Y247205D01*
X606509Y247170D01*
X606489Y247130D01*
X606389Y246990D01*
X606359Y246960D01*
Y243530D01*
X606349Y243405D01*
X606309Y243280D01*
X606249Y243170D01*
X606169Y243070D01*
X606069Y242990D01*
X605959Y242930D01*
X605834Y242890D01*
X605709Y242880D01*
X605584Y242890D01*
X605459Y242930D01*
X605349Y242990D01*
X605249Y243070D01*
X605169Y243170D01*
X605109Y243280D01*
X605069Y243405D01*
X605059Y243530D01*
Y246960D01*
X605029Y246990D01*
X604929Y247130D01*
X604909Y247170D01*
X604894Y247205D01*
X604874Y247245D01*
X604859Y247285D01*
X604849Y247325D01*
X604834Y247370D01*
X604829Y247410D01*
X604819Y247450D01*
X604814Y247495D01*
Y247535D01*
X604809Y247580D01*
X604814Y247625D01*
Y247665D01*
X604819Y247710D01*
X604829Y247750D01*
X604834Y247790D01*
X604849Y247835D01*
X604859Y247875D01*
X604874Y247915D01*
X604894Y247955D01*
X604909Y247990D01*
X604929Y248030D01*
X605029Y248170D01*
X605059Y248200D01*
Y249330D01*
X605069Y249455D01*
X605109Y249580D01*
X605169Y249690D01*
X605249Y249790D01*
X605349Y249870D01*
X605459Y249930D01*
X605584Y249970D01*
X605709Y249980D01*
G37*
G36*
G01X610433D02*
X610558Y249970D01*
X610683Y249930D01*
X610793Y249870D01*
X610893Y249790D01*
X610973Y249690D01*
X611033Y249580D01*
X611073Y249455D01*
X611083Y249330D01*
Y248200D01*
X611113Y248170D01*
X611213Y248030D01*
X611233Y247990D01*
X611248Y247955D01*
X611268Y247915D01*
X611283Y247875D01*
X611293Y247835D01*
X611308Y247790D01*
X611313Y247750D01*
X611323Y247710D01*
X611328Y247665D01*
Y247625D01*
X611333Y247580D01*
X611328Y247535D01*
Y247495D01*
X611323Y247450D01*
X611313Y247410D01*
X611308Y247370D01*
X611293Y247325D01*
X611283Y247285D01*
X611268Y247245D01*
X611248Y247205D01*
X611233Y247170D01*
X611213Y247130D01*
X611113Y246990D01*
X611083Y246960D01*
Y243530D01*
X611073Y243405D01*
X611033Y243280D01*
X610973Y243170D01*
X610893Y243070D01*
X610793Y242990D01*
X610683Y242930D01*
X610558Y242890D01*
X610433Y242880D01*
X610308Y242890D01*
X610183Y242930D01*
X610073Y242990D01*
X609973Y243070D01*
X609893Y243170D01*
X609833Y243280D01*
X609793Y243405D01*
X609783Y243530D01*
Y246960D01*
X609753Y246990D01*
X609653Y247130D01*
X609633Y247170D01*
X609618Y247205D01*
X609598Y247245D01*
X609583Y247285D01*
X609573Y247325D01*
X609558Y247370D01*
X609553Y247410D01*
X609543Y247450D01*
X609538Y247495D01*
Y247535D01*
X609533Y247580D01*
X609538Y247625D01*
Y247665D01*
X609543Y247710D01*
X609553Y247750D01*
X609558Y247790D01*
X609573Y247835D01*
X609583Y247875D01*
X609598Y247915D01*
X609618Y247955D01*
X609633Y247990D01*
X609653Y248030D01*
X609753Y248170D01*
X609783Y248200D01*
Y249330D01*
X609793Y249455D01*
X609833Y249580D01*
X609893Y249690D01*
X609973Y249790D01*
X610073Y249870D01*
X610183Y249930D01*
X610308Y249970D01*
X610433Y249980D01*
G37*
G36*
G01X615158D02*
X615283Y249970D01*
X615408Y249930D01*
X615518Y249870D01*
X615618Y249790D01*
X615698Y249690D01*
X615758Y249580D01*
X615798Y249455D01*
X615808Y249330D01*
Y248200D01*
X615838Y248170D01*
X615938Y248030D01*
X615958Y247990D01*
X615973Y247955D01*
X615993Y247915D01*
X616008Y247875D01*
X616018Y247835D01*
X616033Y247790D01*
X616038Y247750D01*
X616048Y247710D01*
X616053Y247665D01*
Y247625D01*
X616058Y247580D01*
X616053Y247535D01*
Y247495D01*
X616048Y247450D01*
X616038Y247410D01*
X616033Y247370D01*
X616018Y247325D01*
X616008Y247285D01*
X615993Y247245D01*
X615973Y247205D01*
X615958Y247170D01*
X615938Y247130D01*
X615838Y246990D01*
X615808Y246960D01*
Y243530D01*
X615798Y243405D01*
X615758Y243280D01*
X615698Y243170D01*
X615618Y243070D01*
X615518Y242990D01*
X615408Y242930D01*
X615283Y242890D01*
X615158Y242880D01*
X615033Y242890D01*
X614908Y242930D01*
X614798Y242990D01*
X614698Y243070D01*
X614618Y243170D01*
X614558Y243280D01*
X614518Y243405D01*
X614508Y243530D01*
Y246960D01*
X614478Y246990D01*
X614378Y247130D01*
X614358Y247170D01*
X614343Y247205D01*
X614323Y247245D01*
X614308Y247285D01*
X614298Y247325D01*
X614283Y247370D01*
X614278Y247410D01*
X614268Y247450D01*
X614263Y247495D01*
Y247535D01*
X614258Y247580D01*
X614263Y247625D01*
Y247665D01*
X614268Y247710D01*
X614278Y247750D01*
X614283Y247790D01*
X614298Y247835D01*
X614308Y247875D01*
X614323Y247915D01*
X614343Y247955D01*
X614358Y247990D01*
X614378Y248030D01*
X614478Y248170D01*
X614508Y248200D01*
Y249330D01*
X614518Y249455D01*
X614558Y249580D01*
X614618Y249690D01*
X614698Y249790D01*
X614798Y249870D01*
X614908Y249930D01*
X615033Y249970D01*
X615158Y249980D01*
G37*
G36*
G01X619882D02*
X620007Y249970D01*
X620132Y249930D01*
X620242Y249870D01*
X620342Y249790D01*
X620422Y249690D01*
X620482Y249580D01*
X620522Y249455D01*
X620532Y249330D01*
Y248200D01*
X620562Y248170D01*
X620662Y248030D01*
X620682Y247990D01*
X620697Y247955D01*
X620717Y247915D01*
X620732Y247875D01*
X620742Y247835D01*
X620757Y247790D01*
X620762Y247750D01*
X620772Y247710D01*
X620777Y247665D01*
Y247625D01*
X620782Y247580D01*
X620777Y247535D01*
Y247495D01*
X620772Y247450D01*
X620762Y247410D01*
X620757Y247370D01*
X620742Y247325D01*
X620732Y247285D01*
X620717Y247245D01*
X620697Y247205D01*
X620682Y247170D01*
X620662Y247130D01*
X620562Y246990D01*
X620532Y246960D01*
Y243530D01*
X620522Y243405D01*
X620482Y243280D01*
X620422Y243170D01*
X620342Y243070D01*
X620242Y242990D01*
X620132Y242930D01*
X620007Y242890D01*
X619882Y242880D01*
X619757Y242890D01*
X619632Y242930D01*
X619522Y242990D01*
X619422Y243070D01*
X619342Y243170D01*
X619282Y243280D01*
X619242Y243405D01*
X619232Y243530D01*
Y246960D01*
X619202Y246990D01*
X619102Y247130D01*
X619082Y247170D01*
X619067Y247205D01*
X619047Y247245D01*
X619032Y247285D01*
X619022Y247325D01*
X619007Y247370D01*
X619002Y247410D01*
X618992Y247450D01*
X618987Y247495D01*
Y247535D01*
X618982Y247580D01*
X618987Y247625D01*
Y247665D01*
X618992Y247710D01*
X619002Y247750D01*
X619007Y247790D01*
X619022Y247835D01*
X619032Y247875D01*
X619047Y247915D01*
X619067Y247955D01*
X619082Y247990D01*
X619102Y248030D01*
X619202Y248170D01*
X619232Y248200D01*
Y249330D01*
X619242Y249455D01*
X619282Y249580D01*
X619342Y249690D01*
X619422Y249790D01*
X619522Y249870D01*
X619632Y249930D01*
X619757Y249970D01*
X619882Y249980D01*
G37*
G36*
G01X624607D02*
X624732Y249970D01*
X624857Y249930D01*
X624967Y249870D01*
X625067Y249790D01*
X625147Y249690D01*
X625207Y249580D01*
X625247Y249455D01*
X625257Y249330D01*
Y248200D01*
X625287Y248170D01*
X625387Y248030D01*
X625407Y247990D01*
X625422Y247955D01*
X625442Y247915D01*
X625457Y247875D01*
X625467Y247835D01*
X625482Y247790D01*
X625487Y247750D01*
X625497Y247710D01*
X625502Y247665D01*
Y247625D01*
X625507Y247580D01*
X625502Y247535D01*
Y247495D01*
X625497Y247450D01*
X625487Y247410D01*
X625482Y247370D01*
X625467Y247325D01*
X625457Y247285D01*
X625442Y247245D01*
X625422Y247205D01*
X625407Y247170D01*
X625387Y247130D01*
X625287Y246990D01*
X625257Y246960D01*
Y243530D01*
X625247Y243405D01*
X625207Y243280D01*
X625147Y243170D01*
X625067Y243070D01*
X624967Y242990D01*
X624857Y242930D01*
X624732Y242890D01*
X624607Y242880D01*
X624482Y242890D01*
X624357Y242930D01*
X624247Y242990D01*
X624147Y243070D01*
X624067Y243170D01*
X624007Y243280D01*
X623967Y243405D01*
X623957Y243530D01*
Y246960D01*
X623927Y246990D01*
X623827Y247130D01*
X623807Y247170D01*
X623792Y247205D01*
X623772Y247245D01*
X623757Y247285D01*
X623747Y247325D01*
X623732Y247370D01*
X623727Y247410D01*
X623717Y247450D01*
X623712Y247495D01*
Y247535D01*
X623707Y247580D01*
X623712Y247625D01*
Y247665D01*
X623717Y247710D01*
X623727Y247750D01*
X623732Y247790D01*
X623747Y247835D01*
X623757Y247875D01*
X623772Y247915D01*
X623792Y247955D01*
X623807Y247990D01*
X623827Y248030D01*
X623927Y248170D01*
X623957Y248200D01*
Y249330D01*
X623967Y249455D01*
X624007Y249580D01*
X624067Y249690D01*
X624147Y249790D01*
X624247Y249870D01*
X624357Y249930D01*
X624482Y249970D01*
X624607Y249980D01*
G37*
G36*
G01X629331D02*
X629456Y249970D01*
X629581Y249930D01*
X629691Y249870D01*
X629791Y249790D01*
X629871Y249690D01*
X629931Y249580D01*
X629971Y249455D01*
X629981Y249330D01*
Y248200D01*
X630011Y248170D01*
X630111Y248030D01*
X630131Y247990D01*
X630146Y247955D01*
X630166Y247915D01*
X630181Y247875D01*
X630191Y247835D01*
X630206Y247790D01*
X630211Y247750D01*
X630221Y247710D01*
X630226Y247665D01*
Y247625D01*
X630231Y247580D01*
X630226Y247535D01*
Y247495D01*
X630221Y247450D01*
X630211Y247410D01*
X630206Y247370D01*
X630191Y247325D01*
X630181Y247285D01*
X630166Y247245D01*
X630146Y247205D01*
X630131Y247170D01*
X630111Y247130D01*
X630011Y246990D01*
X629981Y246960D01*
Y243530D01*
X629971Y243405D01*
X629931Y243280D01*
X629871Y243170D01*
X629791Y243070D01*
X629691Y242990D01*
X629581Y242930D01*
X629456Y242890D01*
X629331Y242880D01*
X629206Y242890D01*
X629081Y242930D01*
X628971Y242990D01*
X628871Y243070D01*
X628791Y243170D01*
X628731Y243280D01*
X628691Y243405D01*
X628681Y243530D01*
Y246960D01*
X628651Y246990D01*
X628551Y247130D01*
X628531Y247170D01*
X628516Y247205D01*
X628496Y247245D01*
X628481Y247285D01*
X628471Y247325D01*
X628456Y247370D01*
X628451Y247410D01*
X628441Y247450D01*
X628436Y247495D01*
Y247535D01*
X628431Y247580D01*
X628436Y247625D01*
Y247665D01*
X628441Y247710D01*
X628451Y247750D01*
X628456Y247790D01*
X628471Y247835D01*
X628481Y247875D01*
X628496Y247915D01*
X628516Y247955D01*
X628531Y247990D01*
X628551Y248030D01*
X628651Y248170D01*
X628681Y248200D01*
Y249330D01*
X628691Y249455D01*
X628731Y249580D01*
X628791Y249690D01*
X628871Y249790D01*
X628971Y249870D01*
X629081Y249930D01*
X629206Y249970D01*
X629331Y249980D01*
G37*
G36*
G01X634055D02*
X634180Y249970D01*
X634305Y249930D01*
X634415Y249870D01*
X634515Y249790D01*
X634595Y249690D01*
X634655Y249580D01*
X634695Y249455D01*
X634705Y249330D01*
Y248200D01*
X634735Y248170D01*
X634835Y248030D01*
X634855Y247990D01*
X634870Y247955D01*
X634890Y247915D01*
X634905Y247875D01*
X634915Y247835D01*
X634930Y247790D01*
X634935Y247750D01*
X634945Y247710D01*
X634950Y247665D01*
Y247625D01*
X634955Y247580D01*
X634950Y247535D01*
Y247495D01*
X634945Y247450D01*
X634935Y247410D01*
X634930Y247370D01*
X634915Y247325D01*
X634905Y247285D01*
X634890Y247245D01*
X634870Y247205D01*
X634855Y247170D01*
X634835Y247130D01*
X634735Y246990D01*
X634705Y246960D01*
Y243530D01*
X634695Y243405D01*
X634655Y243280D01*
X634595Y243170D01*
X634515Y243070D01*
X634415Y242990D01*
X634305Y242930D01*
X634180Y242890D01*
X634055Y242880D01*
X633930Y242890D01*
X633805Y242930D01*
X633695Y242990D01*
X633595Y243070D01*
X633515Y243170D01*
X633455Y243280D01*
X633415Y243405D01*
X633405Y243530D01*
Y246960D01*
X633375Y246990D01*
X633275Y247130D01*
X633255Y247170D01*
X633240Y247205D01*
X633220Y247245D01*
X633205Y247285D01*
X633195Y247325D01*
X633180Y247370D01*
X633175Y247410D01*
X633165Y247450D01*
X633160Y247495D01*
Y247535D01*
X633155Y247580D01*
X633160Y247625D01*
Y247665D01*
X633165Y247710D01*
X633175Y247750D01*
X633180Y247790D01*
X633195Y247835D01*
X633205Y247875D01*
X633220Y247915D01*
X633240Y247955D01*
X633255Y247990D01*
X633275Y248030D01*
X633375Y248170D01*
X633405Y248200D01*
Y249330D01*
X633415Y249455D01*
X633455Y249580D01*
X633515Y249690D01*
X633595Y249790D01*
X633695Y249870D01*
X633805Y249930D01*
X633930Y249970D01*
X634055Y249980D01*
G37*
G36*
G01X638780D02*
X638905Y249970D01*
X639030Y249930D01*
X639140Y249870D01*
X639240Y249790D01*
X639320Y249690D01*
X639380Y249580D01*
X639420Y249455D01*
X639430Y249330D01*
Y248200D01*
X639460Y248170D01*
X639560Y248030D01*
X639580Y247990D01*
X639595Y247955D01*
X639615Y247915D01*
X639630Y247875D01*
X639640Y247835D01*
X639655Y247790D01*
X639660Y247750D01*
X639670Y247710D01*
X639675Y247665D01*
Y247625D01*
X639680Y247580D01*
X639675Y247535D01*
Y247495D01*
X639670Y247450D01*
X639660Y247410D01*
X639655Y247370D01*
X639640Y247325D01*
X639630Y247285D01*
X639615Y247245D01*
X639595Y247205D01*
X639580Y247170D01*
X639560Y247130D01*
X639460Y246990D01*
X639430Y246960D01*
Y243530D01*
X639420Y243405D01*
X639380Y243280D01*
X639320Y243170D01*
X639240Y243070D01*
X639140Y242990D01*
X639030Y242930D01*
X638905Y242890D01*
X638780Y242880D01*
X638655Y242890D01*
X638530Y242930D01*
X638420Y242990D01*
X638320Y243070D01*
X638240Y243170D01*
X638180Y243280D01*
X638140Y243405D01*
X638130Y243530D01*
Y246960D01*
X638100Y246990D01*
X638000Y247130D01*
X637980Y247170D01*
X637965Y247205D01*
X637945Y247245D01*
X637930Y247285D01*
X637920Y247325D01*
X637905Y247370D01*
X637900Y247410D01*
X637890Y247450D01*
X637885Y247495D01*
Y247535D01*
X637880Y247580D01*
X637885Y247625D01*
Y247665D01*
X637890Y247710D01*
X637900Y247750D01*
X637905Y247790D01*
X637920Y247835D01*
X637930Y247875D01*
X637945Y247915D01*
X637965Y247955D01*
X637980Y247990D01*
X638000Y248030D01*
X638100Y248170D01*
X638130Y248200D01*
Y249330D01*
X638140Y249455D01*
X638180Y249580D01*
X638240Y249690D01*
X638320Y249790D01*
X638420Y249870D01*
X638530Y249930D01*
X638655Y249970D01*
X638780Y249980D01*
G37*
G36*
G01X643504D02*
X643629Y249970D01*
X643754Y249930D01*
X643864Y249870D01*
X643964Y249790D01*
X644044Y249690D01*
X644104Y249580D01*
X644144Y249455D01*
X644154Y249330D01*
Y248200D01*
X644184Y248170D01*
X644284Y248030D01*
X644304Y247990D01*
X644319Y247955D01*
X644339Y247915D01*
X644354Y247875D01*
X644364Y247835D01*
X644379Y247790D01*
X644384Y247750D01*
X644394Y247710D01*
X644399Y247665D01*
Y247625D01*
X644404Y247580D01*
X644399Y247535D01*
Y247495D01*
X644394Y247450D01*
X644384Y247410D01*
X644379Y247370D01*
X644364Y247325D01*
X644354Y247285D01*
X644339Y247245D01*
X644319Y247205D01*
X644304Y247170D01*
X644284Y247130D01*
X644184Y246990D01*
X644154Y246960D01*
Y243530D01*
X644144Y243405D01*
X644104Y243280D01*
X644044Y243170D01*
X643964Y243070D01*
X643864Y242990D01*
X643754Y242930D01*
X643629Y242890D01*
X643504Y242880D01*
X643379Y242890D01*
X643254Y242930D01*
X643144Y242990D01*
X643044Y243070D01*
X642964Y243170D01*
X642904Y243280D01*
X642864Y243405D01*
X642854Y243530D01*
Y246960D01*
X642824Y246990D01*
X642724Y247130D01*
X642704Y247170D01*
X642689Y247205D01*
X642669Y247245D01*
X642654Y247285D01*
X642644Y247325D01*
X642629Y247370D01*
X642624Y247410D01*
X642614Y247450D01*
X642609Y247495D01*
Y247535D01*
X642604Y247580D01*
X642609Y247625D01*
Y247665D01*
X642614Y247710D01*
X642624Y247750D01*
X642629Y247790D01*
X642644Y247835D01*
X642654Y247875D01*
X642669Y247915D01*
X642689Y247955D01*
X642704Y247990D01*
X642724Y248030D01*
X642824Y248170D01*
X642854Y248200D01*
Y249330D01*
X642864Y249455D01*
X642904Y249580D01*
X642964Y249690D01*
X643044Y249790D01*
X643144Y249870D01*
X643254Y249930D01*
X643379Y249970D01*
X643504Y249980D01*
G37*
G36*
G01X648229D02*
X648354Y249970D01*
X648479Y249930D01*
X648589Y249870D01*
X648689Y249790D01*
X648769Y249690D01*
X648829Y249580D01*
X648869Y249455D01*
X648879Y249330D01*
Y248200D01*
X648909Y248170D01*
X649009Y248030D01*
X649029Y247990D01*
X649044Y247955D01*
X649064Y247915D01*
X649079Y247875D01*
X649089Y247835D01*
X649104Y247790D01*
X649109Y247750D01*
X649119Y247710D01*
X649124Y247665D01*
Y247625D01*
X649129Y247580D01*
X649124Y247535D01*
Y247495D01*
X649119Y247450D01*
X649109Y247410D01*
X649104Y247370D01*
X649089Y247325D01*
X649079Y247285D01*
X649064Y247245D01*
X649044Y247205D01*
X649029Y247170D01*
X649009Y247130D01*
X648909Y246990D01*
X648879Y246960D01*
Y243530D01*
X648869Y243405D01*
X648829Y243280D01*
X648769Y243170D01*
X648689Y243070D01*
X648589Y242990D01*
X648479Y242930D01*
X648354Y242890D01*
X648229Y242880D01*
X648104Y242890D01*
X647979Y242930D01*
X647869Y242990D01*
X647769Y243070D01*
X647689Y243170D01*
X647629Y243280D01*
X647589Y243405D01*
X647579Y243530D01*
Y246960D01*
X647549Y246990D01*
X647449Y247130D01*
X647429Y247170D01*
X647414Y247205D01*
X647394Y247245D01*
X647379Y247285D01*
X647369Y247325D01*
X647354Y247370D01*
X647349Y247410D01*
X647339Y247450D01*
X647334Y247495D01*
Y247535D01*
X647329Y247580D01*
X647334Y247625D01*
Y247665D01*
X647339Y247710D01*
X647349Y247750D01*
X647354Y247790D01*
X647369Y247835D01*
X647379Y247875D01*
X647394Y247915D01*
X647414Y247955D01*
X647429Y247990D01*
X647449Y248030D01*
X647549Y248170D01*
X647579Y248200D01*
Y249330D01*
X647589Y249455D01*
X647629Y249580D01*
X647689Y249690D01*
X647769Y249790D01*
X647869Y249870D01*
X647979Y249930D01*
X648104Y249970D01*
X648229Y249980D01*
G37*
G36*
G01X652953D02*
X653078Y249970D01*
X653203Y249930D01*
X653313Y249870D01*
X653413Y249790D01*
X653493Y249690D01*
X653553Y249580D01*
X653593Y249455D01*
X653603Y249330D01*
Y248200D01*
X653633Y248170D01*
X653733Y248030D01*
X653753Y247990D01*
X653768Y247955D01*
X653788Y247915D01*
X653803Y247875D01*
X653813Y247835D01*
X653828Y247790D01*
X653833Y247750D01*
X653843Y247710D01*
X653848Y247665D01*
Y247625D01*
X653853Y247580D01*
X653848Y247535D01*
Y247495D01*
X653843Y247450D01*
X653833Y247410D01*
X653828Y247370D01*
X653813Y247325D01*
X653803Y247285D01*
X653788Y247245D01*
X653768Y247205D01*
X653753Y247170D01*
X653733Y247130D01*
X653633Y246990D01*
X653603Y246960D01*
Y243530D01*
X653593Y243405D01*
X653553Y243280D01*
X653493Y243170D01*
X653413Y243070D01*
X653313Y242990D01*
X653203Y242930D01*
X653078Y242890D01*
X652953Y242880D01*
X652828Y242890D01*
X652703Y242930D01*
X652593Y242990D01*
X652493Y243070D01*
X652413Y243170D01*
X652353Y243280D01*
X652313Y243405D01*
X652303Y243530D01*
Y246960D01*
X652273Y246990D01*
X652173Y247130D01*
X652153Y247170D01*
X652138Y247205D01*
X652118Y247245D01*
X652103Y247285D01*
X652093Y247325D01*
X652078Y247370D01*
X652073Y247410D01*
X652063Y247450D01*
X652058Y247495D01*
Y247535D01*
X652053Y247580D01*
X652058Y247625D01*
Y247665D01*
X652063Y247710D01*
X652073Y247750D01*
X652078Y247790D01*
X652093Y247835D01*
X652103Y247875D01*
X652118Y247915D01*
X652138Y247955D01*
X652153Y247990D01*
X652173Y248030D01*
X652273Y248170D01*
X652303Y248200D01*
Y249330D01*
X652313Y249455D01*
X652353Y249580D01*
X652413Y249690D01*
X652493Y249790D01*
X652593Y249870D01*
X652703Y249930D01*
X652828Y249970D01*
X652953Y249980D01*
G37*
G36*
G01X667126D02*
X667251Y249970D01*
X667376Y249930D01*
X667486Y249870D01*
X667586Y249790D01*
X667666Y249690D01*
X667726Y249580D01*
X667766Y249455D01*
X667776Y249330D01*
Y248200D01*
X667806Y248170D01*
X667906Y248030D01*
X667926Y247990D01*
X667941Y247955D01*
X667961Y247915D01*
X667976Y247875D01*
X667986Y247835D01*
X668001Y247790D01*
X668006Y247750D01*
X668016Y247710D01*
X668021Y247665D01*
Y247625D01*
X668026Y247580D01*
X668021Y247535D01*
Y247495D01*
X668016Y247450D01*
X668006Y247410D01*
X668001Y247370D01*
X667986Y247325D01*
X667976Y247285D01*
X667961Y247245D01*
X667941Y247205D01*
X667926Y247170D01*
X667906Y247130D01*
X667806Y246990D01*
X667776Y246960D01*
Y243530D01*
X667766Y243405D01*
X667726Y243280D01*
X667666Y243170D01*
X667586Y243070D01*
X667486Y242990D01*
X667376Y242930D01*
X667251Y242890D01*
X667126Y242880D01*
X667001Y242890D01*
X666876Y242930D01*
X666766Y242990D01*
X666666Y243070D01*
X666586Y243170D01*
X666526Y243280D01*
X666486Y243405D01*
X666476Y243530D01*
Y246960D01*
X666446Y246990D01*
X666346Y247130D01*
X666326Y247170D01*
X666311Y247205D01*
X666291Y247245D01*
X666276Y247285D01*
X666266Y247325D01*
X666251Y247370D01*
X666246Y247410D01*
X666236Y247450D01*
X666231Y247495D01*
Y247535D01*
X666226Y247580D01*
X666231Y247625D01*
Y247665D01*
X666236Y247710D01*
X666246Y247750D01*
X666251Y247790D01*
X666266Y247835D01*
X666276Y247875D01*
X666291Y247915D01*
X666311Y247955D01*
X666326Y247990D01*
X666346Y248030D01*
X666446Y248170D01*
X666476Y248200D01*
Y249330D01*
X666486Y249455D01*
X666526Y249580D01*
X666586Y249690D01*
X666666Y249790D01*
X666766Y249870D01*
X666876Y249930D01*
X667001Y249970D01*
X667126Y249980D01*
G37*
G36*
G01X671851D02*
X671976Y249970D01*
X672101Y249930D01*
X672211Y249870D01*
X672311Y249790D01*
X672391Y249690D01*
X672451Y249580D01*
X672491Y249455D01*
X672501Y249330D01*
Y248200D01*
X672531Y248170D01*
X672631Y248030D01*
X672651Y247990D01*
X672666Y247955D01*
X672686Y247915D01*
X672701Y247875D01*
X672711Y247835D01*
X672726Y247790D01*
X672731Y247750D01*
X672741Y247710D01*
X672746Y247665D01*
Y247625D01*
X672751Y247580D01*
X672746Y247535D01*
Y247495D01*
X672741Y247450D01*
X672731Y247410D01*
X672726Y247370D01*
X672711Y247325D01*
X672701Y247285D01*
X672686Y247245D01*
X672666Y247205D01*
X672651Y247170D01*
X672631Y247130D01*
X672531Y246990D01*
X672501Y246960D01*
Y243530D01*
X672491Y243405D01*
X672451Y243280D01*
X672391Y243170D01*
X672311Y243070D01*
X672211Y242990D01*
X672101Y242930D01*
X671976Y242890D01*
X671851Y242880D01*
X671726Y242890D01*
X671601Y242930D01*
X671491Y242990D01*
X671391Y243070D01*
X671311Y243170D01*
X671251Y243280D01*
X671211Y243405D01*
X671201Y243530D01*
Y246960D01*
X671171Y246990D01*
X671071Y247130D01*
X671051Y247170D01*
X671036Y247205D01*
X671016Y247245D01*
X671001Y247285D01*
X670991Y247325D01*
X670976Y247370D01*
X670971Y247410D01*
X670961Y247450D01*
X670956Y247495D01*
Y247535D01*
X670951Y247580D01*
X670956Y247625D01*
Y247665D01*
X670961Y247710D01*
X670971Y247750D01*
X670976Y247790D01*
X670991Y247835D01*
X671001Y247875D01*
X671016Y247915D01*
X671036Y247955D01*
X671051Y247990D01*
X671071Y248030D01*
X671171Y248170D01*
X671201Y248200D01*
Y249330D01*
X671211Y249455D01*
X671251Y249580D01*
X671311Y249690D01*
X671391Y249790D01*
X671491Y249870D01*
X671601Y249930D01*
X671726Y249970D01*
X671851Y249980D01*
G37*
G36*
G01X676575D02*
X676700Y249970D01*
X676825Y249930D01*
X676935Y249870D01*
X677035Y249790D01*
X677115Y249690D01*
X677175Y249580D01*
X677215Y249455D01*
X677225Y249330D01*
Y248200D01*
X677255Y248170D01*
X677355Y248030D01*
X677375Y247990D01*
X677390Y247955D01*
X677410Y247915D01*
X677425Y247875D01*
X677435Y247835D01*
X677450Y247790D01*
X677455Y247750D01*
X677465Y247710D01*
X677470Y247665D01*
Y247625D01*
X677475Y247580D01*
X677470Y247535D01*
Y247495D01*
X677465Y247450D01*
X677455Y247410D01*
X677450Y247370D01*
X677435Y247325D01*
X677425Y247285D01*
X677410Y247245D01*
X677390Y247205D01*
X677375Y247170D01*
X677355Y247130D01*
X677255Y246990D01*
X677225Y246960D01*
Y243530D01*
X677215Y243405D01*
X677175Y243280D01*
X677115Y243170D01*
X677035Y243070D01*
X676935Y242990D01*
X676825Y242930D01*
X676700Y242890D01*
X676575Y242880D01*
X676450Y242890D01*
X676325Y242930D01*
X676215Y242990D01*
X676115Y243070D01*
X676035Y243170D01*
X675975Y243280D01*
X675935Y243405D01*
X675925Y243530D01*
Y246960D01*
X675895Y246990D01*
X675795Y247130D01*
X675775Y247170D01*
X675760Y247205D01*
X675740Y247245D01*
X675725Y247285D01*
X675715Y247325D01*
X675700Y247370D01*
X675695Y247410D01*
X675685Y247450D01*
X675680Y247495D01*
Y247535D01*
X675675Y247580D01*
X675680Y247625D01*
Y247665D01*
X675685Y247710D01*
X675695Y247750D01*
X675700Y247790D01*
X675715Y247835D01*
X675725Y247875D01*
X675740Y247915D01*
X675760Y247955D01*
X675775Y247990D01*
X675795Y248030D01*
X675895Y248170D01*
X675925Y248200D01*
Y249330D01*
X675935Y249455D01*
X675975Y249580D01*
X676035Y249690D01*
X676115Y249790D01*
X676215Y249870D01*
X676325Y249930D01*
X676450Y249970D01*
X676575Y249980D01*
G37*
G36*
G01X681299D02*
X681424Y249970D01*
X681549Y249930D01*
X681659Y249870D01*
X681759Y249790D01*
X681839Y249690D01*
X681899Y249580D01*
X681939Y249455D01*
X681949Y249330D01*
Y248200D01*
X681979Y248170D01*
X682079Y248030D01*
X682099Y247990D01*
X682114Y247955D01*
X682134Y247915D01*
X682149Y247875D01*
X682159Y247835D01*
X682174Y247790D01*
X682179Y247750D01*
X682189Y247710D01*
X682194Y247665D01*
Y247625D01*
X682199Y247580D01*
X682194Y247535D01*
Y247495D01*
X682189Y247450D01*
X682179Y247410D01*
X682174Y247370D01*
X682159Y247325D01*
X682149Y247285D01*
X682134Y247245D01*
X682114Y247205D01*
X682099Y247170D01*
X682079Y247130D01*
X681979Y246990D01*
X681949Y246960D01*
Y243530D01*
X681939Y243405D01*
X681899Y243280D01*
X681839Y243170D01*
X681759Y243070D01*
X681659Y242990D01*
X681549Y242930D01*
X681424Y242890D01*
X681299Y242880D01*
X681174Y242890D01*
X681049Y242930D01*
X680939Y242990D01*
X680839Y243070D01*
X680759Y243170D01*
X680699Y243280D01*
X680659Y243405D01*
X680649Y243530D01*
Y246960D01*
X680619Y246990D01*
X680519Y247130D01*
X680499Y247170D01*
X680484Y247205D01*
X680464Y247245D01*
X680449Y247285D01*
X680439Y247325D01*
X680424Y247370D01*
X680419Y247410D01*
X680409Y247450D01*
X680404Y247495D01*
Y247535D01*
X680399Y247580D01*
X680404Y247625D01*
Y247665D01*
X680409Y247710D01*
X680419Y247750D01*
X680424Y247790D01*
X680439Y247835D01*
X680449Y247875D01*
X680464Y247915D01*
X680484Y247955D01*
X680499Y247990D01*
X680519Y248030D01*
X680619Y248170D01*
X680649Y248200D01*
Y249330D01*
X680659Y249455D01*
X680699Y249580D01*
X680759Y249690D01*
X680839Y249790D01*
X680939Y249870D01*
X681049Y249930D01*
X681174Y249970D01*
X681299Y249980D01*
G37*
G36*
G01X686024D02*
X686149Y249970D01*
X686274Y249930D01*
X686384Y249870D01*
X686484Y249790D01*
X686564Y249690D01*
X686624Y249580D01*
X686664Y249455D01*
X686674Y249330D01*
Y248200D01*
X686704Y248170D01*
X686804Y248030D01*
X686824Y247990D01*
X686839Y247955D01*
X686859Y247915D01*
X686874Y247875D01*
X686884Y247835D01*
X686899Y247790D01*
X686904Y247750D01*
X686914Y247710D01*
X686919Y247665D01*
Y247625D01*
X686924Y247580D01*
X686919Y247535D01*
Y247495D01*
X686914Y247450D01*
X686904Y247410D01*
X686899Y247370D01*
X686884Y247325D01*
X686874Y247285D01*
X686859Y247245D01*
X686839Y247205D01*
X686824Y247170D01*
X686804Y247130D01*
X686704Y246990D01*
X686674Y246960D01*
Y243530D01*
X686664Y243405D01*
X686624Y243280D01*
X686564Y243170D01*
X686484Y243070D01*
X686384Y242990D01*
X686274Y242930D01*
X686149Y242890D01*
X686024Y242880D01*
X685899Y242890D01*
X685774Y242930D01*
X685664Y242990D01*
X685564Y243070D01*
X685484Y243170D01*
X685424Y243280D01*
X685384Y243405D01*
X685374Y243530D01*
Y246960D01*
X685344Y246990D01*
X685244Y247130D01*
X685224Y247170D01*
X685209Y247205D01*
X685189Y247245D01*
X685174Y247285D01*
X685164Y247325D01*
X685149Y247370D01*
X685144Y247410D01*
X685134Y247450D01*
X685129Y247495D01*
Y247535D01*
X685124Y247580D01*
X685129Y247625D01*
Y247665D01*
X685134Y247710D01*
X685144Y247750D01*
X685149Y247790D01*
X685164Y247835D01*
X685174Y247875D01*
X685189Y247915D01*
X685209Y247955D01*
X685224Y247990D01*
X685244Y248030D01*
X685344Y248170D01*
X685374Y248200D01*
Y249330D01*
X685384Y249455D01*
X685424Y249580D01*
X685484Y249690D01*
X685564Y249790D01*
X685664Y249870D01*
X685774Y249930D01*
X685899Y249970D01*
X686024Y249980D01*
G37*
G36*
G01X690748D02*
X690873Y249970D01*
X690998Y249930D01*
X691108Y249870D01*
X691208Y249790D01*
X691288Y249690D01*
X691348Y249580D01*
X691388Y249455D01*
X691398Y249330D01*
Y248200D01*
X691428Y248170D01*
X691528Y248030D01*
X691548Y247990D01*
X691563Y247955D01*
X691583Y247915D01*
X691598Y247875D01*
X691608Y247835D01*
X691623Y247790D01*
X691628Y247750D01*
X691638Y247710D01*
X691643Y247665D01*
Y247625D01*
X691648Y247580D01*
X691643Y247535D01*
Y247495D01*
X691638Y247450D01*
X691628Y247410D01*
X691623Y247370D01*
X691608Y247325D01*
X691598Y247285D01*
X691583Y247245D01*
X691563Y247205D01*
X691548Y247170D01*
X691528Y247130D01*
X691428Y246990D01*
X691398Y246960D01*
Y243530D01*
X691388Y243405D01*
X691348Y243280D01*
X691288Y243170D01*
X691208Y243070D01*
X691108Y242990D01*
X690998Y242930D01*
X690873Y242890D01*
X690748Y242880D01*
X690623Y242890D01*
X690498Y242930D01*
X690388Y242990D01*
X690288Y243070D01*
X690208Y243170D01*
X690148Y243280D01*
X690108Y243405D01*
X690098Y243530D01*
Y246960D01*
X690068Y246990D01*
X689968Y247130D01*
X689948Y247170D01*
X689933Y247205D01*
X689913Y247245D01*
X689898Y247285D01*
X689888Y247325D01*
X689873Y247370D01*
X689868Y247410D01*
X689858Y247450D01*
X689853Y247495D01*
Y247535D01*
X689848Y247580D01*
X689853Y247625D01*
Y247665D01*
X689858Y247710D01*
X689868Y247750D01*
X689873Y247790D01*
X689888Y247835D01*
X689898Y247875D01*
X689913Y247915D01*
X689933Y247955D01*
X689948Y247990D01*
X689968Y248030D01*
X690068Y248170D01*
X690098Y248200D01*
Y249330D01*
X690108Y249455D01*
X690148Y249580D01*
X690208Y249690D01*
X690288Y249790D01*
X690388Y249870D01*
X690498Y249930D01*
X690623Y249970D01*
X690748Y249980D01*
G37*
G36*
G01X695473D02*
X695598Y249970D01*
X695723Y249930D01*
X695833Y249870D01*
X695933Y249790D01*
X696013Y249690D01*
X696073Y249580D01*
X696113Y249455D01*
X696123Y249330D01*
Y248200D01*
X696153Y248170D01*
X696253Y248030D01*
X696273Y247990D01*
X696288Y247955D01*
X696308Y247915D01*
X696323Y247875D01*
X696333Y247835D01*
X696348Y247790D01*
X696353Y247750D01*
X696363Y247710D01*
X696368Y247665D01*
Y247625D01*
X696373Y247580D01*
X696368Y247535D01*
Y247495D01*
X696363Y247450D01*
X696353Y247410D01*
X696348Y247370D01*
X696333Y247325D01*
X696323Y247285D01*
X696308Y247245D01*
X696288Y247205D01*
X696273Y247170D01*
X696253Y247130D01*
X696153Y246990D01*
X696123Y246960D01*
Y243530D01*
X696113Y243405D01*
X696073Y243280D01*
X696013Y243170D01*
X695933Y243070D01*
X695833Y242990D01*
X695723Y242930D01*
X695598Y242890D01*
X695473Y242880D01*
X695348Y242890D01*
X695223Y242930D01*
X695113Y242990D01*
X695013Y243070D01*
X694933Y243170D01*
X694873Y243280D01*
X694833Y243405D01*
X694823Y243530D01*
Y246960D01*
X694793Y246990D01*
X694693Y247130D01*
X694673Y247170D01*
X694658Y247205D01*
X694638Y247245D01*
X694623Y247285D01*
X694613Y247325D01*
X694598Y247370D01*
X694593Y247410D01*
X694583Y247450D01*
X694578Y247495D01*
Y247535D01*
X694573Y247580D01*
X694578Y247625D01*
Y247665D01*
X694583Y247710D01*
X694593Y247750D01*
X694598Y247790D01*
X694613Y247835D01*
X694623Y247875D01*
X694638Y247915D01*
X694658Y247955D01*
X694673Y247990D01*
X694693Y248030D01*
X694793Y248170D01*
X694823Y248200D01*
Y249330D01*
X694833Y249455D01*
X694873Y249580D01*
X694933Y249690D01*
X695013Y249790D01*
X695113Y249870D01*
X695223Y249930D01*
X695348Y249970D01*
X695473Y249980D01*
G37*
G36*
G01X700197D02*
X700322Y249970D01*
X700447Y249930D01*
X700557Y249870D01*
X700657Y249790D01*
X700737Y249690D01*
X700797Y249580D01*
X700837Y249455D01*
X700847Y249330D01*
Y248200D01*
X700877Y248170D01*
X700977Y248030D01*
X700997Y247990D01*
X701012Y247955D01*
X701032Y247915D01*
X701047Y247875D01*
X701057Y247835D01*
X701072Y247790D01*
X701077Y247750D01*
X701087Y247710D01*
X701092Y247665D01*
Y247625D01*
X701097Y247580D01*
X701092Y247535D01*
Y247495D01*
X701087Y247450D01*
X701077Y247410D01*
X701072Y247370D01*
X701057Y247325D01*
X701047Y247285D01*
X701032Y247245D01*
X701012Y247205D01*
X700997Y247170D01*
X700977Y247130D01*
X700877Y246990D01*
X700847Y246960D01*
Y243530D01*
X700837Y243405D01*
X700797Y243280D01*
X700737Y243170D01*
X700657Y243070D01*
X700557Y242990D01*
X700447Y242930D01*
X700322Y242890D01*
X700197Y242880D01*
X700072Y242890D01*
X699947Y242930D01*
X699837Y242990D01*
X699737Y243070D01*
X699657Y243170D01*
X699597Y243280D01*
X699557Y243405D01*
X699547Y243530D01*
Y246960D01*
X699517Y246990D01*
X699417Y247130D01*
X699397Y247170D01*
X699382Y247205D01*
X699362Y247245D01*
X699347Y247285D01*
X699337Y247325D01*
X699322Y247370D01*
X699317Y247410D01*
X699307Y247450D01*
X699302Y247495D01*
Y247535D01*
X699297Y247580D01*
X699302Y247625D01*
Y247665D01*
X699307Y247710D01*
X699317Y247750D01*
X699322Y247790D01*
X699337Y247835D01*
X699347Y247875D01*
X699362Y247915D01*
X699382Y247955D01*
X699397Y247990D01*
X699417Y248030D01*
X699517Y248170D01*
X699547Y248200D01*
Y249330D01*
X699557Y249455D01*
X699597Y249580D01*
X699657Y249690D01*
X699737Y249790D01*
X699837Y249870D01*
X699947Y249930D01*
X700072Y249970D01*
X700197Y249980D01*
G37*
G36*
G01X704922D02*
X705047Y249970D01*
X705172Y249930D01*
X705282Y249870D01*
X705382Y249790D01*
X705462Y249690D01*
X705522Y249580D01*
X705562Y249455D01*
X705572Y249330D01*
Y248200D01*
X705602Y248170D01*
X705702Y248030D01*
X705722Y247990D01*
X705737Y247955D01*
X705757Y247915D01*
X705772Y247875D01*
X705782Y247835D01*
X705797Y247790D01*
X705802Y247750D01*
X705812Y247710D01*
X705817Y247665D01*
Y247625D01*
X705822Y247580D01*
X705817Y247535D01*
Y247495D01*
X705812Y247450D01*
X705802Y247410D01*
X705797Y247370D01*
X705782Y247325D01*
X705772Y247285D01*
X705757Y247245D01*
X705737Y247205D01*
X705722Y247170D01*
X705702Y247130D01*
X705602Y246990D01*
X705572Y246960D01*
Y243530D01*
X705562Y243405D01*
X705522Y243280D01*
X705462Y243170D01*
X705382Y243070D01*
X705282Y242990D01*
X705172Y242930D01*
X705047Y242890D01*
X704922Y242880D01*
X704797Y242890D01*
X704672Y242930D01*
X704562Y242990D01*
X704462Y243070D01*
X704382Y243170D01*
X704322Y243280D01*
X704282Y243405D01*
X704272Y243530D01*
Y246960D01*
X704242Y246990D01*
X704142Y247130D01*
X704122Y247170D01*
X704107Y247205D01*
X704087Y247245D01*
X704072Y247285D01*
X704062Y247325D01*
X704047Y247370D01*
X704042Y247410D01*
X704032Y247450D01*
X704027Y247495D01*
Y247535D01*
X704022Y247580D01*
X704027Y247625D01*
Y247665D01*
X704032Y247710D01*
X704042Y247750D01*
X704047Y247790D01*
X704062Y247835D01*
X704072Y247875D01*
X704087Y247915D01*
X704107Y247955D01*
X704122Y247990D01*
X704142Y248030D01*
X704242Y248170D01*
X704272Y248200D01*
Y249330D01*
X704282Y249455D01*
X704322Y249580D01*
X704382Y249690D01*
X704462Y249790D01*
X704562Y249870D01*
X704672Y249930D01*
X704797Y249970D01*
X704922Y249980D01*
G37*
G36*
G01X709646D02*
X709771Y249970D01*
X709896Y249930D01*
X710006Y249870D01*
X710106Y249790D01*
X710186Y249690D01*
X710246Y249580D01*
X710286Y249455D01*
X710296Y249330D01*
Y248200D01*
X710326Y248170D01*
X710426Y248030D01*
X710446Y247990D01*
X710461Y247955D01*
X710481Y247915D01*
X710496Y247875D01*
X710506Y247835D01*
X710521Y247790D01*
X710526Y247750D01*
X710536Y247710D01*
X710541Y247665D01*
Y247625D01*
X710546Y247580D01*
X710541Y247535D01*
Y247495D01*
X710536Y247450D01*
X710526Y247410D01*
X710521Y247370D01*
X710506Y247325D01*
X710496Y247285D01*
X710481Y247245D01*
X710461Y247205D01*
X710446Y247170D01*
X710426Y247130D01*
X710326Y246990D01*
X710296Y246960D01*
Y243530D01*
X710286Y243405D01*
X710246Y243280D01*
X710186Y243170D01*
X710106Y243070D01*
X710006Y242990D01*
X709896Y242930D01*
X709771Y242890D01*
X709646Y242880D01*
X709521Y242890D01*
X709396Y242930D01*
X709286Y242990D01*
X709186Y243070D01*
X709106Y243170D01*
X709046Y243280D01*
X709006Y243405D01*
X708996Y243530D01*
Y246960D01*
X708966Y246990D01*
X708866Y247130D01*
X708846Y247170D01*
X708831Y247205D01*
X708811Y247245D01*
X708796Y247285D01*
X708786Y247325D01*
X708771Y247370D01*
X708766Y247410D01*
X708756Y247450D01*
X708751Y247495D01*
Y247535D01*
X708746Y247580D01*
X708751Y247625D01*
Y247665D01*
X708756Y247710D01*
X708766Y247750D01*
X708771Y247790D01*
X708786Y247835D01*
X708796Y247875D01*
X708811Y247915D01*
X708831Y247955D01*
X708846Y247990D01*
X708866Y248030D01*
X708966Y248170D01*
X708996Y248200D01*
Y249330D01*
X709006Y249455D01*
X709046Y249580D01*
X709106Y249690D01*
X709186Y249790D01*
X709286Y249870D01*
X709396Y249930D01*
X709521Y249970D01*
X709646Y249980D01*
G37*
G36*
G01X714370D02*
X714495Y249970D01*
X714620Y249930D01*
X714730Y249870D01*
X714830Y249790D01*
X714910Y249690D01*
X714970Y249580D01*
X715010Y249455D01*
X715020Y249330D01*
Y248200D01*
X715050Y248170D01*
X715150Y248030D01*
X715170Y247990D01*
X715185Y247955D01*
X715205Y247915D01*
X715220Y247875D01*
X715230Y247835D01*
X715245Y247790D01*
X715250Y247750D01*
X715260Y247710D01*
X715265Y247665D01*
Y247625D01*
X715270Y247580D01*
X715265Y247535D01*
Y247495D01*
X715260Y247450D01*
X715250Y247410D01*
X715245Y247370D01*
X715230Y247325D01*
X715220Y247285D01*
X715205Y247245D01*
X715185Y247205D01*
X715170Y247170D01*
X715150Y247130D01*
X715050Y246990D01*
X715020Y246960D01*
Y243530D01*
X715010Y243405D01*
X714970Y243280D01*
X714910Y243170D01*
X714830Y243070D01*
X714730Y242990D01*
X714620Y242930D01*
X714495Y242890D01*
X714370Y242880D01*
X714245Y242890D01*
X714120Y242930D01*
X714010Y242990D01*
X713910Y243070D01*
X713830Y243170D01*
X713770Y243280D01*
X713730Y243405D01*
X713720Y243530D01*
Y246960D01*
X713690Y246990D01*
X713590Y247130D01*
X713570Y247170D01*
X713555Y247205D01*
X713535Y247245D01*
X713520Y247285D01*
X713510Y247325D01*
X713495Y247370D01*
X713490Y247410D01*
X713480Y247450D01*
X713475Y247495D01*
Y247535D01*
X713470Y247580D01*
X713475Y247625D01*
Y247665D01*
X713480Y247710D01*
X713490Y247750D01*
X713495Y247790D01*
X713510Y247835D01*
X713520Y247875D01*
X713535Y247915D01*
X713555Y247955D01*
X713570Y247990D01*
X713590Y248030D01*
X713690Y248170D01*
X713720Y248200D01*
Y249330D01*
X713730Y249455D01*
X713770Y249580D01*
X713830Y249690D01*
X713910Y249790D01*
X714010Y249870D01*
X714120Y249930D01*
X714245Y249970D01*
X714370Y249980D01*
G37*
G36*
G01X719095D02*
X719220Y249970D01*
X719345Y249930D01*
X719455Y249870D01*
X719555Y249790D01*
X719635Y249690D01*
X719695Y249580D01*
X719735Y249455D01*
X719745Y249330D01*
Y248200D01*
X719775Y248170D01*
X719875Y248030D01*
X719895Y247990D01*
X719910Y247955D01*
X719930Y247915D01*
X719945Y247875D01*
X719955Y247835D01*
X719970Y247790D01*
X719975Y247750D01*
X719985Y247710D01*
X719990Y247665D01*
Y247625D01*
X719995Y247580D01*
X719990Y247535D01*
Y247495D01*
X719985Y247450D01*
X719975Y247410D01*
X719970Y247370D01*
X719955Y247325D01*
X719945Y247285D01*
X719930Y247245D01*
X719910Y247205D01*
X719895Y247170D01*
X719875Y247130D01*
X719775Y246990D01*
X719745Y246960D01*
Y243530D01*
X719735Y243405D01*
X719695Y243280D01*
X719635Y243170D01*
X719555Y243070D01*
X719455Y242990D01*
X719345Y242930D01*
X719220Y242890D01*
X719095Y242880D01*
X718970Y242890D01*
X718845Y242930D01*
X718735Y242990D01*
X718635Y243070D01*
X718555Y243170D01*
X718495Y243280D01*
X718455Y243405D01*
X718445Y243530D01*
Y246960D01*
X718415Y246990D01*
X718315Y247130D01*
X718295Y247170D01*
X718280Y247205D01*
X718260Y247245D01*
X718245Y247285D01*
X718235Y247325D01*
X718220Y247370D01*
X718215Y247410D01*
X718205Y247450D01*
X718200Y247495D01*
Y247535D01*
X718195Y247580D01*
X718200Y247625D01*
Y247665D01*
X718205Y247710D01*
X718215Y247750D01*
X718220Y247790D01*
X718235Y247835D01*
X718245Y247875D01*
X718260Y247915D01*
X718280Y247955D01*
X718295Y247990D01*
X718315Y248030D01*
X718415Y248170D01*
X718445Y248200D01*
Y249330D01*
X718455Y249455D01*
X718495Y249580D01*
X718555Y249690D01*
X718635Y249790D01*
X718735Y249870D01*
X718845Y249930D01*
X718970Y249970D01*
X719095Y249980D01*
G37*
G36*
G01X723819D02*
X723944Y249970D01*
X724069Y249930D01*
X724179Y249870D01*
X724279Y249790D01*
X724359Y249690D01*
X724419Y249580D01*
X724459Y249455D01*
X724469Y249330D01*
Y248200D01*
X724499Y248170D01*
X724599Y248030D01*
X724619Y247990D01*
X724634Y247955D01*
X724654Y247915D01*
X724669Y247875D01*
X724679Y247835D01*
X724694Y247790D01*
X724699Y247750D01*
X724709Y247710D01*
X724714Y247665D01*
Y247625D01*
X724719Y247580D01*
X724714Y247535D01*
Y247495D01*
X724709Y247450D01*
X724699Y247410D01*
X724694Y247370D01*
X724679Y247325D01*
X724669Y247285D01*
X724654Y247245D01*
X724634Y247205D01*
X724619Y247170D01*
X724599Y247130D01*
X724499Y246990D01*
X724469Y246960D01*
Y243530D01*
X724459Y243405D01*
X724419Y243280D01*
X724359Y243170D01*
X724279Y243070D01*
X724179Y242990D01*
X724069Y242930D01*
X723944Y242890D01*
X723819Y242880D01*
X723694Y242890D01*
X723569Y242930D01*
X723459Y242990D01*
X723359Y243070D01*
X723279Y243170D01*
X723219Y243280D01*
X723179Y243405D01*
X723169Y243530D01*
Y246960D01*
X723139Y246990D01*
X723039Y247130D01*
X723019Y247170D01*
X723004Y247205D01*
X722984Y247245D01*
X722969Y247285D01*
X722959Y247325D01*
X722944Y247370D01*
X722939Y247410D01*
X722929Y247450D01*
X722924Y247495D01*
Y247535D01*
X722919Y247580D01*
X722924Y247625D01*
Y247665D01*
X722929Y247710D01*
X722939Y247750D01*
X722944Y247790D01*
X722959Y247835D01*
X722969Y247875D01*
X722984Y247915D01*
X723004Y247955D01*
X723019Y247990D01*
X723039Y248030D01*
X723139Y248170D01*
X723169Y248200D01*
Y249330D01*
X723179Y249455D01*
X723219Y249580D01*
X723279Y249690D01*
X723359Y249790D01*
X723459Y249870D01*
X723569Y249930D01*
X723694Y249970D01*
X723819Y249980D01*
G37*
G36*
G01X728544D02*
X728669Y249970D01*
X728794Y249930D01*
X728904Y249870D01*
X729004Y249790D01*
X729084Y249690D01*
X729144Y249580D01*
X729184Y249455D01*
X729194Y249330D01*
Y248200D01*
X729224Y248170D01*
X729324Y248030D01*
X729344Y247990D01*
X729359Y247955D01*
X729379Y247915D01*
X729394Y247875D01*
X729404Y247835D01*
X729419Y247790D01*
X729424Y247750D01*
X729434Y247710D01*
X729439Y247665D01*
Y247625D01*
X729444Y247580D01*
X729439Y247535D01*
Y247495D01*
X729434Y247450D01*
X729424Y247410D01*
X729419Y247370D01*
X729404Y247325D01*
X729394Y247285D01*
X729379Y247245D01*
X729359Y247205D01*
X729344Y247170D01*
X729324Y247130D01*
X729224Y246990D01*
X729194Y246960D01*
Y243530D01*
X729184Y243405D01*
X729144Y243280D01*
X729084Y243170D01*
X729004Y243070D01*
X728904Y242990D01*
X728794Y242930D01*
X728669Y242890D01*
X728544Y242880D01*
X728419Y242890D01*
X728294Y242930D01*
X728184Y242990D01*
X728084Y243070D01*
X728004Y243170D01*
X727944Y243280D01*
X727904Y243405D01*
X727894Y243530D01*
Y246960D01*
X727864Y246990D01*
X727764Y247130D01*
X727744Y247170D01*
X727729Y247205D01*
X727709Y247245D01*
X727694Y247285D01*
X727684Y247325D01*
X727669Y247370D01*
X727664Y247410D01*
X727654Y247450D01*
X727649Y247495D01*
Y247535D01*
X727644Y247580D01*
X727649Y247625D01*
Y247665D01*
X727654Y247710D01*
X727664Y247750D01*
X727669Y247790D01*
X727684Y247835D01*
X727694Y247875D01*
X727709Y247915D01*
X727729Y247955D01*
X727744Y247990D01*
X727764Y248030D01*
X727864Y248170D01*
X727894Y248200D01*
Y249330D01*
X727904Y249455D01*
X727944Y249580D01*
X728004Y249690D01*
X728084Y249790D01*
X728184Y249870D01*
X728294Y249930D01*
X728419Y249970D01*
X728544Y249980D01*
G37*
G36*
G01X733268D02*
X733393Y249970D01*
X733518Y249930D01*
X733628Y249870D01*
X733728Y249790D01*
X733808Y249690D01*
X733868Y249580D01*
X733908Y249455D01*
X733918Y249330D01*
Y248200D01*
X733948Y248170D01*
X734048Y248030D01*
X734068Y247990D01*
X734083Y247955D01*
X734103Y247915D01*
X734118Y247875D01*
X734128Y247835D01*
X734143Y247790D01*
X734148Y247750D01*
X734158Y247710D01*
X734163Y247665D01*
Y247625D01*
X734168Y247580D01*
X734163Y247535D01*
Y247495D01*
X734158Y247450D01*
X734148Y247410D01*
X734143Y247370D01*
X734128Y247325D01*
X734118Y247285D01*
X734103Y247245D01*
X734083Y247205D01*
X734068Y247170D01*
X734048Y247130D01*
X733948Y246990D01*
X733918Y246960D01*
Y243530D01*
X733908Y243405D01*
X733868Y243280D01*
X733808Y243170D01*
X733728Y243070D01*
X733628Y242990D01*
X733518Y242930D01*
X733393Y242890D01*
X733268Y242880D01*
X733143Y242890D01*
X733018Y242930D01*
X732908Y242990D01*
X732808Y243070D01*
X732728Y243170D01*
X732668Y243280D01*
X732628Y243405D01*
X732618Y243530D01*
Y246960D01*
X732588Y246990D01*
X732488Y247130D01*
X732468Y247170D01*
X732453Y247205D01*
X732433Y247245D01*
X732418Y247285D01*
X732408Y247325D01*
X732393Y247370D01*
X732388Y247410D01*
X732378Y247450D01*
X732373Y247495D01*
Y247535D01*
X732368Y247580D01*
X732373Y247625D01*
Y247665D01*
X732378Y247710D01*
X732388Y247750D01*
X732393Y247790D01*
X732408Y247835D01*
X732418Y247875D01*
X732433Y247915D01*
X732453Y247955D01*
X732468Y247990D01*
X732488Y248030D01*
X732588Y248170D01*
X732618Y248200D01*
Y249330D01*
X732628Y249455D01*
X732668Y249580D01*
X732728Y249690D01*
X732808Y249790D01*
X732908Y249870D01*
X733018Y249930D01*
X733143Y249970D01*
X733268Y249980D01*
G37*
G36*
G01X737992D02*
X738117Y249970D01*
X738242Y249930D01*
X738352Y249870D01*
X738452Y249790D01*
X738532Y249690D01*
X738592Y249580D01*
X738632Y249455D01*
X738642Y249330D01*
Y248200D01*
X738672Y248170D01*
X738772Y248030D01*
X738792Y247990D01*
X738807Y247955D01*
X738827Y247915D01*
X738842Y247875D01*
X738852Y247835D01*
X738867Y247790D01*
X738872Y247750D01*
X738882Y247710D01*
X738887Y247665D01*
Y247625D01*
X738892Y247580D01*
X738887Y247535D01*
Y247495D01*
X738882Y247450D01*
X738872Y247410D01*
X738867Y247370D01*
X738852Y247325D01*
X738842Y247285D01*
X738827Y247245D01*
X738807Y247205D01*
X738792Y247170D01*
X738772Y247130D01*
X738672Y246990D01*
X738642Y246960D01*
Y243530D01*
X738632Y243405D01*
X738592Y243280D01*
X738532Y243170D01*
X738452Y243070D01*
X738352Y242990D01*
X738242Y242930D01*
X738117Y242890D01*
X737992Y242880D01*
X737867Y242890D01*
X737742Y242930D01*
X737632Y242990D01*
X737532Y243070D01*
X737452Y243170D01*
X737392Y243280D01*
X737352Y243405D01*
X737342Y243530D01*
Y246960D01*
X737312Y246990D01*
X737212Y247130D01*
X737192Y247170D01*
X737177Y247205D01*
X737157Y247245D01*
X737142Y247285D01*
X737132Y247325D01*
X737117Y247370D01*
X737112Y247410D01*
X737102Y247450D01*
X737097Y247495D01*
Y247535D01*
X737092Y247580D01*
X737097Y247625D01*
Y247665D01*
X737102Y247710D01*
X737112Y247750D01*
X737117Y247790D01*
X737132Y247835D01*
X737142Y247875D01*
X737157Y247915D01*
X737177Y247955D01*
X737192Y247990D01*
X737212Y248030D01*
X737312Y248170D01*
X737342Y248200D01*
Y249330D01*
X737352Y249455D01*
X737392Y249580D01*
X737452Y249690D01*
X737532Y249790D01*
X737632Y249870D01*
X737742Y249930D01*
X737867Y249970D01*
X737992Y249980D01*
G37*
G36*
G01X742717D02*
X742842Y249970D01*
X742967Y249930D01*
X743077Y249870D01*
X743177Y249790D01*
X743257Y249690D01*
X743317Y249580D01*
X743357Y249455D01*
X743367Y249330D01*
Y248200D01*
X743397Y248170D01*
X743497Y248030D01*
X743517Y247990D01*
X743532Y247955D01*
X743552Y247915D01*
X743567Y247875D01*
X743577Y247835D01*
X743592Y247790D01*
X743597Y247750D01*
X743607Y247710D01*
X743612Y247665D01*
Y247625D01*
X743617Y247580D01*
X743612Y247535D01*
Y247495D01*
X743607Y247450D01*
X743597Y247410D01*
X743592Y247370D01*
X743577Y247325D01*
X743567Y247285D01*
X743552Y247245D01*
X743532Y247205D01*
X743517Y247170D01*
X743497Y247130D01*
X743397Y246990D01*
X743367Y246960D01*
Y243530D01*
X743357Y243405D01*
X743317Y243280D01*
X743257Y243170D01*
X743177Y243070D01*
X743077Y242990D01*
X742967Y242930D01*
X742842Y242890D01*
X742717Y242880D01*
X742592Y242890D01*
X742467Y242930D01*
X742357Y242990D01*
X742257Y243070D01*
X742177Y243170D01*
X742117Y243280D01*
X742077Y243405D01*
X742067Y243530D01*
Y246960D01*
X742037Y246990D01*
X741937Y247130D01*
X741917Y247170D01*
X741902Y247205D01*
X741882Y247245D01*
X741867Y247285D01*
X741857Y247325D01*
X741842Y247370D01*
X741837Y247410D01*
X741827Y247450D01*
X741822Y247495D01*
Y247535D01*
X741817Y247580D01*
X741822Y247625D01*
Y247665D01*
X741827Y247710D01*
X741837Y247750D01*
X741842Y247790D01*
X741857Y247835D01*
X741867Y247875D01*
X741882Y247915D01*
X741902Y247955D01*
X741917Y247990D01*
X741937Y248030D01*
X742037Y248170D01*
X742067Y248200D01*
Y249330D01*
X742077Y249455D01*
X742117Y249580D01*
X742177Y249690D01*
X742257Y249790D01*
X742357Y249870D01*
X742467Y249930D01*
X742592Y249970D01*
X742717Y249980D01*
G37*
G36*
G01X747441D02*
X747566Y249970D01*
X747691Y249930D01*
X747801Y249870D01*
X747901Y249790D01*
X747981Y249690D01*
X748041Y249580D01*
X748081Y249455D01*
X748091Y249330D01*
Y248200D01*
X748121Y248170D01*
X748221Y248030D01*
X748241Y247990D01*
X748256Y247955D01*
X748276Y247915D01*
X748291Y247875D01*
X748301Y247835D01*
X748316Y247790D01*
X748321Y247750D01*
X748331Y247710D01*
X748336Y247665D01*
Y247625D01*
X748341Y247580D01*
X748336Y247535D01*
Y247495D01*
X748331Y247450D01*
X748321Y247410D01*
X748316Y247370D01*
X748301Y247325D01*
X748291Y247285D01*
X748276Y247245D01*
X748256Y247205D01*
X748241Y247170D01*
X748221Y247130D01*
X748121Y246990D01*
X748091Y246960D01*
Y243530D01*
X748081Y243405D01*
X748041Y243280D01*
X747981Y243170D01*
X747901Y243070D01*
X747801Y242990D01*
X747691Y242930D01*
X747566Y242890D01*
X747441Y242880D01*
X747316Y242890D01*
X747191Y242930D01*
X747081Y242990D01*
X746981Y243070D01*
X746901Y243170D01*
X746841Y243280D01*
X746801Y243405D01*
X746791Y243530D01*
Y246960D01*
X746761Y246990D01*
X746661Y247130D01*
X746641Y247170D01*
X746626Y247205D01*
X746606Y247245D01*
X746591Y247285D01*
X746581Y247325D01*
X746566Y247370D01*
X746561Y247410D01*
X746551Y247450D01*
X746546Y247495D01*
Y247535D01*
X746541Y247580D01*
X746546Y247625D01*
Y247665D01*
X746551Y247710D01*
X746561Y247750D01*
X746566Y247790D01*
X746581Y247835D01*
X746591Y247875D01*
X746606Y247915D01*
X746626Y247955D01*
X746641Y247990D01*
X746661Y248030D01*
X746761Y248170D01*
X746791Y248200D01*
Y249330D01*
X746801Y249455D01*
X746841Y249580D01*
X746901Y249690D01*
X746981Y249790D01*
X747081Y249870D01*
X747191Y249930D01*
X747316Y249970D01*
X747441Y249980D01*
G37*
G54D83*
X336652Y102171D03*
X330252D03*
X335832Y206491D03*
X329432D03*
X354382Y102171D03*
X342312D03*
X347982D03*
X353562Y206491D03*
X347162D03*
X341502D03*
X360042Y102171D03*
X365702D03*
X371292Y206491D03*
X364892D03*
X359222D03*
X372102Y102171D03*
X377772D03*
X383432D03*
X376952Y206491D03*
X382622D03*
X389832Y102171D03*
X395502D03*
X401162D03*
X394682Y206491D03*
X389022D03*
X400342D03*
X407562Y102171D03*
X413222D03*
X412412Y206491D03*
X418072D03*
X406742D03*
X418892Y102171D03*
X425292D03*
X424472Y206491D03*
G54D38*
X73057Y113500D03*
X93943D03*
G54D47*
X104000Y214100D03*
X109200D03*
X104000Y224200D03*
X109200D03*
X104000Y219100D03*
X109200D03*
X104000Y235400D03*
X109200D03*
X144400Y196000D03*
X149600D03*
X427100Y75500D03*
X432300D03*
X427396Y232063D03*
X432596D03*
X436896D03*
X442096D03*
X520400Y231000D03*
X525600D03*
X520400Y236000D03*
X525600D03*
X551900D03*
X557100D03*
X658400Y111500D03*
X663600D03*
X658400Y139500D03*
X663600D03*
X675400Y156500D03*
X680600D03*
X725900Y59000D03*
Y54000D03*
X718900Y90000D03*
X724100D03*
X731100Y59000D03*
Y54000D03*
X775900Y12000D03*
X781100D03*
X775900Y7000D03*
X781100D03*
X774100Y133000D03*
X779300D03*
X773900Y154500D03*
X779100D03*
X800400Y260600D03*
Y265600D03*
Y270600D03*
X805600Y260600D03*
Y265600D03*
Y270600D03*
G54D39*
X84500Y230000D03*
G54D48*
X104700Y259800D03*
Y263800D03*
X109900Y261800D03*
G54D66*
X183840Y117340D03*
X176360D03*
X183840Y119900D03*
X176360D03*
X183840Y122460D03*
X176360D03*
X269260Y53060D03*
X276740D03*
X269260Y50500D03*
Y47940D03*
X276740D03*
Y50500D03*
X721260Y187440D03*
Y190000D03*
Y192560D03*
X728740D03*
Y190000D03*
Y187440D03*
G54D75*
X248430Y164600D03*
X246465D03*
Y180400D03*
X248430D03*
X254335Y164600D03*
X252370D03*
X250400D03*
Y180400D03*
X252370D03*
X254335D03*
G54D57*
X155740Y180020D03*
Y187380D03*
X163060Y165320D03*
X157940D03*
X163060Y172680D03*
X157940D03*
X160500D03*
X160860Y180020D03*
Y187380D03*
X158300D03*
X447940Y262820D03*
Y270180D03*
X453060D03*
Y262820D03*
X450500D03*
G36*
G01X500591Y282316D02*
X500716Y282306D01*
X500841Y282266D01*
X500951Y282206D01*
X501051Y282126D01*
X501131Y282026D01*
X501191Y281916D01*
X501231Y281791D01*
X501241Y281666D01*
Y279236D01*
X501271Y279206D01*
X501371Y279066D01*
X501391Y279026D01*
X501406Y278991D01*
X501426Y278951D01*
X501441Y278911D01*
X501451Y278871D01*
X501466Y278826D01*
X501471Y278786D01*
X501481Y278746D01*
X501486Y278701D01*
Y278661D01*
X501491Y278616D01*
X501486Y278571D01*
Y278531D01*
X501481Y278486D01*
X501471Y278446D01*
X501466Y278406D01*
X501451Y278361D01*
X501441Y278321D01*
X501426Y278281D01*
X501406Y278241D01*
X501391Y278206D01*
X501371Y278166D01*
X501271Y278026D01*
X501241Y277996D01*
Y275866D01*
X501231Y275741D01*
X501191Y275616D01*
X501131Y275506D01*
X501051Y275406D01*
X500951Y275326D01*
X500841Y275266D01*
X500716Y275226D01*
X500591Y275216D01*
X500466Y275226D01*
X500341Y275266D01*
X500231Y275326D01*
X500131Y275406D01*
X500051Y275506D01*
X499991Y275616D01*
X499951Y275741D01*
X499941Y275866D01*
Y277991D01*
X499911Y278021D01*
X499886Y278056D01*
X499856Y278091D01*
X499836Y278126D01*
X499811Y278161D01*
X499771Y278241D01*
X499726Y278361D01*
X499716Y278401D01*
X499706Y278446D01*
X499701Y278486D01*
X499691Y278531D01*
Y278701D01*
X499701Y278746D01*
X499706Y278786D01*
X499716Y278831D01*
X499726Y278871D01*
X499771Y278991D01*
X499811Y279071D01*
X499836Y279106D01*
X499856Y279141D01*
X499886Y279176D01*
X499911Y279211D01*
X499941Y279241D01*
Y281666D01*
X499951Y281791D01*
X499991Y281916D01*
X500051Y282026D01*
X500131Y282126D01*
X500231Y282206D01*
X500341Y282266D01*
X500466Y282306D01*
X500591Y282316D01*
G37*
G36*
G01X505315D02*
X505440Y282306D01*
X505565Y282266D01*
X505675Y282206D01*
X505775Y282126D01*
X505855Y282026D01*
X505915Y281916D01*
X505955Y281791D01*
X505965Y281666D01*
Y279236D01*
X505995Y279206D01*
X506095Y279066D01*
X506115Y279026D01*
X506130Y278991D01*
X506150Y278951D01*
X506165Y278911D01*
X506175Y278871D01*
X506190Y278826D01*
X506195Y278786D01*
X506205Y278746D01*
X506210Y278701D01*
Y278661D01*
X506215Y278616D01*
X506210Y278571D01*
Y278531D01*
X506205Y278486D01*
X506195Y278446D01*
X506190Y278406D01*
X506175Y278361D01*
X506165Y278321D01*
X506150Y278281D01*
X506130Y278241D01*
X506115Y278206D01*
X506095Y278166D01*
X505995Y278026D01*
X505965Y277996D01*
Y275866D01*
X505955Y275741D01*
X505915Y275616D01*
X505855Y275506D01*
X505775Y275406D01*
X505675Y275326D01*
X505565Y275266D01*
X505440Y275226D01*
X505315Y275216D01*
X505190Y275226D01*
X505065Y275266D01*
X504955Y275326D01*
X504855Y275406D01*
X504775Y275506D01*
X504715Y275616D01*
X504675Y275741D01*
X504665Y275866D01*
Y277991D01*
X504635Y278021D01*
X504610Y278056D01*
X504580Y278091D01*
X504560Y278126D01*
X504535Y278161D01*
X504495Y278241D01*
X504450Y278361D01*
X504440Y278401D01*
X504430Y278446D01*
X504425Y278486D01*
X504415Y278531D01*
Y278701D01*
X504425Y278746D01*
X504430Y278786D01*
X504440Y278831D01*
X504450Y278871D01*
X504495Y278991D01*
X504535Y279071D01*
X504560Y279106D01*
X504580Y279141D01*
X504610Y279176D01*
X504635Y279211D01*
X504665Y279241D01*
Y281666D01*
X504675Y281791D01*
X504715Y281916D01*
X504775Y282026D01*
X504855Y282126D01*
X504955Y282206D01*
X505065Y282266D01*
X505190Y282306D01*
X505315Y282316D01*
G37*
G36*
G01X510040D02*
X510165Y282306D01*
X510290Y282266D01*
X510400Y282206D01*
X510500Y282126D01*
X510580Y282026D01*
X510640Y281916D01*
X510680Y281791D01*
X510690Y281666D01*
Y279236D01*
X510720Y279206D01*
X510820Y279066D01*
X510840Y279026D01*
X510855Y278991D01*
X510875Y278951D01*
X510890Y278911D01*
X510900Y278871D01*
X510915Y278826D01*
X510920Y278786D01*
X510930Y278746D01*
X510935Y278701D01*
Y278661D01*
X510940Y278616D01*
X510935Y278571D01*
Y278531D01*
X510930Y278486D01*
X510920Y278446D01*
X510915Y278406D01*
X510900Y278361D01*
X510890Y278321D01*
X510875Y278281D01*
X510855Y278241D01*
X510840Y278206D01*
X510820Y278166D01*
X510720Y278026D01*
X510690Y277996D01*
Y275866D01*
X510680Y275741D01*
X510640Y275616D01*
X510580Y275506D01*
X510500Y275406D01*
X510400Y275326D01*
X510290Y275266D01*
X510165Y275226D01*
X510040Y275216D01*
X509915Y275226D01*
X509790Y275266D01*
X509680Y275326D01*
X509580Y275406D01*
X509500Y275506D01*
X509440Y275616D01*
X509400Y275741D01*
X509390Y275866D01*
Y277991D01*
X509360Y278021D01*
X509335Y278056D01*
X509305Y278091D01*
X509285Y278126D01*
X509260Y278161D01*
X509220Y278241D01*
X509175Y278361D01*
X509165Y278401D01*
X509155Y278446D01*
X509150Y278486D01*
X509140Y278531D01*
Y278701D01*
X509150Y278746D01*
X509155Y278786D01*
X509165Y278831D01*
X509175Y278871D01*
X509220Y278991D01*
X509260Y279071D01*
X509285Y279106D01*
X509305Y279141D01*
X509335Y279176D01*
X509360Y279211D01*
X509390Y279241D01*
Y281666D01*
X509400Y281791D01*
X509440Y281916D01*
X509500Y282026D01*
X509580Y282126D01*
X509680Y282206D01*
X509790Y282266D01*
X509915Y282306D01*
X510040Y282316D01*
G37*
G36*
G01X514764D02*
X514889Y282306D01*
X515014Y282266D01*
X515124Y282206D01*
X515224Y282126D01*
X515304Y282026D01*
X515364Y281916D01*
X515404Y281791D01*
X515414Y281666D01*
Y279236D01*
X515444Y279206D01*
X515544Y279066D01*
X515564Y279026D01*
X515579Y278991D01*
X515599Y278951D01*
X515614Y278911D01*
X515624Y278871D01*
X515639Y278826D01*
X515644Y278786D01*
X515654Y278746D01*
X515659Y278701D01*
Y278661D01*
X515664Y278616D01*
X515659Y278571D01*
Y278531D01*
X515654Y278486D01*
X515644Y278446D01*
X515639Y278406D01*
X515624Y278361D01*
X515614Y278321D01*
X515599Y278281D01*
X515579Y278241D01*
X515564Y278206D01*
X515544Y278166D01*
X515444Y278026D01*
X515414Y277996D01*
Y275866D01*
X515404Y275741D01*
X515364Y275616D01*
X515304Y275506D01*
X515224Y275406D01*
X515124Y275326D01*
X515014Y275266D01*
X514889Y275226D01*
X514764Y275216D01*
X514639Y275226D01*
X514514Y275266D01*
X514404Y275326D01*
X514304Y275406D01*
X514224Y275506D01*
X514164Y275616D01*
X514124Y275741D01*
X514114Y275866D01*
Y277991D01*
X514084Y278021D01*
X514059Y278056D01*
X514029Y278091D01*
X514009Y278126D01*
X513984Y278161D01*
X513944Y278241D01*
X513899Y278361D01*
X513889Y278401D01*
X513879Y278446D01*
X513874Y278486D01*
X513864Y278531D01*
Y278701D01*
X513874Y278746D01*
X513879Y278786D01*
X513889Y278831D01*
X513899Y278871D01*
X513944Y278991D01*
X513984Y279071D01*
X514009Y279106D01*
X514029Y279141D01*
X514059Y279176D01*
X514084Y279211D01*
X514114Y279241D01*
Y281666D01*
X514124Y281791D01*
X514164Y281916D01*
X514224Y282026D01*
X514304Y282126D01*
X514404Y282206D01*
X514514Y282266D01*
X514639Y282306D01*
X514764Y282316D01*
G37*
G36*
G01X519488D02*
X519613Y282306D01*
X519738Y282266D01*
X519848Y282206D01*
X519948Y282126D01*
X520028Y282026D01*
X520088Y281916D01*
X520128Y281791D01*
X520138Y281666D01*
Y279236D01*
X520168Y279206D01*
X520268Y279066D01*
X520288Y279026D01*
X520303Y278991D01*
X520323Y278951D01*
X520338Y278911D01*
X520348Y278871D01*
X520363Y278826D01*
X520368Y278786D01*
X520378Y278746D01*
X520383Y278701D01*
Y278661D01*
X520388Y278616D01*
X520383Y278571D01*
Y278531D01*
X520378Y278486D01*
X520368Y278446D01*
X520363Y278406D01*
X520348Y278361D01*
X520338Y278321D01*
X520323Y278281D01*
X520303Y278241D01*
X520288Y278206D01*
X520268Y278166D01*
X520168Y278026D01*
X520138Y277996D01*
Y275866D01*
X520128Y275741D01*
X520088Y275616D01*
X520028Y275506D01*
X519948Y275406D01*
X519848Y275326D01*
X519738Y275266D01*
X519613Y275226D01*
X519488Y275216D01*
X519363Y275226D01*
X519238Y275266D01*
X519128Y275326D01*
X519028Y275406D01*
X518948Y275506D01*
X518888Y275616D01*
X518848Y275741D01*
X518838Y275866D01*
Y277991D01*
X518808Y278021D01*
X518783Y278056D01*
X518753Y278091D01*
X518733Y278126D01*
X518708Y278161D01*
X518668Y278241D01*
X518623Y278361D01*
X518613Y278401D01*
X518603Y278446D01*
X518598Y278486D01*
X518588Y278531D01*
Y278701D01*
X518598Y278746D01*
X518603Y278786D01*
X518613Y278831D01*
X518623Y278871D01*
X518668Y278991D01*
X518708Y279071D01*
X518733Y279106D01*
X518753Y279141D01*
X518783Y279176D01*
X518808Y279211D01*
X518838Y279241D01*
Y281666D01*
X518848Y281791D01*
X518888Y281916D01*
X518948Y282026D01*
X519028Y282126D01*
X519128Y282206D01*
X519238Y282266D01*
X519363Y282306D01*
X519488Y282316D01*
G37*
G36*
G01X524213D02*
X524338Y282306D01*
X524463Y282266D01*
X524573Y282206D01*
X524673Y282126D01*
X524753Y282026D01*
X524813Y281916D01*
X524853Y281791D01*
X524863Y281666D01*
Y279236D01*
X524893Y279206D01*
X524993Y279066D01*
X525013Y279026D01*
X525028Y278991D01*
X525048Y278951D01*
X525063Y278911D01*
X525073Y278871D01*
X525088Y278826D01*
X525093Y278786D01*
X525103Y278746D01*
X525108Y278701D01*
Y278661D01*
X525113Y278616D01*
X525108Y278571D01*
Y278531D01*
X525103Y278486D01*
X525093Y278446D01*
X525088Y278406D01*
X525073Y278361D01*
X525063Y278321D01*
X525048Y278281D01*
X525028Y278241D01*
X525013Y278206D01*
X524993Y278166D01*
X524893Y278026D01*
X524863Y277996D01*
Y275866D01*
X524853Y275741D01*
X524813Y275616D01*
X524753Y275506D01*
X524673Y275406D01*
X524573Y275326D01*
X524463Y275266D01*
X524338Y275226D01*
X524213Y275216D01*
X524088Y275226D01*
X523963Y275266D01*
X523853Y275326D01*
X523753Y275406D01*
X523673Y275506D01*
X523613Y275616D01*
X523573Y275741D01*
X523563Y275866D01*
Y277991D01*
X523533Y278021D01*
X523508Y278056D01*
X523478Y278091D01*
X523458Y278126D01*
X523433Y278161D01*
X523393Y278241D01*
X523348Y278361D01*
X523338Y278401D01*
X523328Y278446D01*
X523323Y278486D01*
X523313Y278531D01*
Y278701D01*
X523323Y278746D01*
X523328Y278786D01*
X523338Y278831D01*
X523348Y278871D01*
X523393Y278991D01*
X523433Y279071D01*
X523458Y279106D01*
X523478Y279141D01*
X523508Y279176D01*
X523533Y279211D01*
X523563Y279241D01*
Y281666D01*
X523573Y281791D01*
X523613Y281916D01*
X523673Y282026D01*
X523753Y282126D01*
X523853Y282206D01*
X523963Y282266D01*
X524088Y282306D01*
X524213Y282316D01*
G37*
G36*
G01X528937D02*
X529062Y282306D01*
X529187Y282266D01*
X529297Y282206D01*
X529397Y282126D01*
X529477Y282026D01*
X529537Y281916D01*
X529577Y281791D01*
X529587Y281666D01*
Y279236D01*
X529617Y279206D01*
X529717Y279066D01*
X529737Y279026D01*
X529752Y278991D01*
X529772Y278951D01*
X529787Y278911D01*
X529797Y278871D01*
X529812Y278826D01*
X529817Y278786D01*
X529827Y278746D01*
X529832Y278701D01*
Y278661D01*
X529837Y278616D01*
X529832Y278571D01*
Y278531D01*
X529827Y278486D01*
X529817Y278446D01*
X529812Y278406D01*
X529797Y278361D01*
X529787Y278321D01*
X529772Y278281D01*
X529752Y278241D01*
X529737Y278206D01*
X529717Y278166D01*
X529617Y278026D01*
X529587Y277996D01*
Y275866D01*
X529577Y275741D01*
X529537Y275616D01*
X529477Y275506D01*
X529397Y275406D01*
X529297Y275326D01*
X529187Y275266D01*
X529062Y275226D01*
X528937Y275216D01*
X528812Y275226D01*
X528687Y275266D01*
X528577Y275326D01*
X528477Y275406D01*
X528397Y275506D01*
X528337Y275616D01*
X528297Y275741D01*
X528287Y275866D01*
Y277991D01*
X528257Y278021D01*
X528232Y278056D01*
X528202Y278091D01*
X528182Y278126D01*
X528157Y278161D01*
X528117Y278241D01*
X528072Y278361D01*
X528062Y278401D01*
X528052Y278446D01*
X528047Y278486D01*
X528037Y278531D01*
Y278701D01*
X528047Y278746D01*
X528052Y278786D01*
X528062Y278831D01*
X528072Y278871D01*
X528117Y278991D01*
X528157Y279071D01*
X528182Y279106D01*
X528202Y279141D01*
X528232Y279176D01*
X528257Y279211D01*
X528287Y279241D01*
Y281666D01*
X528297Y281791D01*
X528337Y281916D01*
X528397Y282026D01*
X528477Y282126D01*
X528577Y282206D01*
X528687Y282266D01*
X528812Y282306D01*
X528937Y282316D01*
G37*
G36*
G01X533662D02*
X533787Y282306D01*
X533912Y282266D01*
X534022Y282206D01*
X534122Y282126D01*
X534202Y282026D01*
X534262Y281916D01*
X534302Y281791D01*
X534312Y281666D01*
Y279236D01*
X534342Y279206D01*
X534442Y279066D01*
X534462Y279026D01*
X534477Y278991D01*
X534497Y278951D01*
X534512Y278911D01*
X534522Y278871D01*
X534537Y278826D01*
X534542Y278786D01*
X534552Y278746D01*
X534557Y278701D01*
Y278661D01*
X534562Y278616D01*
X534557Y278571D01*
Y278531D01*
X534552Y278486D01*
X534542Y278446D01*
X534537Y278406D01*
X534522Y278361D01*
X534512Y278321D01*
X534497Y278281D01*
X534477Y278241D01*
X534462Y278206D01*
X534442Y278166D01*
X534342Y278026D01*
X534312Y277996D01*
Y275866D01*
X534302Y275741D01*
X534262Y275616D01*
X534202Y275506D01*
X534122Y275406D01*
X534022Y275326D01*
X533912Y275266D01*
X533787Y275226D01*
X533662Y275216D01*
X533537Y275226D01*
X533412Y275266D01*
X533302Y275326D01*
X533202Y275406D01*
X533122Y275506D01*
X533062Y275616D01*
X533022Y275741D01*
X533012Y275866D01*
Y277991D01*
X532982Y278021D01*
X532957Y278056D01*
X532927Y278091D01*
X532907Y278126D01*
X532882Y278161D01*
X532842Y278241D01*
X532797Y278361D01*
X532787Y278401D01*
X532777Y278446D01*
X532772Y278486D01*
X532762Y278531D01*
Y278701D01*
X532772Y278746D01*
X532777Y278786D01*
X532787Y278831D01*
X532797Y278871D01*
X532842Y278991D01*
X532882Y279071D01*
X532907Y279106D01*
X532927Y279141D01*
X532957Y279176D01*
X532982Y279211D01*
X533012Y279241D01*
Y281666D01*
X533022Y281791D01*
X533062Y281916D01*
X533122Y282026D01*
X533202Y282126D01*
X533302Y282206D01*
X533412Y282266D01*
X533537Y282306D01*
X533662Y282316D01*
G37*
G36*
G01X538386D02*
X538511Y282306D01*
X538636Y282266D01*
X538746Y282206D01*
X538846Y282126D01*
X538926Y282026D01*
X538986Y281916D01*
X539026Y281791D01*
X539036Y281666D01*
Y279236D01*
X539066Y279206D01*
X539166Y279066D01*
X539186Y279026D01*
X539201Y278991D01*
X539221Y278951D01*
X539236Y278911D01*
X539246Y278871D01*
X539261Y278826D01*
X539266Y278786D01*
X539276Y278746D01*
X539281Y278701D01*
Y278661D01*
X539286Y278616D01*
X539281Y278571D01*
Y278531D01*
X539276Y278486D01*
X539266Y278446D01*
X539261Y278406D01*
X539246Y278361D01*
X539236Y278321D01*
X539221Y278281D01*
X539201Y278241D01*
X539186Y278206D01*
X539166Y278166D01*
X539066Y278026D01*
X539036Y277996D01*
Y275866D01*
X539026Y275741D01*
X538986Y275616D01*
X538926Y275506D01*
X538846Y275406D01*
X538746Y275326D01*
X538636Y275266D01*
X538511Y275226D01*
X538386Y275216D01*
X538261Y275226D01*
X538136Y275266D01*
X538026Y275326D01*
X537926Y275406D01*
X537846Y275506D01*
X537786Y275616D01*
X537746Y275741D01*
X537736Y275866D01*
Y277991D01*
X537706Y278021D01*
X537681Y278056D01*
X537651Y278091D01*
X537631Y278126D01*
X537606Y278161D01*
X537566Y278241D01*
X537521Y278361D01*
X537511Y278401D01*
X537501Y278446D01*
X537496Y278486D01*
X537486Y278531D01*
Y278701D01*
X537496Y278746D01*
X537501Y278786D01*
X537511Y278831D01*
X537521Y278871D01*
X537566Y278991D01*
X537606Y279071D01*
X537631Y279106D01*
X537651Y279141D01*
X537681Y279176D01*
X537706Y279211D01*
X537736Y279241D01*
Y281666D01*
X537746Y281791D01*
X537786Y281916D01*
X537846Y282026D01*
X537926Y282126D01*
X538026Y282206D01*
X538136Y282266D01*
X538261Y282306D01*
X538386Y282316D01*
G37*
G36*
G01X543110D02*
X543235Y282306D01*
X543360Y282266D01*
X543470Y282206D01*
X543570Y282126D01*
X543650Y282026D01*
X543710Y281916D01*
X543750Y281791D01*
X543760Y281666D01*
Y279236D01*
X543790Y279206D01*
X543890Y279066D01*
X543910Y279026D01*
X543925Y278991D01*
X543945Y278951D01*
X543960Y278911D01*
X543970Y278871D01*
X543985Y278826D01*
X543990Y278786D01*
X544000Y278746D01*
X544005Y278701D01*
Y278661D01*
X544010Y278616D01*
X544005Y278571D01*
Y278531D01*
X544000Y278486D01*
X543990Y278446D01*
X543985Y278406D01*
X543970Y278361D01*
X543960Y278321D01*
X543945Y278281D01*
X543925Y278241D01*
X543910Y278206D01*
X543890Y278166D01*
X543790Y278026D01*
X543760Y277996D01*
Y275866D01*
X543750Y275741D01*
X543710Y275616D01*
X543650Y275506D01*
X543570Y275406D01*
X543470Y275326D01*
X543360Y275266D01*
X543235Y275226D01*
X543110Y275216D01*
X542985Y275226D01*
X542860Y275266D01*
X542750Y275326D01*
X542650Y275406D01*
X542570Y275506D01*
X542510Y275616D01*
X542470Y275741D01*
X542460Y275866D01*
Y277991D01*
X542430Y278021D01*
X542405Y278056D01*
X542375Y278091D01*
X542355Y278126D01*
X542330Y278161D01*
X542290Y278241D01*
X542245Y278361D01*
X542235Y278401D01*
X542225Y278446D01*
X542220Y278486D01*
X542210Y278531D01*
Y278701D01*
X542220Y278746D01*
X542225Y278786D01*
X542235Y278831D01*
X542245Y278871D01*
X542290Y278991D01*
X542330Y279071D01*
X542355Y279106D01*
X542375Y279141D01*
X542405Y279176D01*
X542430Y279211D01*
X542460Y279241D01*
Y281666D01*
X542470Y281791D01*
X542510Y281916D01*
X542570Y282026D01*
X542650Y282126D01*
X542750Y282206D01*
X542860Y282266D01*
X542985Y282306D01*
X543110Y282316D01*
G37*
G36*
G01X547835D02*
X547960Y282306D01*
X548085Y282266D01*
X548195Y282206D01*
X548295Y282126D01*
X548375Y282026D01*
X548435Y281916D01*
X548475Y281791D01*
X548485Y281666D01*
Y279236D01*
X548515Y279206D01*
X548615Y279066D01*
X548635Y279026D01*
X548650Y278991D01*
X548670Y278951D01*
X548685Y278911D01*
X548695Y278871D01*
X548710Y278826D01*
X548715Y278786D01*
X548725Y278746D01*
X548730Y278701D01*
Y278661D01*
X548735Y278616D01*
X548730Y278571D01*
Y278531D01*
X548725Y278486D01*
X548715Y278446D01*
X548710Y278406D01*
X548695Y278361D01*
X548685Y278321D01*
X548670Y278281D01*
X548650Y278241D01*
X548635Y278206D01*
X548615Y278166D01*
X548515Y278026D01*
X548485Y277996D01*
Y275866D01*
X548475Y275741D01*
X548435Y275616D01*
X548375Y275506D01*
X548295Y275406D01*
X548195Y275326D01*
X548085Y275266D01*
X547960Y275226D01*
X547835Y275216D01*
X547710Y275226D01*
X547585Y275266D01*
X547475Y275326D01*
X547375Y275406D01*
X547295Y275506D01*
X547235Y275616D01*
X547195Y275741D01*
X547185Y275866D01*
Y277991D01*
X547155Y278021D01*
X547130Y278056D01*
X547100Y278091D01*
X547080Y278126D01*
X547055Y278161D01*
X547015Y278241D01*
X546970Y278361D01*
X546960Y278401D01*
X546950Y278446D01*
X546945Y278486D01*
X546935Y278531D01*
Y278701D01*
X546945Y278746D01*
X546950Y278786D01*
X546960Y278831D01*
X546970Y278871D01*
X547015Y278991D01*
X547055Y279071D01*
X547080Y279106D01*
X547100Y279141D01*
X547130Y279176D01*
X547155Y279211D01*
X547185Y279241D01*
Y281666D01*
X547195Y281791D01*
X547235Y281916D01*
X547295Y282026D01*
X547375Y282126D01*
X547475Y282206D01*
X547585Y282266D01*
X547710Y282306D01*
X547835Y282316D01*
G37*
G36*
G01X552559D02*
X552684Y282306D01*
X552809Y282266D01*
X552919Y282206D01*
X553019Y282126D01*
X553099Y282026D01*
X553159Y281916D01*
X553199Y281791D01*
X553209Y281666D01*
Y279236D01*
X553239Y279206D01*
X553339Y279066D01*
X553359Y279026D01*
X553374Y278991D01*
X553394Y278951D01*
X553409Y278911D01*
X553419Y278871D01*
X553434Y278826D01*
X553439Y278786D01*
X553449Y278746D01*
X553454Y278701D01*
Y278661D01*
X553459Y278616D01*
X553454Y278571D01*
Y278531D01*
X553449Y278486D01*
X553439Y278446D01*
X553434Y278406D01*
X553419Y278361D01*
X553409Y278321D01*
X553394Y278281D01*
X553374Y278241D01*
X553359Y278206D01*
X553339Y278166D01*
X553239Y278026D01*
X553209Y277996D01*
Y275866D01*
X553199Y275741D01*
X553159Y275616D01*
X553099Y275506D01*
X553019Y275406D01*
X552919Y275326D01*
X552809Y275266D01*
X552684Y275226D01*
X552559Y275216D01*
X552434Y275226D01*
X552309Y275266D01*
X552199Y275326D01*
X552099Y275406D01*
X552019Y275506D01*
X551959Y275616D01*
X551919Y275741D01*
X551909Y275866D01*
Y277991D01*
X551879Y278021D01*
X551854Y278056D01*
X551824Y278091D01*
X551804Y278126D01*
X551779Y278161D01*
X551739Y278241D01*
X551694Y278361D01*
X551684Y278401D01*
X551674Y278446D01*
X551669Y278486D01*
X551659Y278531D01*
Y278701D01*
X551669Y278746D01*
X551674Y278786D01*
X551684Y278831D01*
X551694Y278871D01*
X551739Y278991D01*
X551779Y279071D01*
X551804Y279106D01*
X551824Y279141D01*
X551854Y279176D01*
X551879Y279211D01*
X551909Y279241D01*
Y281666D01*
X551919Y281791D01*
X551959Y281916D01*
X552019Y282026D01*
X552099Y282126D01*
X552199Y282206D01*
X552309Y282266D01*
X552434Y282306D01*
X552559Y282316D01*
G37*
G36*
G01X557284D02*
X557409Y282306D01*
X557534Y282266D01*
X557644Y282206D01*
X557744Y282126D01*
X557824Y282026D01*
X557884Y281916D01*
X557924Y281791D01*
X557934Y281666D01*
Y279236D01*
X557964Y279206D01*
X558064Y279066D01*
X558084Y279026D01*
X558099Y278991D01*
X558119Y278951D01*
X558134Y278911D01*
X558144Y278871D01*
X558159Y278826D01*
X558164Y278786D01*
X558174Y278746D01*
X558179Y278701D01*
Y278661D01*
X558184Y278616D01*
X558179Y278571D01*
Y278531D01*
X558174Y278486D01*
X558164Y278446D01*
X558159Y278406D01*
X558144Y278361D01*
X558134Y278321D01*
X558119Y278281D01*
X558099Y278241D01*
X558084Y278206D01*
X558064Y278166D01*
X557964Y278026D01*
X557934Y277996D01*
Y275866D01*
X557924Y275741D01*
X557884Y275616D01*
X557824Y275506D01*
X557744Y275406D01*
X557644Y275326D01*
X557534Y275266D01*
X557409Y275226D01*
X557284Y275216D01*
X557159Y275226D01*
X557034Y275266D01*
X556924Y275326D01*
X556824Y275406D01*
X556744Y275506D01*
X556684Y275616D01*
X556644Y275741D01*
X556634Y275866D01*
Y277991D01*
X556604Y278021D01*
X556579Y278056D01*
X556549Y278091D01*
X556529Y278126D01*
X556504Y278161D01*
X556464Y278241D01*
X556419Y278361D01*
X556409Y278401D01*
X556399Y278446D01*
X556394Y278486D01*
X556384Y278531D01*
Y278701D01*
X556394Y278746D01*
X556399Y278786D01*
X556409Y278831D01*
X556419Y278871D01*
X556464Y278991D01*
X556504Y279071D01*
X556529Y279106D01*
X556549Y279141D01*
X556579Y279176D01*
X556604Y279211D01*
X556634Y279241D01*
Y281666D01*
X556644Y281791D01*
X556684Y281916D01*
X556744Y282026D01*
X556824Y282126D01*
X556924Y282206D01*
X557034Y282266D01*
X557159Y282306D01*
X557284Y282316D01*
G37*
G36*
G01X562008D02*
X562133Y282306D01*
X562258Y282266D01*
X562368Y282206D01*
X562468Y282126D01*
X562548Y282026D01*
X562608Y281916D01*
X562648Y281791D01*
X562658Y281666D01*
Y279236D01*
X562688Y279206D01*
X562788Y279066D01*
X562808Y279026D01*
X562823Y278991D01*
X562843Y278951D01*
X562858Y278911D01*
X562868Y278871D01*
X562883Y278826D01*
X562888Y278786D01*
X562898Y278746D01*
X562903Y278701D01*
Y278661D01*
X562908Y278616D01*
X562903Y278571D01*
Y278531D01*
X562898Y278486D01*
X562888Y278446D01*
X562883Y278406D01*
X562868Y278361D01*
X562858Y278321D01*
X562843Y278281D01*
X562823Y278241D01*
X562808Y278206D01*
X562788Y278166D01*
X562688Y278026D01*
X562658Y277996D01*
Y275866D01*
X562648Y275741D01*
X562608Y275616D01*
X562548Y275506D01*
X562468Y275406D01*
X562368Y275326D01*
X562258Y275266D01*
X562133Y275226D01*
X562008Y275216D01*
X561883Y275226D01*
X561758Y275266D01*
X561648Y275326D01*
X561548Y275406D01*
X561468Y275506D01*
X561408Y275616D01*
X561368Y275741D01*
X561358Y275866D01*
Y277991D01*
X561328Y278021D01*
X561303Y278056D01*
X561273Y278091D01*
X561253Y278126D01*
X561228Y278161D01*
X561188Y278241D01*
X561143Y278361D01*
X561133Y278401D01*
X561123Y278446D01*
X561118Y278486D01*
X561108Y278531D01*
Y278701D01*
X561118Y278746D01*
X561123Y278786D01*
X561133Y278831D01*
X561143Y278871D01*
X561188Y278991D01*
X561228Y279071D01*
X561253Y279106D01*
X561273Y279141D01*
X561303Y279176D01*
X561328Y279211D01*
X561358Y279241D01*
Y281666D01*
X561368Y281791D01*
X561408Y281916D01*
X561468Y282026D01*
X561548Y282126D01*
X561648Y282206D01*
X561758Y282266D01*
X561883Y282306D01*
X562008Y282316D01*
G37*
G36*
G01X566733D02*
X566858Y282306D01*
X566983Y282266D01*
X567093Y282206D01*
X567193Y282126D01*
X567273Y282026D01*
X567333Y281916D01*
X567373Y281791D01*
X567383Y281666D01*
Y279236D01*
X567413Y279206D01*
X567513Y279066D01*
X567533Y279026D01*
X567548Y278991D01*
X567568Y278951D01*
X567583Y278911D01*
X567593Y278871D01*
X567608Y278826D01*
X567613Y278786D01*
X567623Y278746D01*
X567628Y278701D01*
Y278661D01*
X567633Y278616D01*
X567628Y278571D01*
Y278531D01*
X567623Y278486D01*
X567613Y278446D01*
X567608Y278406D01*
X567593Y278361D01*
X567583Y278321D01*
X567568Y278281D01*
X567548Y278241D01*
X567533Y278206D01*
X567513Y278166D01*
X567413Y278026D01*
X567383Y277996D01*
Y275866D01*
X567373Y275741D01*
X567333Y275616D01*
X567273Y275506D01*
X567193Y275406D01*
X567093Y275326D01*
X566983Y275266D01*
X566858Y275226D01*
X566733Y275216D01*
X566608Y275226D01*
X566483Y275266D01*
X566373Y275326D01*
X566273Y275406D01*
X566193Y275506D01*
X566133Y275616D01*
X566093Y275741D01*
X566083Y275866D01*
Y277991D01*
X566053Y278021D01*
X566028Y278056D01*
X565998Y278091D01*
X565978Y278126D01*
X565953Y278161D01*
X565913Y278241D01*
X565868Y278361D01*
X565858Y278401D01*
X565848Y278446D01*
X565843Y278486D01*
X565833Y278531D01*
Y278701D01*
X565843Y278746D01*
X565848Y278786D01*
X565858Y278831D01*
X565868Y278871D01*
X565913Y278991D01*
X565953Y279071D01*
X565978Y279106D01*
X565998Y279141D01*
X566028Y279176D01*
X566053Y279211D01*
X566083Y279241D01*
Y281666D01*
X566093Y281791D01*
X566133Y281916D01*
X566193Y282026D01*
X566273Y282126D01*
X566373Y282206D01*
X566483Y282266D01*
X566608Y282306D01*
X566733Y282316D01*
G37*
G36*
G01X571457D02*
X571582Y282306D01*
X571707Y282266D01*
X571817Y282206D01*
X571917Y282126D01*
X571997Y282026D01*
X572057Y281916D01*
X572097Y281791D01*
X572107Y281666D01*
Y279236D01*
X572137Y279206D01*
X572237Y279066D01*
X572257Y279026D01*
X572272Y278991D01*
X572292Y278951D01*
X572307Y278911D01*
X572317Y278871D01*
X572332Y278826D01*
X572337Y278786D01*
X572347Y278746D01*
X572352Y278701D01*
Y278661D01*
X572357Y278616D01*
X572352Y278571D01*
Y278531D01*
X572347Y278486D01*
X572337Y278446D01*
X572332Y278406D01*
X572317Y278361D01*
X572307Y278321D01*
X572292Y278281D01*
X572272Y278241D01*
X572257Y278206D01*
X572237Y278166D01*
X572137Y278026D01*
X572107Y277996D01*
Y275866D01*
X572097Y275741D01*
X572057Y275616D01*
X571997Y275506D01*
X571917Y275406D01*
X571817Y275326D01*
X571707Y275266D01*
X571582Y275226D01*
X571457Y275216D01*
X571332Y275226D01*
X571207Y275266D01*
X571097Y275326D01*
X570997Y275406D01*
X570917Y275506D01*
X570857Y275616D01*
X570817Y275741D01*
X570807Y275866D01*
Y277991D01*
X570777Y278021D01*
X570752Y278056D01*
X570722Y278091D01*
X570702Y278126D01*
X570677Y278161D01*
X570637Y278241D01*
X570592Y278361D01*
X570582Y278401D01*
X570572Y278446D01*
X570567Y278486D01*
X570557Y278531D01*
Y278701D01*
X570567Y278746D01*
X570572Y278786D01*
X570582Y278831D01*
X570592Y278871D01*
X570637Y278991D01*
X570677Y279071D01*
X570702Y279106D01*
X570722Y279141D01*
X570752Y279176D01*
X570777Y279211D01*
X570807Y279241D01*
Y281666D01*
X570817Y281791D01*
X570857Y281916D01*
X570917Y282026D01*
X570997Y282126D01*
X571097Y282206D01*
X571207Y282266D01*
X571332Y282306D01*
X571457Y282316D01*
G37*
G36*
G01X576181D02*
X576306Y282306D01*
X576431Y282266D01*
X576541Y282206D01*
X576641Y282126D01*
X576721Y282026D01*
X576781Y281916D01*
X576821Y281791D01*
X576831Y281666D01*
Y279236D01*
X576861Y279206D01*
X576961Y279066D01*
X576981Y279026D01*
X576996Y278991D01*
X577016Y278951D01*
X577031Y278911D01*
X577041Y278871D01*
X577056Y278826D01*
X577061Y278786D01*
X577071Y278746D01*
X577076Y278701D01*
Y278661D01*
X577081Y278616D01*
X577076Y278571D01*
Y278531D01*
X577071Y278486D01*
X577061Y278446D01*
X577056Y278406D01*
X577041Y278361D01*
X577031Y278321D01*
X577016Y278281D01*
X576996Y278241D01*
X576981Y278206D01*
X576961Y278166D01*
X576861Y278026D01*
X576831Y277996D01*
Y275866D01*
X576821Y275741D01*
X576781Y275616D01*
X576721Y275506D01*
X576641Y275406D01*
X576541Y275326D01*
X576431Y275266D01*
X576306Y275226D01*
X576181Y275216D01*
X576056Y275226D01*
X575931Y275266D01*
X575821Y275326D01*
X575721Y275406D01*
X575641Y275506D01*
X575581Y275616D01*
X575541Y275741D01*
X575531Y275866D01*
Y277991D01*
X575501Y278021D01*
X575476Y278056D01*
X575446Y278091D01*
X575426Y278126D01*
X575401Y278161D01*
X575361Y278241D01*
X575316Y278361D01*
X575306Y278401D01*
X575296Y278446D01*
X575291Y278486D01*
X575281Y278531D01*
Y278701D01*
X575291Y278746D01*
X575296Y278786D01*
X575306Y278831D01*
X575316Y278871D01*
X575361Y278991D01*
X575401Y279071D01*
X575426Y279106D01*
X575446Y279141D01*
X575476Y279176D01*
X575501Y279211D01*
X575531Y279241D01*
Y281666D01*
X575541Y281791D01*
X575581Y281916D01*
X575641Y282026D01*
X575721Y282126D01*
X575821Y282206D01*
X575931Y282266D01*
X576056Y282306D01*
X576181Y282316D01*
G37*
G36*
G01X580906D02*
X581031Y282306D01*
X581156Y282266D01*
X581266Y282206D01*
X581366Y282126D01*
X581446Y282026D01*
X581506Y281916D01*
X581546Y281791D01*
X581556Y281666D01*
Y279236D01*
X581586Y279206D01*
X581686Y279066D01*
X581706Y279026D01*
X581721Y278991D01*
X581741Y278951D01*
X581756Y278911D01*
X581766Y278871D01*
X581781Y278826D01*
X581786Y278786D01*
X581796Y278746D01*
X581801Y278701D01*
Y278661D01*
X581806Y278616D01*
X581801Y278571D01*
Y278531D01*
X581796Y278486D01*
X581786Y278446D01*
X581781Y278406D01*
X581766Y278361D01*
X581756Y278321D01*
X581741Y278281D01*
X581721Y278241D01*
X581706Y278206D01*
X581686Y278166D01*
X581586Y278026D01*
X581556Y277996D01*
Y275866D01*
X581546Y275741D01*
X581506Y275616D01*
X581446Y275506D01*
X581366Y275406D01*
X581266Y275326D01*
X581156Y275266D01*
X581031Y275226D01*
X580906Y275216D01*
X580781Y275226D01*
X580656Y275266D01*
X580546Y275326D01*
X580446Y275406D01*
X580366Y275506D01*
X580306Y275616D01*
X580266Y275741D01*
X580256Y275866D01*
Y277991D01*
X580226Y278021D01*
X580201Y278056D01*
X580171Y278091D01*
X580151Y278126D01*
X580126Y278161D01*
X580086Y278241D01*
X580041Y278361D01*
X580031Y278401D01*
X580021Y278446D01*
X580016Y278486D01*
X580006Y278531D01*
Y278701D01*
X580016Y278746D01*
X580021Y278786D01*
X580031Y278831D01*
X580041Y278871D01*
X580086Y278991D01*
X580126Y279071D01*
X580151Y279106D01*
X580171Y279141D01*
X580201Y279176D01*
X580226Y279211D01*
X580256Y279241D01*
Y281666D01*
X580266Y281791D01*
X580306Y281916D01*
X580366Y282026D01*
X580446Y282126D01*
X580546Y282206D01*
X580656Y282266D01*
X580781Y282306D01*
X580906Y282316D01*
G37*
G36*
G01X585630D02*
X585755Y282306D01*
X585880Y282266D01*
X585990Y282206D01*
X586090Y282126D01*
X586170Y282026D01*
X586230Y281916D01*
X586270Y281791D01*
X586280Y281666D01*
Y279236D01*
X586310Y279206D01*
X586410Y279066D01*
X586430Y279026D01*
X586445Y278991D01*
X586465Y278951D01*
X586480Y278911D01*
X586490Y278871D01*
X586505Y278826D01*
X586510Y278786D01*
X586520Y278746D01*
X586525Y278701D01*
Y278661D01*
X586530Y278616D01*
X586525Y278571D01*
Y278531D01*
X586520Y278486D01*
X586510Y278446D01*
X586505Y278406D01*
X586490Y278361D01*
X586480Y278321D01*
X586465Y278281D01*
X586445Y278241D01*
X586430Y278206D01*
X586410Y278166D01*
X586310Y278026D01*
X586280Y277996D01*
Y275866D01*
X586270Y275741D01*
X586230Y275616D01*
X586170Y275506D01*
X586090Y275406D01*
X585990Y275326D01*
X585880Y275266D01*
X585755Y275226D01*
X585630Y275216D01*
X585505Y275226D01*
X585380Y275266D01*
X585270Y275326D01*
X585170Y275406D01*
X585090Y275506D01*
X585030Y275616D01*
X584990Y275741D01*
X584980Y275866D01*
Y277991D01*
X584950Y278021D01*
X584925Y278056D01*
X584895Y278091D01*
X584875Y278126D01*
X584850Y278161D01*
X584810Y278241D01*
X584765Y278361D01*
X584755Y278401D01*
X584745Y278446D01*
X584740Y278486D01*
X584730Y278531D01*
Y278701D01*
X584740Y278746D01*
X584745Y278786D01*
X584755Y278831D01*
X584765Y278871D01*
X584810Y278991D01*
X584850Y279071D01*
X584875Y279106D01*
X584895Y279141D01*
X584925Y279176D01*
X584950Y279211D01*
X584980Y279241D01*
Y281666D01*
X584990Y281791D01*
X585030Y281916D01*
X585090Y282026D01*
X585170Y282126D01*
X585270Y282206D01*
X585380Y282266D01*
X585505Y282306D01*
X585630Y282316D01*
G37*
G36*
G01X590355D02*
X590480Y282306D01*
X590605Y282266D01*
X590715Y282206D01*
X590815Y282126D01*
X590895Y282026D01*
X590955Y281916D01*
X590995Y281791D01*
X591005Y281666D01*
Y279236D01*
X591035Y279206D01*
X591135Y279066D01*
X591155Y279026D01*
X591170Y278991D01*
X591190Y278951D01*
X591205Y278911D01*
X591215Y278871D01*
X591230Y278826D01*
X591235Y278786D01*
X591245Y278746D01*
X591250Y278701D01*
Y278661D01*
X591255Y278616D01*
X591250Y278571D01*
Y278531D01*
X591245Y278486D01*
X591235Y278446D01*
X591230Y278406D01*
X591215Y278361D01*
X591205Y278321D01*
X591190Y278281D01*
X591170Y278241D01*
X591155Y278206D01*
X591135Y278166D01*
X591035Y278026D01*
X591005Y277996D01*
Y275866D01*
X590995Y275741D01*
X590955Y275616D01*
X590895Y275506D01*
X590815Y275406D01*
X590715Y275326D01*
X590605Y275266D01*
X590480Y275226D01*
X590355Y275216D01*
X590230Y275226D01*
X590105Y275266D01*
X589995Y275326D01*
X589895Y275406D01*
X589815Y275506D01*
X589755Y275616D01*
X589715Y275741D01*
X589705Y275866D01*
Y277991D01*
X589675Y278021D01*
X589650Y278056D01*
X589620Y278091D01*
X589600Y278126D01*
X589575Y278161D01*
X589535Y278241D01*
X589490Y278361D01*
X589480Y278401D01*
X589470Y278446D01*
X589465Y278486D01*
X589455Y278531D01*
Y278701D01*
X589465Y278746D01*
X589470Y278786D01*
X589480Y278831D01*
X589490Y278871D01*
X589535Y278991D01*
X589575Y279071D01*
X589600Y279106D01*
X589620Y279141D01*
X589650Y279176D01*
X589675Y279211D01*
X589705Y279241D01*
Y281666D01*
X589715Y281791D01*
X589755Y281916D01*
X589815Y282026D01*
X589895Y282126D01*
X589995Y282206D01*
X590105Y282266D01*
X590230Y282306D01*
X590355Y282316D01*
G37*
G36*
G01X595079D02*
X595204Y282306D01*
X595329Y282266D01*
X595439Y282206D01*
X595539Y282126D01*
X595619Y282026D01*
X595679Y281916D01*
X595719Y281791D01*
X595729Y281666D01*
Y279236D01*
X595759Y279206D01*
X595859Y279066D01*
X595879Y279026D01*
X595894Y278991D01*
X595914Y278951D01*
X595929Y278911D01*
X595939Y278871D01*
X595954Y278826D01*
X595959Y278786D01*
X595969Y278746D01*
X595974Y278701D01*
Y278661D01*
X595979Y278616D01*
X595974Y278571D01*
Y278531D01*
X595969Y278486D01*
X595959Y278446D01*
X595954Y278406D01*
X595939Y278361D01*
X595929Y278321D01*
X595914Y278281D01*
X595894Y278241D01*
X595879Y278206D01*
X595859Y278166D01*
X595759Y278026D01*
X595729Y277996D01*
Y275866D01*
X595719Y275741D01*
X595679Y275616D01*
X595619Y275506D01*
X595539Y275406D01*
X595439Y275326D01*
X595329Y275266D01*
X595204Y275226D01*
X595079Y275216D01*
X594954Y275226D01*
X594829Y275266D01*
X594719Y275326D01*
X594619Y275406D01*
X594539Y275506D01*
X594479Y275616D01*
X594439Y275741D01*
X594429Y275866D01*
Y277991D01*
X594399Y278021D01*
X594374Y278056D01*
X594344Y278091D01*
X594324Y278126D01*
X594299Y278161D01*
X594259Y278241D01*
X594214Y278361D01*
X594204Y278401D01*
X594194Y278446D01*
X594189Y278486D01*
X594179Y278531D01*
Y278701D01*
X594189Y278746D01*
X594194Y278786D01*
X594204Y278831D01*
X594214Y278871D01*
X594259Y278991D01*
X594299Y279071D01*
X594324Y279106D01*
X594344Y279141D01*
X594374Y279176D01*
X594399Y279211D01*
X594429Y279241D01*
Y281666D01*
X594439Y281791D01*
X594479Y281916D01*
X594539Y282026D01*
X594619Y282126D01*
X594719Y282206D01*
X594829Y282266D01*
X594954Y282306D01*
X595079Y282316D01*
G37*
G36*
G01X599803D02*
X599928Y282306D01*
X600053Y282266D01*
X600163Y282206D01*
X600263Y282126D01*
X600343Y282026D01*
X600403Y281916D01*
X600443Y281791D01*
X600453Y281666D01*
Y279236D01*
X600483Y279206D01*
X600583Y279066D01*
X600603Y279026D01*
X600618Y278991D01*
X600638Y278951D01*
X600653Y278911D01*
X600663Y278871D01*
X600678Y278826D01*
X600683Y278786D01*
X600693Y278746D01*
X600698Y278701D01*
Y278661D01*
X600703Y278616D01*
X600698Y278571D01*
Y278531D01*
X600693Y278486D01*
X600683Y278446D01*
X600678Y278406D01*
X600663Y278361D01*
X600653Y278321D01*
X600638Y278281D01*
X600618Y278241D01*
X600603Y278206D01*
X600583Y278166D01*
X600483Y278026D01*
X600453Y277996D01*
Y275866D01*
X600443Y275741D01*
X600403Y275616D01*
X600343Y275506D01*
X600263Y275406D01*
X600163Y275326D01*
X600053Y275266D01*
X599928Y275226D01*
X599803Y275216D01*
X599678Y275226D01*
X599553Y275266D01*
X599443Y275326D01*
X599343Y275406D01*
X599263Y275506D01*
X599203Y275616D01*
X599163Y275741D01*
X599153Y275866D01*
Y277991D01*
X599123Y278021D01*
X599098Y278056D01*
X599068Y278091D01*
X599048Y278126D01*
X599023Y278161D01*
X598983Y278241D01*
X598938Y278361D01*
X598928Y278401D01*
X598918Y278446D01*
X598913Y278486D01*
X598903Y278531D01*
Y278701D01*
X598913Y278746D01*
X598918Y278786D01*
X598928Y278831D01*
X598938Y278871D01*
X598983Y278991D01*
X599023Y279071D01*
X599048Y279106D01*
X599068Y279141D01*
X599098Y279176D01*
X599123Y279211D01*
X599153Y279241D01*
Y281666D01*
X599163Y281791D01*
X599203Y281916D01*
X599263Y282026D01*
X599343Y282126D01*
X599443Y282206D01*
X599553Y282266D01*
X599678Y282306D01*
X599803Y282316D01*
G37*
G36*
G01X604528D02*
X604653Y282306D01*
X604778Y282266D01*
X604888Y282206D01*
X604988Y282126D01*
X605068Y282026D01*
X605128Y281916D01*
X605168Y281791D01*
X605178Y281666D01*
Y279236D01*
X605208Y279206D01*
X605308Y279066D01*
X605328Y279026D01*
X605343Y278991D01*
X605363Y278951D01*
X605378Y278911D01*
X605388Y278871D01*
X605403Y278826D01*
X605408Y278786D01*
X605418Y278746D01*
X605423Y278701D01*
Y278661D01*
X605428Y278616D01*
X605423Y278571D01*
Y278531D01*
X605418Y278486D01*
X605408Y278446D01*
X605403Y278406D01*
X605388Y278361D01*
X605378Y278321D01*
X605363Y278281D01*
X605343Y278241D01*
X605328Y278206D01*
X605308Y278166D01*
X605208Y278026D01*
X605178Y277996D01*
Y275866D01*
X605168Y275741D01*
X605128Y275616D01*
X605068Y275506D01*
X604988Y275406D01*
X604888Y275326D01*
X604778Y275266D01*
X604653Y275226D01*
X604528Y275216D01*
X604403Y275226D01*
X604278Y275266D01*
X604168Y275326D01*
X604068Y275406D01*
X603988Y275506D01*
X603928Y275616D01*
X603888Y275741D01*
X603878Y275866D01*
Y277991D01*
X603848Y278021D01*
X603823Y278056D01*
X603793Y278091D01*
X603773Y278126D01*
X603748Y278161D01*
X603708Y278241D01*
X603663Y278361D01*
X603653Y278401D01*
X603643Y278446D01*
X603638Y278486D01*
X603628Y278531D01*
Y278701D01*
X603638Y278746D01*
X603643Y278786D01*
X603653Y278831D01*
X603663Y278871D01*
X603708Y278991D01*
X603748Y279071D01*
X603773Y279106D01*
X603793Y279141D01*
X603823Y279176D01*
X603848Y279211D01*
X603878Y279241D01*
Y281666D01*
X603888Y281791D01*
X603928Y281916D01*
X603988Y282026D01*
X604068Y282126D01*
X604168Y282206D01*
X604278Y282266D01*
X604403Y282306D01*
X604528Y282316D01*
G37*
G36*
G01X609252D02*
X609377Y282306D01*
X609502Y282266D01*
X609612Y282206D01*
X609712Y282126D01*
X609792Y282026D01*
X609852Y281916D01*
X609892Y281791D01*
X609902Y281666D01*
Y279236D01*
X609932Y279206D01*
X610032Y279066D01*
X610052Y279026D01*
X610067Y278991D01*
X610087Y278951D01*
X610102Y278911D01*
X610112Y278871D01*
X610127Y278826D01*
X610132Y278786D01*
X610142Y278746D01*
X610147Y278701D01*
Y278661D01*
X610152Y278616D01*
X610147Y278571D01*
Y278531D01*
X610142Y278486D01*
X610132Y278446D01*
X610127Y278406D01*
X610112Y278361D01*
X610102Y278321D01*
X610087Y278281D01*
X610067Y278241D01*
X610052Y278206D01*
X610032Y278166D01*
X609932Y278026D01*
X609902Y277996D01*
Y275866D01*
X609892Y275741D01*
X609852Y275616D01*
X609792Y275506D01*
X609712Y275406D01*
X609612Y275326D01*
X609502Y275266D01*
X609377Y275226D01*
X609252Y275216D01*
X609127Y275226D01*
X609002Y275266D01*
X608892Y275326D01*
X608792Y275406D01*
X608712Y275506D01*
X608652Y275616D01*
X608612Y275741D01*
X608602Y275866D01*
Y277991D01*
X608572Y278021D01*
X608547Y278056D01*
X608517Y278091D01*
X608497Y278126D01*
X608472Y278161D01*
X608432Y278241D01*
X608387Y278361D01*
X608377Y278401D01*
X608367Y278446D01*
X608362Y278486D01*
X608352Y278531D01*
Y278701D01*
X608362Y278746D01*
X608367Y278786D01*
X608377Y278831D01*
X608387Y278871D01*
X608432Y278991D01*
X608472Y279071D01*
X608497Y279106D01*
X608517Y279141D01*
X608547Y279176D01*
X608572Y279211D01*
X608602Y279241D01*
Y281666D01*
X608612Y281791D01*
X608652Y281916D01*
X608712Y282026D01*
X608792Y282126D01*
X608892Y282206D01*
X609002Y282266D01*
X609127Y282306D01*
X609252Y282316D01*
G37*
G36*
G01X613977D02*
X614102Y282306D01*
X614227Y282266D01*
X614337Y282206D01*
X614437Y282126D01*
X614517Y282026D01*
X614577Y281916D01*
X614617Y281791D01*
X614627Y281666D01*
Y279236D01*
X614657Y279206D01*
X614757Y279066D01*
X614777Y279026D01*
X614792Y278991D01*
X614812Y278951D01*
X614827Y278911D01*
X614837Y278871D01*
X614852Y278826D01*
X614857Y278786D01*
X614867Y278746D01*
X614872Y278701D01*
Y278661D01*
X614877Y278616D01*
X614872Y278571D01*
Y278531D01*
X614867Y278486D01*
X614857Y278446D01*
X614852Y278406D01*
X614837Y278361D01*
X614827Y278321D01*
X614812Y278281D01*
X614792Y278241D01*
X614777Y278206D01*
X614757Y278166D01*
X614657Y278026D01*
X614627Y277996D01*
Y275866D01*
X614617Y275741D01*
X614577Y275616D01*
X614517Y275506D01*
X614437Y275406D01*
X614337Y275326D01*
X614227Y275266D01*
X614102Y275226D01*
X613977Y275216D01*
X613852Y275226D01*
X613727Y275266D01*
X613617Y275326D01*
X613517Y275406D01*
X613437Y275506D01*
X613377Y275616D01*
X613337Y275741D01*
X613327Y275866D01*
Y277991D01*
X613297Y278021D01*
X613272Y278056D01*
X613242Y278091D01*
X613222Y278126D01*
X613197Y278161D01*
X613157Y278241D01*
X613112Y278361D01*
X613102Y278401D01*
X613092Y278446D01*
X613087Y278486D01*
X613077Y278531D01*
Y278701D01*
X613087Y278746D01*
X613092Y278786D01*
X613102Y278831D01*
X613112Y278871D01*
X613157Y278991D01*
X613197Y279071D01*
X613222Y279106D01*
X613242Y279141D01*
X613272Y279176D01*
X613297Y279211D01*
X613327Y279241D01*
Y281666D01*
X613337Y281791D01*
X613377Y281916D01*
X613437Y282026D01*
X613517Y282126D01*
X613617Y282206D01*
X613727Y282266D01*
X613852Y282306D01*
X613977Y282316D01*
G37*
G36*
G01X618701D02*
X618826Y282306D01*
X618951Y282266D01*
X619061Y282206D01*
X619161Y282126D01*
X619241Y282026D01*
X619301Y281916D01*
X619341Y281791D01*
X619351Y281666D01*
Y279236D01*
X619381Y279206D01*
X619481Y279066D01*
X619501Y279026D01*
X619516Y278991D01*
X619536Y278951D01*
X619551Y278911D01*
X619561Y278871D01*
X619576Y278826D01*
X619581Y278786D01*
X619591Y278746D01*
X619596Y278701D01*
Y278661D01*
X619601Y278616D01*
X619596Y278571D01*
Y278531D01*
X619591Y278486D01*
X619581Y278446D01*
X619576Y278406D01*
X619561Y278361D01*
X619551Y278321D01*
X619536Y278281D01*
X619516Y278241D01*
X619501Y278206D01*
X619481Y278166D01*
X619381Y278026D01*
X619351Y277996D01*
Y275866D01*
X619341Y275741D01*
X619301Y275616D01*
X619241Y275506D01*
X619161Y275406D01*
X619061Y275326D01*
X618951Y275266D01*
X618826Y275226D01*
X618701Y275216D01*
X618576Y275226D01*
X618451Y275266D01*
X618341Y275326D01*
X618241Y275406D01*
X618161Y275506D01*
X618101Y275616D01*
X618061Y275741D01*
X618051Y275866D01*
Y277991D01*
X618021Y278021D01*
X617996Y278056D01*
X617966Y278091D01*
X617946Y278126D01*
X617921Y278161D01*
X617881Y278241D01*
X617836Y278361D01*
X617826Y278401D01*
X617816Y278446D01*
X617811Y278486D01*
X617801Y278531D01*
Y278701D01*
X617811Y278746D01*
X617816Y278786D01*
X617826Y278831D01*
X617836Y278871D01*
X617881Y278991D01*
X617921Y279071D01*
X617946Y279106D01*
X617966Y279141D01*
X617996Y279176D01*
X618021Y279211D01*
X618051Y279241D01*
Y281666D01*
X618061Y281791D01*
X618101Y281916D01*
X618161Y282026D01*
X618241Y282126D01*
X618341Y282206D01*
X618451Y282266D01*
X618576Y282306D01*
X618701Y282316D01*
G37*
G36*
G01X623425D02*
X623550Y282306D01*
X623675Y282266D01*
X623785Y282206D01*
X623885Y282126D01*
X623965Y282026D01*
X624025Y281916D01*
X624065Y281791D01*
X624075Y281666D01*
Y279236D01*
X624105Y279206D01*
X624205Y279066D01*
X624225Y279026D01*
X624240Y278991D01*
X624260Y278951D01*
X624275Y278911D01*
X624285Y278871D01*
X624300Y278826D01*
X624305Y278786D01*
X624315Y278746D01*
X624320Y278701D01*
Y278661D01*
X624325Y278616D01*
X624320Y278571D01*
Y278531D01*
X624315Y278486D01*
X624305Y278446D01*
X624300Y278406D01*
X624285Y278361D01*
X624275Y278321D01*
X624260Y278281D01*
X624240Y278241D01*
X624225Y278206D01*
X624205Y278166D01*
X624105Y278026D01*
X624075Y277996D01*
Y275866D01*
X624065Y275741D01*
X624025Y275616D01*
X623965Y275506D01*
X623885Y275406D01*
X623785Y275326D01*
X623675Y275266D01*
X623550Y275226D01*
X623425Y275216D01*
X623300Y275226D01*
X623175Y275266D01*
X623065Y275326D01*
X622965Y275406D01*
X622885Y275506D01*
X622825Y275616D01*
X622785Y275741D01*
X622775Y275866D01*
Y277991D01*
X622745Y278021D01*
X622720Y278056D01*
X622690Y278091D01*
X622670Y278126D01*
X622645Y278161D01*
X622605Y278241D01*
X622560Y278361D01*
X622550Y278401D01*
X622540Y278446D01*
X622535Y278486D01*
X622525Y278531D01*
Y278701D01*
X622535Y278746D01*
X622540Y278786D01*
X622550Y278831D01*
X622560Y278871D01*
X622605Y278991D01*
X622645Y279071D01*
X622670Y279106D01*
X622690Y279141D01*
X622720Y279176D01*
X622745Y279211D01*
X622775Y279241D01*
Y281666D01*
X622785Y281791D01*
X622825Y281916D01*
X622885Y282026D01*
X622965Y282126D01*
X623065Y282206D01*
X623175Y282266D01*
X623300Y282306D01*
X623425Y282316D01*
G37*
G36*
G01X628150D02*
X628275Y282306D01*
X628400Y282266D01*
X628510Y282206D01*
X628610Y282126D01*
X628690Y282026D01*
X628750Y281916D01*
X628790Y281791D01*
X628800Y281666D01*
Y279236D01*
X628830Y279206D01*
X628930Y279066D01*
X628950Y279026D01*
X628965Y278991D01*
X628985Y278951D01*
X629000Y278911D01*
X629010Y278871D01*
X629025Y278826D01*
X629030Y278786D01*
X629040Y278746D01*
X629045Y278701D01*
Y278661D01*
X629050Y278616D01*
X629045Y278571D01*
Y278531D01*
X629040Y278486D01*
X629030Y278446D01*
X629025Y278406D01*
X629010Y278361D01*
X629000Y278321D01*
X628985Y278281D01*
X628965Y278241D01*
X628950Y278206D01*
X628930Y278166D01*
X628830Y278026D01*
X628800Y277996D01*
Y275866D01*
X628790Y275741D01*
X628750Y275616D01*
X628690Y275506D01*
X628610Y275406D01*
X628510Y275326D01*
X628400Y275266D01*
X628275Y275226D01*
X628150Y275216D01*
X628025Y275226D01*
X627900Y275266D01*
X627790Y275326D01*
X627690Y275406D01*
X627610Y275506D01*
X627550Y275616D01*
X627510Y275741D01*
X627500Y275866D01*
Y277991D01*
X627470Y278021D01*
X627445Y278056D01*
X627415Y278091D01*
X627395Y278126D01*
X627370Y278161D01*
X627330Y278241D01*
X627285Y278361D01*
X627275Y278401D01*
X627265Y278446D01*
X627260Y278486D01*
X627250Y278531D01*
Y278701D01*
X627260Y278746D01*
X627265Y278786D01*
X627275Y278831D01*
X627285Y278871D01*
X627330Y278991D01*
X627370Y279071D01*
X627395Y279106D01*
X627415Y279141D01*
X627445Y279176D01*
X627470Y279211D01*
X627500Y279241D01*
Y281666D01*
X627510Y281791D01*
X627550Y281916D01*
X627610Y282026D01*
X627690Y282126D01*
X627790Y282206D01*
X627900Y282266D01*
X628025Y282306D01*
X628150Y282316D01*
G37*
G36*
G01X632874D02*
X632999Y282306D01*
X633124Y282266D01*
X633234Y282206D01*
X633334Y282126D01*
X633414Y282026D01*
X633474Y281916D01*
X633514Y281791D01*
X633524Y281666D01*
Y279236D01*
X633554Y279206D01*
X633654Y279066D01*
X633674Y279026D01*
X633689Y278991D01*
X633709Y278951D01*
X633724Y278911D01*
X633734Y278871D01*
X633749Y278826D01*
X633754Y278786D01*
X633764Y278746D01*
X633769Y278701D01*
Y278661D01*
X633774Y278616D01*
X633769Y278571D01*
Y278531D01*
X633764Y278486D01*
X633754Y278446D01*
X633749Y278406D01*
X633734Y278361D01*
X633724Y278321D01*
X633709Y278281D01*
X633689Y278241D01*
X633674Y278206D01*
X633654Y278166D01*
X633554Y278026D01*
X633524Y277996D01*
Y275866D01*
X633514Y275741D01*
X633474Y275616D01*
X633414Y275506D01*
X633334Y275406D01*
X633234Y275326D01*
X633124Y275266D01*
X632999Y275226D01*
X632874Y275216D01*
X632749Y275226D01*
X632624Y275266D01*
X632514Y275326D01*
X632414Y275406D01*
X632334Y275506D01*
X632274Y275616D01*
X632234Y275741D01*
X632224Y275866D01*
Y277991D01*
X632194Y278021D01*
X632169Y278056D01*
X632139Y278091D01*
X632119Y278126D01*
X632094Y278161D01*
X632054Y278241D01*
X632009Y278361D01*
X631999Y278401D01*
X631989Y278446D01*
X631984Y278486D01*
X631974Y278531D01*
Y278701D01*
X631984Y278746D01*
X631989Y278786D01*
X631999Y278831D01*
X632009Y278871D01*
X632054Y278991D01*
X632094Y279071D01*
X632119Y279106D01*
X632139Y279141D01*
X632169Y279176D01*
X632194Y279211D01*
X632224Y279241D01*
Y281666D01*
X632234Y281791D01*
X632274Y281916D01*
X632334Y282026D01*
X632414Y282126D01*
X632514Y282206D01*
X632624Y282266D01*
X632749Y282306D01*
X632874Y282316D01*
G37*
G36*
G01X637599D02*
X637724Y282306D01*
X637849Y282266D01*
X637959Y282206D01*
X638059Y282126D01*
X638139Y282026D01*
X638199Y281916D01*
X638239Y281791D01*
X638249Y281666D01*
Y279236D01*
X638279Y279206D01*
X638379Y279066D01*
X638399Y279026D01*
X638414Y278991D01*
X638434Y278951D01*
X638449Y278911D01*
X638459Y278871D01*
X638474Y278826D01*
X638479Y278786D01*
X638489Y278746D01*
X638494Y278701D01*
Y278661D01*
X638499Y278616D01*
X638494Y278571D01*
Y278531D01*
X638489Y278486D01*
X638479Y278446D01*
X638474Y278406D01*
X638459Y278361D01*
X638449Y278321D01*
X638434Y278281D01*
X638414Y278241D01*
X638399Y278206D01*
X638379Y278166D01*
X638279Y278026D01*
X638249Y277996D01*
Y275866D01*
X638239Y275741D01*
X638199Y275616D01*
X638139Y275506D01*
X638059Y275406D01*
X637959Y275326D01*
X637849Y275266D01*
X637724Y275226D01*
X637599Y275216D01*
X637474Y275226D01*
X637349Y275266D01*
X637239Y275326D01*
X637139Y275406D01*
X637059Y275506D01*
X636999Y275616D01*
X636959Y275741D01*
X636949Y275866D01*
Y277991D01*
X636919Y278021D01*
X636894Y278056D01*
X636864Y278091D01*
X636844Y278126D01*
X636819Y278161D01*
X636779Y278241D01*
X636734Y278361D01*
X636724Y278401D01*
X636714Y278446D01*
X636709Y278486D01*
X636699Y278531D01*
Y278701D01*
X636709Y278746D01*
X636714Y278786D01*
X636724Y278831D01*
X636734Y278871D01*
X636779Y278991D01*
X636819Y279071D01*
X636844Y279106D01*
X636864Y279141D01*
X636894Y279176D01*
X636919Y279211D01*
X636949Y279241D01*
Y281666D01*
X636959Y281791D01*
X636999Y281916D01*
X637059Y282026D01*
X637139Y282126D01*
X637239Y282206D01*
X637349Y282266D01*
X637474Y282306D01*
X637599Y282316D01*
G37*
G36*
G01X642323D02*
X642448Y282306D01*
X642573Y282266D01*
X642683Y282206D01*
X642783Y282126D01*
X642863Y282026D01*
X642923Y281916D01*
X642963Y281791D01*
X642973Y281666D01*
Y279236D01*
X643003Y279206D01*
X643103Y279066D01*
X643123Y279026D01*
X643138Y278991D01*
X643158Y278951D01*
X643173Y278911D01*
X643183Y278871D01*
X643198Y278826D01*
X643203Y278786D01*
X643213Y278746D01*
X643218Y278701D01*
Y278661D01*
X643223Y278616D01*
X643218Y278571D01*
Y278531D01*
X643213Y278486D01*
X643203Y278446D01*
X643198Y278406D01*
X643183Y278361D01*
X643173Y278321D01*
X643158Y278281D01*
X643138Y278241D01*
X643123Y278206D01*
X643103Y278166D01*
X643003Y278026D01*
X642973Y277996D01*
Y275866D01*
X642963Y275741D01*
X642923Y275616D01*
X642863Y275506D01*
X642783Y275406D01*
X642683Y275326D01*
X642573Y275266D01*
X642448Y275226D01*
X642323Y275216D01*
X642198Y275226D01*
X642073Y275266D01*
X641963Y275326D01*
X641863Y275406D01*
X641783Y275506D01*
X641723Y275616D01*
X641683Y275741D01*
X641673Y275866D01*
Y277991D01*
X641643Y278021D01*
X641618Y278056D01*
X641588Y278091D01*
X641568Y278126D01*
X641543Y278161D01*
X641503Y278241D01*
X641458Y278361D01*
X641448Y278401D01*
X641438Y278446D01*
X641433Y278486D01*
X641423Y278531D01*
Y278701D01*
X641433Y278746D01*
X641438Y278786D01*
X641448Y278831D01*
X641458Y278871D01*
X641503Y278991D01*
X641543Y279071D01*
X641568Y279106D01*
X641588Y279141D01*
X641618Y279176D01*
X641643Y279211D01*
X641673Y279241D01*
Y281666D01*
X641683Y281791D01*
X641723Y281916D01*
X641783Y282026D01*
X641863Y282126D01*
X641963Y282206D01*
X642073Y282266D01*
X642198Y282306D01*
X642323Y282316D01*
G37*
G36*
G01X647047D02*
X647172Y282306D01*
X647297Y282266D01*
X647407Y282206D01*
X647507Y282126D01*
X647587Y282026D01*
X647647Y281916D01*
X647687Y281791D01*
X647697Y281666D01*
Y279236D01*
X647727Y279206D01*
X647827Y279066D01*
X647847Y279026D01*
X647862Y278991D01*
X647882Y278951D01*
X647897Y278911D01*
X647907Y278871D01*
X647922Y278826D01*
X647927Y278786D01*
X647937Y278746D01*
X647942Y278701D01*
Y278661D01*
X647947Y278616D01*
X647942Y278571D01*
Y278531D01*
X647937Y278486D01*
X647927Y278446D01*
X647922Y278406D01*
X647907Y278361D01*
X647897Y278321D01*
X647882Y278281D01*
X647862Y278241D01*
X647847Y278206D01*
X647827Y278166D01*
X647727Y278026D01*
X647697Y277996D01*
Y275866D01*
X647687Y275741D01*
X647647Y275616D01*
X647587Y275506D01*
X647507Y275406D01*
X647407Y275326D01*
X647297Y275266D01*
X647172Y275226D01*
X647047Y275216D01*
X646922Y275226D01*
X646797Y275266D01*
X646687Y275326D01*
X646587Y275406D01*
X646507Y275506D01*
X646447Y275616D01*
X646407Y275741D01*
X646397Y275866D01*
Y277991D01*
X646367Y278021D01*
X646342Y278056D01*
X646312Y278091D01*
X646292Y278126D01*
X646267Y278161D01*
X646227Y278241D01*
X646182Y278361D01*
X646172Y278401D01*
X646162Y278446D01*
X646157Y278486D01*
X646147Y278531D01*
Y278701D01*
X646157Y278746D01*
X646162Y278786D01*
X646172Y278831D01*
X646182Y278871D01*
X646227Y278991D01*
X646267Y279071D01*
X646292Y279106D01*
X646312Y279141D01*
X646342Y279176D01*
X646367Y279211D01*
X646397Y279241D01*
Y281666D01*
X646407Y281791D01*
X646447Y281916D01*
X646507Y282026D01*
X646587Y282126D01*
X646687Y282206D01*
X646797Y282266D01*
X646922Y282306D01*
X647047Y282316D01*
G37*
G36*
G01X651772D02*
X651897Y282306D01*
X652022Y282266D01*
X652132Y282206D01*
X652232Y282126D01*
X652312Y282026D01*
X652372Y281916D01*
X652412Y281791D01*
X652422Y281666D01*
Y279236D01*
X652452Y279206D01*
X652552Y279066D01*
X652572Y279026D01*
X652587Y278991D01*
X652607Y278951D01*
X652622Y278911D01*
X652632Y278871D01*
X652647Y278826D01*
X652652Y278786D01*
X652662Y278746D01*
X652667Y278701D01*
Y278661D01*
X652672Y278616D01*
X652667Y278571D01*
Y278531D01*
X652662Y278486D01*
X652652Y278446D01*
X652647Y278406D01*
X652632Y278361D01*
X652622Y278321D01*
X652607Y278281D01*
X652587Y278241D01*
X652572Y278206D01*
X652552Y278166D01*
X652452Y278026D01*
X652422Y277996D01*
Y275866D01*
X652412Y275741D01*
X652372Y275616D01*
X652312Y275506D01*
X652232Y275406D01*
X652132Y275326D01*
X652022Y275266D01*
X651897Y275226D01*
X651772Y275216D01*
X651647Y275226D01*
X651522Y275266D01*
X651412Y275326D01*
X651312Y275406D01*
X651232Y275506D01*
X651172Y275616D01*
X651132Y275741D01*
X651122Y275866D01*
Y277991D01*
X651092Y278021D01*
X651067Y278056D01*
X651037Y278091D01*
X651017Y278126D01*
X650992Y278161D01*
X650952Y278241D01*
X650907Y278361D01*
X650897Y278401D01*
X650887Y278446D01*
X650882Y278486D01*
X650872Y278531D01*
Y278701D01*
X650882Y278746D01*
X650887Y278786D01*
X650897Y278831D01*
X650907Y278871D01*
X650952Y278991D01*
X650992Y279071D01*
X651017Y279106D01*
X651037Y279141D01*
X651067Y279176D01*
X651092Y279211D01*
X651122Y279241D01*
Y281666D01*
X651132Y281791D01*
X651172Y281916D01*
X651232Y282026D01*
X651312Y282126D01*
X651412Y282206D01*
X651522Y282266D01*
X651647Y282306D01*
X651772Y282316D01*
G37*
G36*
G01X665945D02*
X666070Y282306D01*
X666195Y282266D01*
X666305Y282206D01*
X666405Y282126D01*
X666485Y282026D01*
X666545Y281916D01*
X666585Y281791D01*
X666595Y281666D01*
Y279236D01*
X666625Y279206D01*
X666725Y279066D01*
X666745Y279026D01*
X666760Y278991D01*
X666780Y278951D01*
X666795Y278911D01*
X666805Y278871D01*
X666820Y278826D01*
X666825Y278786D01*
X666835Y278746D01*
X666840Y278701D01*
Y278661D01*
X666845Y278616D01*
X666840Y278571D01*
Y278531D01*
X666835Y278486D01*
X666825Y278446D01*
X666820Y278406D01*
X666805Y278361D01*
X666795Y278321D01*
X666780Y278281D01*
X666760Y278241D01*
X666745Y278206D01*
X666725Y278166D01*
X666625Y278026D01*
X666595Y277996D01*
Y275866D01*
X666585Y275741D01*
X666545Y275616D01*
X666485Y275506D01*
X666405Y275406D01*
X666305Y275326D01*
X666195Y275266D01*
X666070Y275226D01*
X665945Y275216D01*
X665820Y275226D01*
X665695Y275266D01*
X665585Y275326D01*
X665485Y275406D01*
X665405Y275506D01*
X665345Y275616D01*
X665305Y275741D01*
X665295Y275866D01*
Y277991D01*
X665265Y278021D01*
X665240Y278056D01*
X665210Y278091D01*
X665190Y278126D01*
X665165Y278161D01*
X665125Y278241D01*
X665080Y278361D01*
X665070Y278401D01*
X665060Y278446D01*
X665055Y278486D01*
X665045Y278531D01*
Y278701D01*
X665055Y278746D01*
X665060Y278786D01*
X665070Y278831D01*
X665080Y278871D01*
X665125Y278991D01*
X665165Y279071D01*
X665190Y279106D01*
X665210Y279141D01*
X665240Y279176D01*
X665265Y279211D01*
X665295Y279241D01*
Y281666D01*
X665305Y281791D01*
X665345Y281916D01*
X665405Y282026D01*
X665485Y282126D01*
X665585Y282206D01*
X665695Y282266D01*
X665820Y282306D01*
X665945Y282316D01*
G37*
G36*
G01X670670D02*
X670795Y282306D01*
X670920Y282266D01*
X671030Y282206D01*
X671130Y282126D01*
X671210Y282026D01*
X671270Y281916D01*
X671310Y281791D01*
X671320Y281666D01*
Y279236D01*
X671350Y279206D01*
X671450Y279066D01*
X671470Y279026D01*
X671485Y278991D01*
X671505Y278951D01*
X671520Y278911D01*
X671530Y278871D01*
X671545Y278826D01*
X671550Y278786D01*
X671560Y278746D01*
X671565Y278701D01*
Y278661D01*
X671570Y278616D01*
X671565Y278571D01*
Y278531D01*
X671560Y278486D01*
X671550Y278446D01*
X671545Y278406D01*
X671530Y278361D01*
X671520Y278321D01*
X671505Y278281D01*
X671485Y278241D01*
X671470Y278206D01*
X671450Y278166D01*
X671350Y278026D01*
X671320Y277996D01*
Y275866D01*
X671310Y275741D01*
X671270Y275616D01*
X671210Y275506D01*
X671130Y275406D01*
X671030Y275326D01*
X670920Y275266D01*
X670795Y275226D01*
X670670Y275216D01*
X670545Y275226D01*
X670420Y275266D01*
X670310Y275326D01*
X670210Y275406D01*
X670130Y275506D01*
X670070Y275616D01*
X670030Y275741D01*
X670020Y275866D01*
Y277991D01*
X669990Y278021D01*
X669965Y278056D01*
X669935Y278091D01*
X669915Y278126D01*
X669890Y278161D01*
X669850Y278241D01*
X669805Y278361D01*
X669795Y278401D01*
X669785Y278446D01*
X669780Y278486D01*
X669770Y278531D01*
Y278701D01*
X669780Y278746D01*
X669785Y278786D01*
X669795Y278831D01*
X669805Y278871D01*
X669850Y278991D01*
X669890Y279071D01*
X669915Y279106D01*
X669935Y279141D01*
X669965Y279176D01*
X669990Y279211D01*
X670020Y279241D01*
Y281666D01*
X670030Y281791D01*
X670070Y281916D01*
X670130Y282026D01*
X670210Y282126D01*
X670310Y282206D01*
X670420Y282266D01*
X670545Y282306D01*
X670670Y282316D01*
G37*
G36*
G01X675394D02*
X675519Y282306D01*
X675644Y282266D01*
X675754Y282206D01*
X675854Y282126D01*
X675934Y282026D01*
X675994Y281916D01*
X676034Y281791D01*
X676044Y281666D01*
Y279236D01*
X676074Y279206D01*
X676174Y279066D01*
X676194Y279026D01*
X676209Y278991D01*
X676229Y278951D01*
X676244Y278911D01*
X676254Y278871D01*
X676269Y278826D01*
X676274Y278786D01*
X676284Y278746D01*
X676289Y278701D01*
Y278661D01*
X676294Y278616D01*
X676289Y278571D01*
Y278531D01*
X676284Y278486D01*
X676274Y278446D01*
X676269Y278406D01*
X676254Y278361D01*
X676244Y278321D01*
X676229Y278281D01*
X676209Y278241D01*
X676194Y278206D01*
X676174Y278166D01*
X676074Y278026D01*
X676044Y277996D01*
Y275866D01*
X676034Y275741D01*
X675994Y275616D01*
X675934Y275506D01*
X675854Y275406D01*
X675754Y275326D01*
X675644Y275266D01*
X675519Y275226D01*
X675394Y275216D01*
X675269Y275226D01*
X675144Y275266D01*
X675034Y275326D01*
X674934Y275406D01*
X674854Y275506D01*
X674794Y275616D01*
X674754Y275741D01*
X674744Y275866D01*
Y277991D01*
X674714Y278021D01*
X674689Y278056D01*
X674659Y278091D01*
X674639Y278126D01*
X674614Y278161D01*
X674574Y278241D01*
X674529Y278361D01*
X674519Y278401D01*
X674509Y278446D01*
X674504Y278486D01*
X674494Y278531D01*
Y278701D01*
X674504Y278746D01*
X674509Y278786D01*
X674519Y278831D01*
X674529Y278871D01*
X674574Y278991D01*
X674614Y279071D01*
X674639Y279106D01*
X674659Y279141D01*
X674689Y279176D01*
X674714Y279211D01*
X674744Y279241D01*
Y281666D01*
X674754Y281791D01*
X674794Y281916D01*
X674854Y282026D01*
X674934Y282126D01*
X675034Y282206D01*
X675144Y282266D01*
X675269Y282306D01*
X675394Y282316D01*
G37*
G36*
G01X680118D02*
X680243Y282306D01*
X680368Y282266D01*
X680478Y282206D01*
X680578Y282126D01*
X680658Y282026D01*
X680718Y281916D01*
X680758Y281791D01*
X680768Y281666D01*
Y279236D01*
X680798Y279206D01*
X680898Y279066D01*
X680918Y279026D01*
X680933Y278991D01*
X680953Y278951D01*
X680968Y278911D01*
X680978Y278871D01*
X680993Y278826D01*
X680998Y278786D01*
X681008Y278746D01*
X681013Y278701D01*
Y278661D01*
X681018Y278616D01*
X681013Y278571D01*
Y278531D01*
X681008Y278486D01*
X680998Y278446D01*
X680993Y278406D01*
X680978Y278361D01*
X680968Y278321D01*
X680953Y278281D01*
X680933Y278241D01*
X680918Y278206D01*
X680898Y278166D01*
X680798Y278026D01*
X680768Y277996D01*
Y275866D01*
X680758Y275741D01*
X680718Y275616D01*
X680658Y275506D01*
X680578Y275406D01*
X680478Y275326D01*
X680368Y275266D01*
X680243Y275226D01*
X680118Y275216D01*
X679993Y275226D01*
X679868Y275266D01*
X679758Y275326D01*
X679658Y275406D01*
X679578Y275506D01*
X679518Y275616D01*
X679478Y275741D01*
X679468Y275866D01*
Y277991D01*
X679438Y278021D01*
X679413Y278056D01*
X679383Y278091D01*
X679363Y278126D01*
X679338Y278161D01*
X679298Y278241D01*
X679253Y278361D01*
X679243Y278401D01*
X679233Y278446D01*
X679228Y278486D01*
X679218Y278531D01*
Y278701D01*
X679228Y278746D01*
X679233Y278786D01*
X679243Y278831D01*
X679253Y278871D01*
X679298Y278991D01*
X679338Y279071D01*
X679363Y279106D01*
X679383Y279141D01*
X679413Y279176D01*
X679438Y279211D01*
X679468Y279241D01*
Y281666D01*
X679478Y281791D01*
X679518Y281916D01*
X679578Y282026D01*
X679658Y282126D01*
X679758Y282206D01*
X679868Y282266D01*
X679993Y282306D01*
X680118Y282316D01*
G37*
G36*
G01X684843D02*
X684968Y282306D01*
X685093Y282266D01*
X685203Y282206D01*
X685303Y282126D01*
X685383Y282026D01*
X685443Y281916D01*
X685483Y281791D01*
X685493Y281666D01*
Y279236D01*
X685523Y279206D01*
X685623Y279066D01*
X685643Y279026D01*
X685658Y278991D01*
X685678Y278951D01*
X685693Y278911D01*
X685703Y278871D01*
X685718Y278826D01*
X685723Y278786D01*
X685733Y278746D01*
X685738Y278701D01*
Y278661D01*
X685743Y278616D01*
X685738Y278571D01*
Y278531D01*
X685733Y278486D01*
X685723Y278446D01*
X685718Y278406D01*
X685703Y278361D01*
X685693Y278321D01*
X685678Y278281D01*
X685658Y278241D01*
X685643Y278206D01*
X685623Y278166D01*
X685523Y278026D01*
X685493Y277996D01*
Y275866D01*
X685483Y275741D01*
X685443Y275616D01*
X685383Y275506D01*
X685303Y275406D01*
X685203Y275326D01*
X685093Y275266D01*
X684968Y275226D01*
X684843Y275216D01*
X684718Y275226D01*
X684593Y275266D01*
X684483Y275326D01*
X684383Y275406D01*
X684303Y275506D01*
X684243Y275616D01*
X684203Y275741D01*
X684193Y275866D01*
Y277991D01*
X684163Y278021D01*
X684138Y278056D01*
X684108Y278091D01*
X684088Y278126D01*
X684063Y278161D01*
X684023Y278241D01*
X683978Y278361D01*
X683968Y278401D01*
X683958Y278446D01*
X683953Y278486D01*
X683943Y278531D01*
Y278701D01*
X683953Y278746D01*
X683958Y278786D01*
X683968Y278831D01*
X683978Y278871D01*
X684023Y278991D01*
X684063Y279071D01*
X684088Y279106D01*
X684108Y279141D01*
X684138Y279176D01*
X684163Y279211D01*
X684193Y279241D01*
Y281666D01*
X684203Y281791D01*
X684243Y281916D01*
X684303Y282026D01*
X684383Y282126D01*
X684483Y282206D01*
X684593Y282266D01*
X684718Y282306D01*
X684843Y282316D01*
G37*
G36*
G01X689567D02*
X689692Y282306D01*
X689817Y282266D01*
X689927Y282206D01*
X690027Y282126D01*
X690107Y282026D01*
X690167Y281916D01*
X690207Y281791D01*
X690217Y281666D01*
Y279236D01*
X690247Y279206D01*
X690347Y279066D01*
X690367Y279026D01*
X690382Y278991D01*
X690402Y278951D01*
X690417Y278911D01*
X690427Y278871D01*
X690442Y278826D01*
X690447Y278786D01*
X690457Y278746D01*
X690462Y278701D01*
Y278661D01*
X690467Y278616D01*
X690462Y278571D01*
Y278531D01*
X690457Y278486D01*
X690447Y278446D01*
X690442Y278406D01*
X690427Y278361D01*
X690417Y278321D01*
X690402Y278281D01*
X690382Y278241D01*
X690367Y278206D01*
X690347Y278166D01*
X690247Y278026D01*
X690217Y277996D01*
Y275866D01*
X690207Y275741D01*
X690167Y275616D01*
X690107Y275506D01*
X690027Y275406D01*
X689927Y275326D01*
X689817Y275266D01*
X689692Y275226D01*
X689567Y275216D01*
X689442Y275226D01*
X689317Y275266D01*
X689207Y275326D01*
X689107Y275406D01*
X689027Y275506D01*
X688967Y275616D01*
X688927Y275741D01*
X688917Y275866D01*
Y277991D01*
X688887Y278021D01*
X688862Y278056D01*
X688832Y278091D01*
X688812Y278126D01*
X688787Y278161D01*
X688747Y278241D01*
X688702Y278361D01*
X688692Y278401D01*
X688682Y278446D01*
X688677Y278486D01*
X688667Y278531D01*
Y278701D01*
X688677Y278746D01*
X688682Y278786D01*
X688692Y278831D01*
X688702Y278871D01*
X688747Y278991D01*
X688787Y279071D01*
X688812Y279106D01*
X688832Y279141D01*
X688862Y279176D01*
X688887Y279211D01*
X688917Y279241D01*
Y281666D01*
X688927Y281791D01*
X688967Y281916D01*
X689027Y282026D01*
X689107Y282126D01*
X689207Y282206D01*
X689317Y282266D01*
X689442Y282306D01*
X689567Y282316D01*
G37*
G36*
G01X694292D02*
X694417Y282306D01*
X694542Y282266D01*
X694652Y282206D01*
X694752Y282126D01*
X694832Y282026D01*
X694892Y281916D01*
X694932Y281791D01*
X694942Y281666D01*
Y279236D01*
X694972Y279206D01*
X695072Y279066D01*
X695092Y279026D01*
X695107Y278991D01*
X695127Y278951D01*
X695142Y278911D01*
X695152Y278871D01*
X695167Y278826D01*
X695172Y278786D01*
X695182Y278746D01*
X695187Y278701D01*
Y278661D01*
X695192Y278616D01*
X695187Y278571D01*
Y278531D01*
X695182Y278486D01*
X695172Y278446D01*
X695167Y278406D01*
X695152Y278361D01*
X695142Y278321D01*
X695127Y278281D01*
X695107Y278241D01*
X695092Y278206D01*
X695072Y278166D01*
X694972Y278026D01*
X694942Y277996D01*
Y275866D01*
X694932Y275741D01*
X694892Y275616D01*
X694832Y275506D01*
X694752Y275406D01*
X694652Y275326D01*
X694542Y275266D01*
X694417Y275226D01*
X694292Y275216D01*
X694167Y275226D01*
X694042Y275266D01*
X693932Y275326D01*
X693832Y275406D01*
X693752Y275506D01*
X693692Y275616D01*
X693652Y275741D01*
X693642Y275866D01*
Y277991D01*
X693612Y278021D01*
X693587Y278056D01*
X693557Y278091D01*
X693537Y278126D01*
X693512Y278161D01*
X693472Y278241D01*
X693427Y278361D01*
X693417Y278401D01*
X693407Y278446D01*
X693402Y278486D01*
X693392Y278531D01*
Y278701D01*
X693402Y278746D01*
X693407Y278786D01*
X693417Y278831D01*
X693427Y278871D01*
X693472Y278991D01*
X693512Y279071D01*
X693537Y279106D01*
X693557Y279141D01*
X693587Y279176D01*
X693612Y279211D01*
X693642Y279241D01*
Y281666D01*
X693652Y281791D01*
X693692Y281916D01*
X693752Y282026D01*
X693832Y282126D01*
X693932Y282206D01*
X694042Y282266D01*
X694167Y282306D01*
X694292Y282316D01*
G37*
G36*
G01X699016D02*
X699141Y282306D01*
X699266Y282266D01*
X699376Y282206D01*
X699476Y282126D01*
X699556Y282026D01*
X699616Y281916D01*
X699656Y281791D01*
X699666Y281666D01*
Y279236D01*
X699696Y279206D01*
X699796Y279066D01*
X699816Y279026D01*
X699831Y278991D01*
X699851Y278951D01*
X699866Y278911D01*
X699876Y278871D01*
X699891Y278826D01*
X699896Y278786D01*
X699906Y278746D01*
X699911Y278701D01*
Y278661D01*
X699916Y278616D01*
X699911Y278571D01*
Y278531D01*
X699906Y278486D01*
X699896Y278446D01*
X699891Y278406D01*
X699876Y278361D01*
X699866Y278321D01*
X699851Y278281D01*
X699831Y278241D01*
X699816Y278206D01*
X699796Y278166D01*
X699696Y278026D01*
X699666Y277996D01*
Y275866D01*
X699656Y275741D01*
X699616Y275616D01*
X699556Y275506D01*
X699476Y275406D01*
X699376Y275326D01*
X699266Y275266D01*
X699141Y275226D01*
X699016Y275216D01*
X698891Y275226D01*
X698766Y275266D01*
X698656Y275326D01*
X698556Y275406D01*
X698476Y275506D01*
X698416Y275616D01*
X698376Y275741D01*
X698366Y275866D01*
Y277991D01*
X698336Y278021D01*
X698311Y278056D01*
X698281Y278091D01*
X698261Y278126D01*
X698236Y278161D01*
X698196Y278241D01*
X698151Y278361D01*
X698141Y278401D01*
X698131Y278446D01*
X698126Y278486D01*
X698116Y278531D01*
Y278701D01*
X698126Y278746D01*
X698131Y278786D01*
X698141Y278831D01*
X698151Y278871D01*
X698196Y278991D01*
X698236Y279071D01*
X698261Y279106D01*
X698281Y279141D01*
X698311Y279176D01*
X698336Y279211D01*
X698366Y279241D01*
Y281666D01*
X698376Y281791D01*
X698416Y281916D01*
X698476Y282026D01*
X698556Y282126D01*
X698656Y282206D01*
X698766Y282266D01*
X698891Y282306D01*
X699016Y282316D01*
G37*
G36*
G01X703740D02*
X703865Y282306D01*
X703990Y282266D01*
X704100Y282206D01*
X704200Y282126D01*
X704280Y282026D01*
X704340Y281916D01*
X704380Y281791D01*
X704390Y281666D01*
Y279236D01*
X704420Y279206D01*
X704520Y279066D01*
X704540Y279026D01*
X704555Y278991D01*
X704575Y278951D01*
X704590Y278911D01*
X704600Y278871D01*
X704615Y278826D01*
X704620Y278786D01*
X704630Y278746D01*
X704635Y278701D01*
Y278661D01*
X704640Y278616D01*
X704635Y278571D01*
Y278531D01*
X704630Y278486D01*
X704620Y278446D01*
X704615Y278406D01*
X704600Y278361D01*
X704590Y278321D01*
X704575Y278281D01*
X704555Y278241D01*
X704540Y278206D01*
X704520Y278166D01*
X704420Y278026D01*
X704390Y277996D01*
Y275866D01*
X704380Y275741D01*
X704340Y275616D01*
X704280Y275506D01*
X704200Y275406D01*
X704100Y275326D01*
X703990Y275266D01*
X703865Y275226D01*
X703740Y275216D01*
X703615Y275226D01*
X703490Y275266D01*
X703380Y275326D01*
X703280Y275406D01*
X703200Y275506D01*
X703140Y275616D01*
X703100Y275741D01*
X703090Y275866D01*
Y277991D01*
X703060Y278021D01*
X703035Y278056D01*
X703005Y278091D01*
X702985Y278126D01*
X702960Y278161D01*
X702920Y278241D01*
X702875Y278361D01*
X702865Y278401D01*
X702855Y278446D01*
X702850Y278486D01*
X702840Y278531D01*
Y278701D01*
X702850Y278746D01*
X702855Y278786D01*
X702865Y278831D01*
X702875Y278871D01*
X702920Y278991D01*
X702960Y279071D01*
X702985Y279106D01*
X703005Y279141D01*
X703035Y279176D01*
X703060Y279211D01*
X703090Y279241D01*
Y281666D01*
X703100Y281791D01*
X703140Y281916D01*
X703200Y282026D01*
X703280Y282126D01*
X703380Y282206D01*
X703490Y282266D01*
X703615Y282306D01*
X703740Y282316D01*
G37*
G36*
G01X708465D02*
X708590Y282306D01*
X708715Y282266D01*
X708825Y282206D01*
X708925Y282126D01*
X709005Y282026D01*
X709065Y281916D01*
X709105Y281791D01*
X709115Y281666D01*
Y279236D01*
X709145Y279206D01*
X709245Y279066D01*
X709265Y279026D01*
X709280Y278991D01*
X709300Y278951D01*
X709315Y278911D01*
X709325Y278871D01*
X709340Y278826D01*
X709345Y278786D01*
X709355Y278746D01*
X709360Y278701D01*
Y278661D01*
X709365Y278616D01*
X709360Y278571D01*
Y278531D01*
X709355Y278486D01*
X709345Y278446D01*
X709340Y278406D01*
X709325Y278361D01*
X709315Y278321D01*
X709300Y278281D01*
X709280Y278241D01*
X709265Y278206D01*
X709245Y278166D01*
X709145Y278026D01*
X709115Y277996D01*
Y275866D01*
X709105Y275741D01*
X709065Y275616D01*
X709005Y275506D01*
X708925Y275406D01*
X708825Y275326D01*
X708715Y275266D01*
X708590Y275226D01*
X708465Y275216D01*
X708340Y275226D01*
X708215Y275266D01*
X708105Y275326D01*
X708005Y275406D01*
X707925Y275506D01*
X707865Y275616D01*
X707825Y275741D01*
X707815Y275866D01*
Y277991D01*
X707785Y278021D01*
X707760Y278056D01*
X707730Y278091D01*
X707710Y278126D01*
X707685Y278161D01*
X707645Y278241D01*
X707600Y278361D01*
X707590Y278401D01*
X707580Y278446D01*
X707575Y278486D01*
X707565Y278531D01*
Y278701D01*
X707575Y278746D01*
X707580Y278786D01*
X707590Y278831D01*
X707600Y278871D01*
X707645Y278991D01*
X707685Y279071D01*
X707710Y279106D01*
X707730Y279141D01*
X707760Y279176D01*
X707785Y279211D01*
X707815Y279241D01*
Y281666D01*
X707825Y281791D01*
X707865Y281916D01*
X707925Y282026D01*
X708005Y282126D01*
X708105Y282206D01*
X708215Y282266D01*
X708340Y282306D01*
X708465Y282316D01*
G37*
G36*
G01X713189D02*
X713314Y282306D01*
X713439Y282266D01*
X713549Y282206D01*
X713649Y282126D01*
X713729Y282026D01*
X713789Y281916D01*
X713829Y281791D01*
X713839Y281666D01*
Y279236D01*
X713869Y279206D01*
X713969Y279066D01*
X713989Y279026D01*
X714004Y278991D01*
X714024Y278951D01*
X714039Y278911D01*
X714049Y278871D01*
X714064Y278826D01*
X714069Y278786D01*
X714079Y278746D01*
X714084Y278701D01*
Y278661D01*
X714089Y278616D01*
X714084Y278571D01*
Y278531D01*
X714079Y278486D01*
X714069Y278446D01*
X714064Y278406D01*
X714049Y278361D01*
X714039Y278321D01*
X714024Y278281D01*
X714004Y278241D01*
X713989Y278206D01*
X713969Y278166D01*
X713869Y278026D01*
X713839Y277996D01*
Y275866D01*
X713829Y275741D01*
X713789Y275616D01*
X713729Y275506D01*
X713649Y275406D01*
X713549Y275326D01*
X713439Y275266D01*
X713314Y275226D01*
X713189Y275216D01*
X713064Y275226D01*
X712939Y275266D01*
X712829Y275326D01*
X712729Y275406D01*
X712649Y275506D01*
X712589Y275616D01*
X712549Y275741D01*
X712539Y275866D01*
Y277991D01*
X712509Y278021D01*
X712484Y278056D01*
X712454Y278091D01*
X712434Y278126D01*
X712409Y278161D01*
X712369Y278241D01*
X712324Y278361D01*
X712314Y278401D01*
X712304Y278446D01*
X712299Y278486D01*
X712289Y278531D01*
Y278701D01*
X712299Y278746D01*
X712304Y278786D01*
X712314Y278831D01*
X712324Y278871D01*
X712369Y278991D01*
X712409Y279071D01*
X712434Y279106D01*
X712454Y279141D01*
X712484Y279176D01*
X712509Y279211D01*
X712539Y279241D01*
Y281666D01*
X712549Y281791D01*
X712589Y281916D01*
X712649Y282026D01*
X712729Y282126D01*
X712829Y282206D01*
X712939Y282266D01*
X713064Y282306D01*
X713189Y282316D01*
G37*
G36*
G01X717914D02*
X718039Y282306D01*
X718164Y282266D01*
X718274Y282206D01*
X718374Y282126D01*
X718454Y282026D01*
X718514Y281916D01*
X718554Y281791D01*
X718564Y281666D01*
Y279236D01*
X718594Y279206D01*
X718694Y279066D01*
X718714Y279026D01*
X718729Y278991D01*
X718749Y278951D01*
X718764Y278911D01*
X718774Y278871D01*
X718789Y278826D01*
X718794Y278786D01*
X718804Y278746D01*
X718809Y278701D01*
Y278661D01*
X718814Y278616D01*
X718809Y278571D01*
Y278531D01*
X718804Y278486D01*
X718794Y278446D01*
X718789Y278406D01*
X718774Y278361D01*
X718764Y278321D01*
X718749Y278281D01*
X718729Y278241D01*
X718714Y278206D01*
X718694Y278166D01*
X718594Y278026D01*
X718564Y277996D01*
Y275866D01*
X718554Y275741D01*
X718514Y275616D01*
X718454Y275506D01*
X718374Y275406D01*
X718274Y275326D01*
X718164Y275266D01*
X718039Y275226D01*
X717914Y275216D01*
X717789Y275226D01*
X717664Y275266D01*
X717554Y275326D01*
X717454Y275406D01*
X717374Y275506D01*
X717314Y275616D01*
X717274Y275741D01*
X717264Y275866D01*
Y277991D01*
X717234Y278021D01*
X717209Y278056D01*
X717179Y278091D01*
X717159Y278126D01*
X717134Y278161D01*
X717094Y278241D01*
X717049Y278361D01*
X717039Y278401D01*
X717029Y278446D01*
X717024Y278486D01*
X717014Y278531D01*
Y278701D01*
X717024Y278746D01*
X717029Y278786D01*
X717039Y278831D01*
X717049Y278871D01*
X717094Y278991D01*
X717134Y279071D01*
X717159Y279106D01*
X717179Y279141D01*
X717209Y279176D01*
X717234Y279211D01*
X717264Y279241D01*
Y281666D01*
X717274Y281791D01*
X717314Y281916D01*
X717374Y282026D01*
X717454Y282126D01*
X717554Y282206D01*
X717664Y282266D01*
X717789Y282306D01*
X717914Y282316D01*
G37*
G36*
G01X722638D02*
X722763Y282306D01*
X722888Y282266D01*
X722998Y282206D01*
X723098Y282126D01*
X723178Y282026D01*
X723238Y281916D01*
X723278Y281791D01*
X723288Y281666D01*
Y279236D01*
X723318Y279206D01*
X723418Y279066D01*
X723438Y279026D01*
X723453Y278991D01*
X723473Y278951D01*
X723488Y278911D01*
X723498Y278871D01*
X723513Y278826D01*
X723518Y278786D01*
X723528Y278746D01*
X723533Y278701D01*
Y278661D01*
X723538Y278616D01*
X723533Y278571D01*
Y278531D01*
X723528Y278486D01*
X723518Y278446D01*
X723513Y278406D01*
X723498Y278361D01*
X723488Y278321D01*
X723473Y278281D01*
X723453Y278241D01*
X723438Y278206D01*
X723418Y278166D01*
X723318Y278026D01*
X723288Y277996D01*
Y275866D01*
X723278Y275741D01*
X723238Y275616D01*
X723178Y275506D01*
X723098Y275406D01*
X722998Y275326D01*
X722888Y275266D01*
X722763Y275226D01*
X722638Y275216D01*
X722513Y275226D01*
X722388Y275266D01*
X722278Y275326D01*
X722178Y275406D01*
X722098Y275506D01*
X722038Y275616D01*
X721998Y275741D01*
X721988Y275866D01*
Y277991D01*
X721958Y278021D01*
X721933Y278056D01*
X721903Y278091D01*
X721883Y278126D01*
X721858Y278161D01*
X721818Y278241D01*
X721773Y278361D01*
X721763Y278401D01*
X721753Y278446D01*
X721748Y278486D01*
X721738Y278531D01*
Y278701D01*
X721748Y278746D01*
X721753Y278786D01*
X721763Y278831D01*
X721773Y278871D01*
X721818Y278991D01*
X721858Y279071D01*
X721883Y279106D01*
X721903Y279141D01*
X721933Y279176D01*
X721958Y279211D01*
X721988Y279241D01*
Y281666D01*
X721998Y281791D01*
X722038Y281916D01*
X722098Y282026D01*
X722178Y282126D01*
X722278Y282206D01*
X722388Y282266D01*
X722513Y282306D01*
X722638Y282316D01*
G37*
G36*
G01X727362D02*
X727487Y282306D01*
X727612Y282266D01*
X727722Y282206D01*
X727822Y282126D01*
X727902Y282026D01*
X727962Y281916D01*
X728002Y281791D01*
X728012Y281666D01*
Y279236D01*
X728042Y279206D01*
X728142Y279066D01*
X728162Y279026D01*
X728177Y278991D01*
X728197Y278951D01*
X728212Y278911D01*
X728222Y278871D01*
X728237Y278826D01*
X728242Y278786D01*
X728252Y278746D01*
X728257Y278701D01*
Y278661D01*
X728262Y278616D01*
X728257Y278571D01*
Y278531D01*
X728252Y278486D01*
X728242Y278446D01*
X728237Y278406D01*
X728222Y278361D01*
X728212Y278321D01*
X728197Y278281D01*
X728177Y278241D01*
X728162Y278206D01*
X728142Y278166D01*
X728042Y278026D01*
X728012Y277996D01*
Y275866D01*
X728002Y275741D01*
X727962Y275616D01*
X727902Y275506D01*
X727822Y275406D01*
X727722Y275326D01*
X727612Y275266D01*
X727487Y275226D01*
X727362Y275216D01*
X727237Y275226D01*
X727112Y275266D01*
X727002Y275326D01*
X726902Y275406D01*
X726822Y275506D01*
X726762Y275616D01*
X726722Y275741D01*
X726712Y275866D01*
Y277991D01*
X726682Y278021D01*
X726657Y278056D01*
X726627Y278091D01*
X726607Y278126D01*
X726582Y278161D01*
X726542Y278241D01*
X726497Y278361D01*
X726487Y278401D01*
X726477Y278446D01*
X726472Y278486D01*
X726462Y278531D01*
Y278701D01*
X726472Y278746D01*
X726477Y278786D01*
X726487Y278831D01*
X726497Y278871D01*
X726542Y278991D01*
X726582Y279071D01*
X726607Y279106D01*
X726627Y279141D01*
X726657Y279176D01*
X726682Y279211D01*
X726712Y279241D01*
Y281666D01*
X726722Y281791D01*
X726762Y281916D01*
X726822Y282026D01*
X726902Y282126D01*
X727002Y282206D01*
X727112Y282266D01*
X727237Y282306D01*
X727362Y282316D01*
G37*
G36*
G01X732087D02*
X732212Y282306D01*
X732337Y282266D01*
X732447Y282206D01*
X732547Y282126D01*
X732627Y282026D01*
X732687Y281916D01*
X732727Y281791D01*
X732737Y281666D01*
Y279236D01*
X732767Y279206D01*
X732867Y279066D01*
X732887Y279026D01*
X732902Y278991D01*
X732922Y278951D01*
X732937Y278911D01*
X732947Y278871D01*
X732962Y278826D01*
X732967Y278786D01*
X732977Y278746D01*
X732982Y278701D01*
Y278661D01*
X732987Y278616D01*
X732982Y278571D01*
Y278531D01*
X732977Y278486D01*
X732967Y278446D01*
X732962Y278406D01*
X732947Y278361D01*
X732937Y278321D01*
X732922Y278281D01*
X732902Y278241D01*
X732887Y278206D01*
X732867Y278166D01*
X732767Y278026D01*
X732737Y277996D01*
Y275866D01*
X732727Y275741D01*
X732687Y275616D01*
X732627Y275506D01*
X732547Y275406D01*
X732447Y275326D01*
X732337Y275266D01*
X732212Y275226D01*
X732087Y275216D01*
X731962Y275226D01*
X731837Y275266D01*
X731727Y275326D01*
X731627Y275406D01*
X731547Y275506D01*
X731487Y275616D01*
X731447Y275741D01*
X731437Y275866D01*
Y277991D01*
X731407Y278021D01*
X731382Y278056D01*
X731352Y278091D01*
X731332Y278126D01*
X731307Y278161D01*
X731267Y278241D01*
X731222Y278361D01*
X731212Y278401D01*
X731202Y278446D01*
X731197Y278486D01*
X731187Y278531D01*
Y278701D01*
X731197Y278746D01*
X731202Y278786D01*
X731212Y278831D01*
X731222Y278871D01*
X731267Y278991D01*
X731307Y279071D01*
X731332Y279106D01*
X731352Y279141D01*
X731382Y279176D01*
X731407Y279211D01*
X731437Y279241D01*
Y281666D01*
X731447Y281791D01*
X731487Y281916D01*
X731547Y282026D01*
X731627Y282126D01*
X731727Y282206D01*
X731837Y282266D01*
X731962Y282306D01*
X732087Y282316D01*
G37*
G36*
G01X736811D02*
X736936Y282306D01*
X737061Y282266D01*
X737171Y282206D01*
X737271Y282126D01*
X737351Y282026D01*
X737411Y281916D01*
X737451Y281791D01*
X737461Y281666D01*
Y279236D01*
X737491Y279206D01*
X737591Y279066D01*
X737611Y279026D01*
X737626Y278991D01*
X737646Y278951D01*
X737661Y278911D01*
X737671Y278871D01*
X737686Y278826D01*
X737691Y278786D01*
X737701Y278746D01*
X737706Y278701D01*
Y278661D01*
X737711Y278616D01*
X737706Y278571D01*
Y278531D01*
X737701Y278486D01*
X737691Y278446D01*
X737686Y278406D01*
X737671Y278361D01*
X737661Y278321D01*
X737646Y278281D01*
X737626Y278241D01*
X737611Y278206D01*
X737591Y278166D01*
X737491Y278026D01*
X737461Y277996D01*
Y275866D01*
X737451Y275741D01*
X737411Y275616D01*
X737351Y275506D01*
X737271Y275406D01*
X737171Y275326D01*
X737061Y275266D01*
X736936Y275226D01*
X736811Y275216D01*
X736686Y275226D01*
X736561Y275266D01*
X736451Y275326D01*
X736351Y275406D01*
X736271Y275506D01*
X736211Y275616D01*
X736171Y275741D01*
X736161Y275866D01*
Y277991D01*
X736131Y278021D01*
X736106Y278056D01*
X736076Y278091D01*
X736056Y278126D01*
X736031Y278161D01*
X735991Y278241D01*
X735946Y278361D01*
X735936Y278401D01*
X735926Y278446D01*
X735921Y278486D01*
X735911Y278531D01*
Y278701D01*
X735921Y278746D01*
X735926Y278786D01*
X735936Y278831D01*
X735946Y278871D01*
X735991Y278991D01*
X736031Y279071D01*
X736056Y279106D01*
X736076Y279141D01*
X736106Y279176D01*
X736131Y279211D01*
X736161Y279241D01*
Y281666D01*
X736171Y281791D01*
X736211Y281916D01*
X736271Y282026D01*
X736351Y282126D01*
X736451Y282206D01*
X736561Y282266D01*
X736686Y282306D01*
X736811Y282316D01*
G37*
G36*
G01X741536D02*
X741661Y282306D01*
X741786Y282266D01*
X741896Y282206D01*
X741996Y282126D01*
X742076Y282026D01*
X742136Y281916D01*
X742176Y281791D01*
X742186Y281666D01*
Y279236D01*
X742216Y279206D01*
X742316Y279066D01*
X742336Y279026D01*
X742351Y278991D01*
X742371Y278951D01*
X742386Y278911D01*
X742396Y278871D01*
X742411Y278826D01*
X742416Y278786D01*
X742426Y278746D01*
X742431Y278701D01*
Y278661D01*
X742436Y278616D01*
X742431Y278571D01*
Y278531D01*
X742426Y278486D01*
X742416Y278446D01*
X742411Y278406D01*
X742396Y278361D01*
X742386Y278321D01*
X742371Y278281D01*
X742351Y278241D01*
X742336Y278206D01*
X742316Y278166D01*
X742216Y278026D01*
X742186Y277996D01*
Y275866D01*
X742176Y275741D01*
X742136Y275616D01*
X742076Y275506D01*
X741996Y275406D01*
X741896Y275326D01*
X741786Y275266D01*
X741661Y275226D01*
X741536Y275216D01*
X741411Y275226D01*
X741286Y275266D01*
X741176Y275326D01*
X741076Y275406D01*
X740996Y275506D01*
X740936Y275616D01*
X740896Y275741D01*
X740886Y275866D01*
Y277991D01*
X740856Y278021D01*
X740831Y278056D01*
X740801Y278091D01*
X740781Y278126D01*
X740756Y278161D01*
X740716Y278241D01*
X740671Y278361D01*
X740661Y278401D01*
X740651Y278446D01*
X740646Y278486D01*
X740636Y278531D01*
Y278701D01*
X740646Y278746D01*
X740651Y278786D01*
X740661Y278831D01*
X740671Y278871D01*
X740716Y278991D01*
X740756Y279071D01*
X740781Y279106D01*
X740801Y279141D01*
X740831Y279176D01*
X740856Y279211D01*
X740886Y279241D01*
Y281666D01*
X740896Y281791D01*
X740936Y281916D01*
X740996Y282026D01*
X741076Y282126D01*
X741176Y282206D01*
X741286Y282266D01*
X741411Y282306D01*
X741536Y282316D01*
G37*
G36*
G01X746260D02*
X746385Y282306D01*
X746510Y282266D01*
X746620Y282206D01*
X746720Y282126D01*
X746800Y282026D01*
X746860Y281916D01*
X746900Y281791D01*
X746910Y281666D01*
Y279236D01*
X746940Y279206D01*
X747040Y279066D01*
X747060Y279026D01*
X747075Y278991D01*
X747095Y278951D01*
X747110Y278911D01*
X747120Y278871D01*
X747135Y278826D01*
X747140Y278786D01*
X747150Y278746D01*
X747155Y278701D01*
Y278661D01*
X747160Y278616D01*
X747155Y278571D01*
Y278531D01*
X747150Y278486D01*
X747140Y278446D01*
X747135Y278406D01*
X747120Y278361D01*
X747110Y278321D01*
X747095Y278281D01*
X747075Y278241D01*
X747060Y278206D01*
X747040Y278166D01*
X746940Y278026D01*
X746910Y277996D01*
Y275866D01*
X746900Y275741D01*
X746860Y275616D01*
X746800Y275506D01*
X746720Y275406D01*
X746620Y275326D01*
X746510Y275266D01*
X746385Y275226D01*
X746260Y275216D01*
X746135Y275226D01*
X746010Y275266D01*
X745900Y275326D01*
X745800Y275406D01*
X745720Y275506D01*
X745660Y275616D01*
X745620Y275741D01*
X745610Y275866D01*
Y277991D01*
X745580Y278021D01*
X745555Y278056D01*
X745525Y278091D01*
X745505Y278126D01*
X745480Y278161D01*
X745440Y278241D01*
X745395Y278361D01*
X745385Y278401D01*
X745375Y278446D01*
X745370Y278486D01*
X745360Y278531D01*
Y278701D01*
X745370Y278746D01*
X745375Y278786D01*
X745385Y278831D01*
X745395Y278871D01*
X745440Y278991D01*
X745480Y279071D01*
X745505Y279106D01*
X745525Y279141D01*
X745555Y279176D01*
X745580Y279211D01*
X745610Y279241D01*
Y281666D01*
X745620Y281791D01*
X745660Y281916D01*
X745720Y282026D01*
X745800Y282126D01*
X745900Y282206D01*
X746010Y282266D01*
X746135Y282306D01*
X746260Y282316D01*
G37*
G54D84*
X353742Y135431D03*
Y148031D03*
Y151181D03*
Y138581D03*
Y141731D03*
Y144881D03*
Y166931D03*
Y160631D03*
Y157481D03*
Y154331D03*
Y163781D03*
Y170081D03*
Y173231D03*
X369482Y135431D03*
X369882Y132671D03*
X356882Y135431D03*
X360042D03*
X366342D03*
X363182D03*
X356882Y132671D03*
X366342D03*
X369482Y148031D03*
Y151181D03*
Y138581D03*
Y144881D03*
Y141731D03*
X356882Y148031D03*
Y151181D03*
X360042Y148031D03*
X366342D03*
X363182D03*
X360042Y151181D03*
X366342D03*
X363182D03*
X356882Y138581D03*
X360042D03*
X366342D03*
X363182D03*
X356882Y144881D03*
Y141731D03*
X360042Y144881D03*
Y141731D03*
X366342Y144881D03*
Y141731D03*
X363182Y144881D03*
Y141731D03*
X369482Y166931D03*
Y154331D03*
Y157481D03*
Y160631D03*
Y163781D03*
X356882Y166931D03*
X360042D03*
X366342D03*
X363182D03*
X356882Y154331D03*
Y157481D03*
Y160631D03*
X360042Y154331D03*
Y157481D03*
Y160631D03*
X366342Y154331D03*
Y157481D03*
Y160631D03*
X363182Y154331D03*
Y157481D03*
Y160631D03*
X356882Y163781D03*
X360042D03*
X366342D03*
X363182D03*
X369482Y170081D03*
Y173231D03*
X369092Y175991D03*
X356882Y170081D03*
X360042D03*
X366342D03*
X363182D03*
X356882Y173231D03*
X360042D03*
X366342D03*
X363182D03*
X356882Y175991D03*
X366342D03*
X372642Y135431D03*
X375782D03*
X378942D03*
X382082D03*
Y132671D03*
X372642D03*
X385242Y135431D03*
X385632Y132671D03*
X372642Y148031D03*
X375782D03*
X372642Y151181D03*
X375782D03*
X378942Y148031D03*
Y151181D03*
X382082Y148031D03*
Y151181D03*
X385242Y148031D03*
Y151181D03*
X372642Y138581D03*
X375782D03*
X378942D03*
X372642Y144881D03*
Y141731D03*
X375782D03*
Y144881D03*
X378942Y141731D03*
Y144881D03*
X382082Y138581D03*
Y144881D03*
Y141731D03*
X385242Y138581D03*
Y144881D03*
Y141731D03*
X372642Y166931D03*
X375782D03*
X378942D03*
X382082D03*
X385242D03*
X372642Y154331D03*
Y157481D03*
Y160631D03*
X375782D03*
Y157481D03*
Y154331D03*
X378942Y160631D03*
Y157481D03*
Y154331D03*
X382082D03*
Y157481D03*
Y160631D03*
X372642Y163781D03*
X375782D03*
X378942D03*
X382082D03*
X385242Y154331D03*
Y157481D03*
Y160631D03*
Y163781D03*
X372642Y170081D03*
X375782D03*
X378942D03*
X372642Y173231D03*
X375782D03*
X378942D03*
X382082Y170081D03*
Y173231D03*
X372642Y175991D03*
X382082D03*
X385242Y170081D03*
Y173231D03*
X384842Y175991D03*
X394682Y135431D03*
X391542D03*
X388382D03*
X397842D03*
Y132671D03*
X388382D03*
X400982Y135431D03*
X394682Y148031D03*
X391542D03*
X388382D03*
X394682Y151181D03*
X391542D03*
X388382D03*
X397842Y148031D03*
Y151181D03*
X400982Y148031D03*
Y151181D03*
X394682Y138581D03*
X391542D03*
X388382D03*
X397842D03*
X394682Y144881D03*
Y141731D03*
X391542Y144881D03*
Y141731D03*
X388382Y144881D03*
Y141731D03*
X397842Y144881D03*
Y141731D03*
X400982Y138581D03*
Y144881D03*
Y141731D03*
X394682Y166931D03*
X391542D03*
X388382D03*
X397842D03*
X400982D03*
X394682Y154331D03*
Y157481D03*
Y160631D03*
X391542Y154331D03*
Y157481D03*
Y160631D03*
X388382Y154331D03*
Y157481D03*
Y160631D03*
X397842Y154331D03*
Y157481D03*
Y160631D03*
X394682Y163781D03*
X391542D03*
X388382D03*
X397842D03*
X400982Y154331D03*
Y157481D03*
Y160631D03*
Y163781D03*
X394682Y170081D03*
X391542D03*
X388382D03*
X397842D03*
X388382Y173231D03*
X394682D03*
X391542D03*
X397842D03*
X388382Y175991D03*
X397842D03*
X400982Y170081D03*
Y173231D03*
G54D85*
X482874Y67286D03*
X476969Y218110D03*
X776968Y67286D03*
X771063Y218110D03*
G54D49*
X109600Y268500D03*
X104400D03*
X126100Y121000D03*
X120900D03*
X171100Y61000D03*
X165900D03*
X171900Y213500D03*
X170000Y203300D03*
X180600Y61000D03*
X175400D03*
X177100Y213500D03*
X175200Y203300D03*
X183600Y215150D03*
X195600Y177000D03*
X190400D03*
X193600Y197500D03*
X188400D03*
X195851Y210150D03*
X190651D03*
X188800Y215150D03*
X198300D03*
X193100D03*
X249400Y207000D03*
X254600D03*
X441600Y75500D03*
X436400D03*
X474300Y254500D03*
X469100D03*
X474300Y249500D03*
X469100D03*
X557080Y230982D03*
X551880D03*
X663600Y91000D03*
X658400D03*
X662600Y119100D03*
X657400D03*
X665400Y153500D03*
X670600D03*
X724100Y85000D03*
X718900D03*
G54D76*
X259750Y177440D03*
Y180000D03*
Y182560D03*
X279750Y81060D03*
Y78500D03*
Y75940D03*
X266250Y177440D03*
Y180000D03*
Y182560D03*
X286250Y81060D03*
Y78500D03*
Y75940D03*
X526750Y57940D03*
Y60500D03*
Y63060D03*
X533250Y57940D03*
Y60500D03*
Y63060D03*
X628650Y182440D03*
X635150D03*
X628650Y185000D03*
Y187560D03*
X635150Y185000D03*
Y187560D03*
X651750Y179940D03*
Y182500D03*
X658250Y179940D03*
Y182500D03*
X651750Y185060D03*
X658250D03*
G54D67*
X187250Y164000D03*
Y159000D03*
Y154000D03*
Y169000D03*
X203850Y74900D03*
Y69900D03*
Y84900D03*
Y79900D03*
X194197Y105871D03*
Y120871D03*
Y115871D03*
Y110871D03*
X206750Y154000D03*
Y159000D03*
Y164000D03*
Y169000D03*
X223350Y69900D03*
Y74900D03*
Y79900D03*
Y84900D03*
X221299Y105871D03*
Y110871D03*
Y115871D03*
Y120871D03*
G36*
G01X502953Y282316D02*
X503078Y282306D01*
X503203Y282266D01*
X503313Y282206D01*
X503413Y282126D01*
X503493Y282026D01*
X503553Y281916D01*
X503593Y281791D01*
X503603Y281666D01*
Y278236D01*
X503633Y278206D01*
X503733Y278066D01*
X503753Y278026D01*
X503768Y277991D01*
X503788Y277951D01*
X503803Y277911D01*
X503813Y277871D01*
X503828Y277826D01*
X503833Y277786D01*
X503843Y277746D01*
X503848Y277701D01*
Y277661D01*
X503853Y277616D01*
X503848Y277571D01*
Y277531D01*
X503843Y277486D01*
X503833Y277446D01*
X503828Y277406D01*
X503813Y277361D01*
X503803Y277321D01*
X503788Y277281D01*
X503768Y277241D01*
X503753Y277206D01*
X503733Y277166D01*
X503633Y277026D01*
X503603Y276996D01*
Y275866D01*
X503593Y275741D01*
X503553Y275616D01*
X503493Y275506D01*
X503413Y275406D01*
X503313Y275326D01*
X503203Y275266D01*
X503078Y275226D01*
X502953Y275216D01*
X502828Y275226D01*
X502703Y275266D01*
X502593Y275326D01*
X502493Y275406D01*
X502413Y275506D01*
X502353Y275616D01*
X502313Y275741D01*
X502303Y275866D01*
Y276996D01*
X502273Y277026D01*
X502173Y277166D01*
X502153Y277206D01*
X502138Y277241D01*
X502118Y277281D01*
X502103Y277321D01*
X502093Y277361D01*
X502078Y277406D01*
X502073Y277446D01*
X502063Y277486D01*
X502058Y277531D01*
Y277571D01*
X502053Y277616D01*
X502058Y277661D01*
Y277701D01*
X502063Y277746D01*
X502073Y277786D01*
X502078Y277826D01*
X502093Y277871D01*
X502103Y277911D01*
X502118Y277951D01*
X502138Y277991D01*
X502153Y278026D01*
X502173Y278066D01*
X502273Y278206D01*
X502303Y278236D01*
Y281666D01*
X502313Y281791D01*
X502353Y281916D01*
X502413Y282026D01*
X502493Y282126D01*
X502593Y282206D01*
X502703Y282266D01*
X502828Y282306D01*
X502953Y282316D01*
G37*
G36*
G01X507677D02*
X507802Y282306D01*
X507927Y282266D01*
X508037Y282206D01*
X508137Y282126D01*
X508217Y282026D01*
X508277Y281916D01*
X508317Y281791D01*
X508327Y281666D01*
Y278236D01*
X508357Y278206D01*
X508457Y278066D01*
X508477Y278026D01*
X508492Y277991D01*
X508512Y277951D01*
X508527Y277911D01*
X508537Y277871D01*
X508552Y277826D01*
X508557Y277786D01*
X508567Y277746D01*
X508572Y277701D01*
Y277661D01*
X508577Y277616D01*
X508572Y277571D01*
Y277531D01*
X508567Y277486D01*
X508557Y277446D01*
X508552Y277406D01*
X508537Y277361D01*
X508527Y277321D01*
X508512Y277281D01*
X508492Y277241D01*
X508477Y277206D01*
X508457Y277166D01*
X508357Y277026D01*
X508327Y276996D01*
Y275866D01*
X508317Y275741D01*
X508277Y275616D01*
X508217Y275506D01*
X508137Y275406D01*
X508037Y275326D01*
X507927Y275266D01*
X507802Y275226D01*
X507677Y275216D01*
X507552Y275226D01*
X507427Y275266D01*
X507317Y275326D01*
X507217Y275406D01*
X507137Y275506D01*
X507077Y275616D01*
X507037Y275741D01*
X507027Y275866D01*
Y276996D01*
X506997Y277026D01*
X506897Y277166D01*
X506877Y277206D01*
X506862Y277241D01*
X506842Y277281D01*
X506827Y277321D01*
X506817Y277361D01*
X506802Y277406D01*
X506797Y277446D01*
X506787Y277486D01*
X506782Y277531D01*
Y277571D01*
X506777Y277616D01*
X506782Y277661D01*
Y277701D01*
X506787Y277746D01*
X506797Y277786D01*
X506802Y277826D01*
X506817Y277871D01*
X506827Y277911D01*
X506842Y277951D01*
X506862Y277991D01*
X506877Y278026D01*
X506897Y278066D01*
X506997Y278206D01*
X507027Y278236D01*
Y281666D01*
X507037Y281791D01*
X507077Y281916D01*
X507137Y282026D01*
X507217Y282126D01*
X507317Y282206D01*
X507427Y282266D01*
X507552Y282306D01*
X507677Y282316D01*
G37*
G36*
G01X512402D02*
X512527Y282306D01*
X512652Y282266D01*
X512762Y282206D01*
X512862Y282126D01*
X512942Y282026D01*
X513002Y281916D01*
X513042Y281791D01*
X513052Y281666D01*
Y278236D01*
X513082Y278206D01*
X513182Y278066D01*
X513202Y278026D01*
X513217Y277991D01*
X513237Y277951D01*
X513252Y277911D01*
X513262Y277871D01*
X513277Y277826D01*
X513282Y277786D01*
X513292Y277746D01*
X513297Y277701D01*
Y277661D01*
X513302Y277616D01*
X513297Y277571D01*
Y277531D01*
X513292Y277486D01*
X513282Y277446D01*
X513277Y277406D01*
X513262Y277361D01*
X513252Y277321D01*
X513237Y277281D01*
X513217Y277241D01*
X513202Y277206D01*
X513182Y277166D01*
X513082Y277026D01*
X513052Y276996D01*
Y275866D01*
X513042Y275741D01*
X513002Y275616D01*
X512942Y275506D01*
X512862Y275406D01*
X512762Y275326D01*
X512652Y275266D01*
X512527Y275226D01*
X512402Y275216D01*
X512277Y275226D01*
X512152Y275266D01*
X512042Y275326D01*
X511942Y275406D01*
X511862Y275506D01*
X511802Y275616D01*
X511762Y275741D01*
X511752Y275866D01*
Y276996D01*
X511722Y277026D01*
X511622Y277166D01*
X511602Y277206D01*
X511587Y277241D01*
X511567Y277281D01*
X511552Y277321D01*
X511542Y277361D01*
X511527Y277406D01*
X511522Y277446D01*
X511512Y277486D01*
X511507Y277531D01*
Y277571D01*
X511502Y277616D01*
X511507Y277661D01*
Y277701D01*
X511512Y277746D01*
X511522Y277786D01*
X511527Y277826D01*
X511542Y277871D01*
X511552Y277911D01*
X511567Y277951D01*
X511587Y277991D01*
X511602Y278026D01*
X511622Y278066D01*
X511722Y278206D01*
X511752Y278236D01*
Y281666D01*
X511762Y281791D01*
X511802Y281916D01*
X511862Y282026D01*
X511942Y282126D01*
X512042Y282206D01*
X512152Y282266D01*
X512277Y282306D01*
X512402Y282316D01*
G37*
G36*
G01X517126D02*
X517251Y282306D01*
X517376Y282266D01*
X517486Y282206D01*
X517586Y282126D01*
X517666Y282026D01*
X517726Y281916D01*
X517766Y281791D01*
X517776Y281666D01*
Y278236D01*
X517806Y278206D01*
X517906Y278066D01*
X517926Y278026D01*
X517941Y277991D01*
X517961Y277951D01*
X517976Y277911D01*
X517986Y277871D01*
X518001Y277826D01*
X518006Y277786D01*
X518016Y277746D01*
X518021Y277701D01*
Y277661D01*
X518026Y277616D01*
X518021Y277571D01*
Y277531D01*
X518016Y277486D01*
X518006Y277446D01*
X518001Y277406D01*
X517986Y277361D01*
X517976Y277321D01*
X517961Y277281D01*
X517941Y277241D01*
X517926Y277206D01*
X517906Y277166D01*
X517806Y277026D01*
X517776Y276996D01*
Y275866D01*
X517766Y275741D01*
X517726Y275616D01*
X517666Y275506D01*
X517586Y275406D01*
X517486Y275326D01*
X517376Y275266D01*
X517251Y275226D01*
X517126Y275216D01*
X517001Y275226D01*
X516876Y275266D01*
X516766Y275326D01*
X516666Y275406D01*
X516586Y275506D01*
X516526Y275616D01*
X516486Y275741D01*
X516476Y275866D01*
Y276996D01*
X516446Y277026D01*
X516346Y277166D01*
X516326Y277206D01*
X516311Y277241D01*
X516291Y277281D01*
X516276Y277321D01*
X516266Y277361D01*
X516251Y277406D01*
X516246Y277446D01*
X516236Y277486D01*
X516231Y277531D01*
Y277571D01*
X516226Y277616D01*
X516231Y277661D01*
Y277701D01*
X516236Y277746D01*
X516246Y277786D01*
X516251Y277826D01*
X516266Y277871D01*
X516276Y277911D01*
X516291Y277951D01*
X516311Y277991D01*
X516326Y278026D01*
X516346Y278066D01*
X516446Y278206D01*
X516476Y278236D01*
Y281666D01*
X516486Y281791D01*
X516526Y281916D01*
X516586Y282026D01*
X516666Y282126D01*
X516766Y282206D01*
X516876Y282266D01*
X517001Y282306D01*
X517126Y282316D01*
G37*
G36*
G01X521851D02*
X521976Y282306D01*
X522101Y282266D01*
X522211Y282206D01*
X522311Y282126D01*
X522391Y282026D01*
X522451Y281916D01*
X522491Y281791D01*
X522501Y281666D01*
Y278236D01*
X522531Y278206D01*
X522631Y278066D01*
X522651Y278026D01*
X522666Y277991D01*
X522686Y277951D01*
X522701Y277911D01*
X522711Y277871D01*
X522726Y277826D01*
X522731Y277786D01*
X522741Y277746D01*
X522746Y277701D01*
Y277661D01*
X522751Y277616D01*
X522746Y277571D01*
Y277531D01*
X522741Y277486D01*
X522731Y277446D01*
X522726Y277406D01*
X522711Y277361D01*
X522701Y277321D01*
X522686Y277281D01*
X522666Y277241D01*
X522651Y277206D01*
X522631Y277166D01*
X522531Y277026D01*
X522501Y276996D01*
Y275866D01*
X522491Y275741D01*
X522451Y275616D01*
X522391Y275506D01*
X522311Y275406D01*
X522211Y275326D01*
X522101Y275266D01*
X521976Y275226D01*
X521851Y275216D01*
X521726Y275226D01*
X521601Y275266D01*
X521491Y275326D01*
X521391Y275406D01*
X521311Y275506D01*
X521251Y275616D01*
X521211Y275741D01*
X521201Y275866D01*
Y276996D01*
X521171Y277026D01*
X521071Y277166D01*
X521051Y277206D01*
X521036Y277241D01*
X521016Y277281D01*
X521001Y277321D01*
X520991Y277361D01*
X520976Y277406D01*
X520971Y277446D01*
X520961Y277486D01*
X520956Y277531D01*
Y277571D01*
X520951Y277616D01*
X520956Y277661D01*
Y277701D01*
X520961Y277746D01*
X520971Y277786D01*
X520976Y277826D01*
X520991Y277871D01*
X521001Y277911D01*
X521016Y277951D01*
X521036Y277991D01*
X521051Y278026D01*
X521071Y278066D01*
X521171Y278206D01*
X521201Y278236D01*
Y281666D01*
X521211Y281791D01*
X521251Y281916D01*
X521311Y282026D01*
X521391Y282126D01*
X521491Y282206D01*
X521601Y282266D01*
X521726Y282306D01*
X521851Y282316D01*
G37*
G36*
G01X526575D02*
X526700Y282306D01*
X526825Y282266D01*
X526935Y282206D01*
X527035Y282126D01*
X527115Y282026D01*
X527175Y281916D01*
X527215Y281791D01*
X527225Y281666D01*
Y278236D01*
X527255Y278206D01*
X527355Y278066D01*
X527375Y278026D01*
X527390Y277991D01*
X527410Y277951D01*
X527425Y277911D01*
X527435Y277871D01*
X527450Y277826D01*
X527455Y277786D01*
X527465Y277746D01*
X527470Y277701D01*
Y277661D01*
X527475Y277616D01*
X527470Y277571D01*
Y277531D01*
X527465Y277486D01*
X527455Y277446D01*
X527450Y277406D01*
X527435Y277361D01*
X527425Y277321D01*
X527410Y277281D01*
X527390Y277241D01*
X527375Y277206D01*
X527355Y277166D01*
X527255Y277026D01*
X527225Y276996D01*
Y275866D01*
X527215Y275741D01*
X527175Y275616D01*
X527115Y275506D01*
X527035Y275406D01*
X526935Y275326D01*
X526825Y275266D01*
X526700Y275226D01*
X526575Y275216D01*
X526450Y275226D01*
X526325Y275266D01*
X526215Y275326D01*
X526115Y275406D01*
X526035Y275506D01*
X525975Y275616D01*
X525935Y275741D01*
X525925Y275866D01*
Y276996D01*
X525895Y277026D01*
X525795Y277166D01*
X525775Y277206D01*
X525760Y277241D01*
X525740Y277281D01*
X525725Y277321D01*
X525715Y277361D01*
X525700Y277406D01*
X525695Y277446D01*
X525685Y277486D01*
X525680Y277531D01*
Y277571D01*
X525675Y277616D01*
X525680Y277661D01*
Y277701D01*
X525685Y277746D01*
X525695Y277786D01*
X525700Y277826D01*
X525715Y277871D01*
X525725Y277911D01*
X525740Y277951D01*
X525760Y277991D01*
X525775Y278026D01*
X525795Y278066D01*
X525895Y278206D01*
X525925Y278236D01*
Y281666D01*
X525935Y281791D01*
X525975Y281916D01*
X526035Y282026D01*
X526115Y282126D01*
X526215Y282206D01*
X526325Y282266D01*
X526450Y282306D01*
X526575Y282316D01*
G37*
G36*
G01X531299D02*
X531424Y282306D01*
X531549Y282266D01*
X531659Y282206D01*
X531759Y282126D01*
X531839Y282026D01*
X531899Y281916D01*
X531939Y281791D01*
X531949Y281666D01*
Y278236D01*
X531979Y278206D01*
X532079Y278066D01*
X532099Y278026D01*
X532114Y277991D01*
X532134Y277951D01*
X532149Y277911D01*
X532159Y277871D01*
X532174Y277826D01*
X532179Y277786D01*
X532189Y277746D01*
X532194Y277701D01*
Y277661D01*
X532199Y277616D01*
X532194Y277571D01*
Y277531D01*
X532189Y277486D01*
X532179Y277446D01*
X532174Y277406D01*
X532159Y277361D01*
X532149Y277321D01*
X532134Y277281D01*
X532114Y277241D01*
X532099Y277206D01*
X532079Y277166D01*
X531979Y277026D01*
X531949Y276996D01*
Y275866D01*
X531939Y275741D01*
X531899Y275616D01*
X531839Y275506D01*
X531759Y275406D01*
X531659Y275326D01*
X531549Y275266D01*
X531424Y275226D01*
X531299Y275216D01*
X531174Y275226D01*
X531049Y275266D01*
X530939Y275326D01*
X530839Y275406D01*
X530759Y275506D01*
X530699Y275616D01*
X530659Y275741D01*
X530649Y275866D01*
Y276996D01*
X530619Y277026D01*
X530519Y277166D01*
X530499Y277206D01*
X530484Y277241D01*
X530464Y277281D01*
X530449Y277321D01*
X530439Y277361D01*
X530424Y277406D01*
X530419Y277446D01*
X530409Y277486D01*
X530404Y277531D01*
Y277571D01*
X530399Y277616D01*
X530404Y277661D01*
Y277701D01*
X530409Y277746D01*
X530419Y277786D01*
X530424Y277826D01*
X530439Y277871D01*
X530449Y277911D01*
X530464Y277951D01*
X530484Y277991D01*
X530499Y278026D01*
X530519Y278066D01*
X530619Y278206D01*
X530649Y278236D01*
Y281666D01*
X530659Y281791D01*
X530699Y281916D01*
X530759Y282026D01*
X530839Y282126D01*
X530939Y282206D01*
X531049Y282266D01*
X531174Y282306D01*
X531299Y282316D01*
G37*
G36*
G01X536024D02*
X536149Y282306D01*
X536274Y282266D01*
X536384Y282206D01*
X536484Y282126D01*
X536564Y282026D01*
X536624Y281916D01*
X536664Y281791D01*
X536674Y281666D01*
Y278236D01*
X536704Y278206D01*
X536804Y278066D01*
X536824Y278026D01*
X536839Y277991D01*
X536859Y277951D01*
X536874Y277911D01*
X536884Y277871D01*
X536899Y277826D01*
X536904Y277786D01*
X536914Y277746D01*
X536919Y277701D01*
Y277661D01*
X536924Y277616D01*
X536919Y277571D01*
Y277531D01*
X536914Y277486D01*
X536904Y277446D01*
X536899Y277406D01*
X536884Y277361D01*
X536874Y277321D01*
X536859Y277281D01*
X536839Y277241D01*
X536824Y277206D01*
X536804Y277166D01*
X536704Y277026D01*
X536674Y276996D01*
Y275866D01*
X536664Y275741D01*
X536624Y275616D01*
X536564Y275506D01*
X536484Y275406D01*
X536384Y275326D01*
X536274Y275266D01*
X536149Y275226D01*
X536024Y275216D01*
X535899Y275226D01*
X535774Y275266D01*
X535664Y275326D01*
X535564Y275406D01*
X535484Y275506D01*
X535424Y275616D01*
X535384Y275741D01*
X535374Y275866D01*
Y276996D01*
X535344Y277026D01*
X535244Y277166D01*
X535224Y277206D01*
X535209Y277241D01*
X535189Y277281D01*
X535174Y277321D01*
X535164Y277361D01*
X535149Y277406D01*
X535144Y277446D01*
X535134Y277486D01*
X535129Y277531D01*
Y277571D01*
X535124Y277616D01*
X535129Y277661D01*
Y277701D01*
X535134Y277746D01*
X535144Y277786D01*
X535149Y277826D01*
X535164Y277871D01*
X535174Y277911D01*
X535189Y277951D01*
X535209Y277991D01*
X535224Y278026D01*
X535244Y278066D01*
X535344Y278206D01*
X535374Y278236D01*
Y281666D01*
X535384Y281791D01*
X535424Y281916D01*
X535484Y282026D01*
X535564Y282126D01*
X535664Y282206D01*
X535774Y282266D01*
X535899Y282306D01*
X536024Y282316D01*
G37*
G36*
G01X540748D02*
X540873Y282306D01*
X540998Y282266D01*
X541108Y282206D01*
X541208Y282126D01*
X541288Y282026D01*
X541348Y281916D01*
X541388Y281791D01*
X541398Y281666D01*
Y278236D01*
X541428Y278206D01*
X541528Y278066D01*
X541548Y278026D01*
X541563Y277991D01*
X541583Y277951D01*
X541598Y277911D01*
X541608Y277871D01*
X541623Y277826D01*
X541628Y277786D01*
X541638Y277746D01*
X541643Y277701D01*
Y277661D01*
X541648Y277616D01*
X541643Y277571D01*
Y277531D01*
X541638Y277486D01*
X541628Y277446D01*
X541623Y277406D01*
X541608Y277361D01*
X541598Y277321D01*
X541583Y277281D01*
X541563Y277241D01*
X541548Y277206D01*
X541528Y277166D01*
X541428Y277026D01*
X541398Y276996D01*
Y275866D01*
X541388Y275741D01*
X541348Y275616D01*
X541288Y275506D01*
X541208Y275406D01*
X541108Y275326D01*
X540998Y275266D01*
X540873Y275226D01*
X540748Y275216D01*
X540623Y275226D01*
X540498Y275266D01*
X540388Y275326D01*
X540288Y275406D01*
X540208Y275506D01*
X540148Y275616D01*
X540108Y275741D01*
X540098Y275866D01*
Y276996D01*
X540068Y277026D01*
X539968Y277166D01*
X539948Y277206D01*
X539933Y277241D01*
X539913Y277281D01*
X539898Y277321D01*
X539888Y277361D01*
X539873Y277406D01*
X539868Y277446D01*
X539858Y277486D01*
X539853Y277531D01*
Y277571D01*
X539848Y277616D01*
X539853Y277661D01*
Y277701D01*
X539858Y277746D01*
X539868Y277786D01*
X539873Y277826D01*
X539888Y277871D01*
X539898Y277911D01*
X539913Y277951D01*
X539933Y277991D01*
X539948Y278026D01*
X539968Y278066D01*
X540068Y278206D01*
X540098Y278236D01*
Y281666D01*
X540108Y281791D01*
X540148Y281916D01*
X540208Y282026D01*
X540288Y282126D01*
X540388Y282206D01*
X540498Y282266D01*
X540623Y282306D01*
X540748Y282316D01*
G37*
G36*
G01X545473D02*
X545598Y282306D01*
X545723Y282266D01*
X545833Y282206D01*
X545933Y282126D01*
X546013Y282026D01*
X546073Y281916D01*
X546113Y281791D01*
X546123Y281666D01*
Y278236D01*
X546153Y278206D01*
X546253Y278066D01*
X546273Y278026D01*
X546288Y277991D01*
X546308Y277951D01*
X546323Y277911D01*
X546333Y277871D01*
X546348Y277826D01*
X546353Y277786D01*
X546363Y277746D01*
X546368Y277701D01*
Y277661D01*
X546373Y277616D01*
X546368Y277571D01*
Y277531D01*
X546363Y277486D01*
X546353Y277446D01*
X546348Y277406D01*
X546333Y277361D01*
X546323Y277321D01*
X546308Y277281D01*
X546288Y277241D01*
X546273Y277206D01*
X546253Y277166D01*
X546153Y277026D01*
X546123Y276996D01*
Y275866D01*
X546113Y275741D01*
X546073Y275616D01*
X546013Y275506D01*
X545933Y275406D01*
X545833Y275326D01*
X545723Y275266D01*
X545598Y275226D01*
X545473Y275216D01*
X545348Y275226D01*
X545223Y275266D01*
X545113Y275326D01*
X545013Y275406D01*
X544933Y275506D01*
X544873Y275616D01*
X544833Y275741D01*
X544823Y275866D01*
Y276996D01*
X544793Y277026D01*
X544693Y277166D01*
X544673Y277206D01*
X544658Y277241D01*
X544638Y277281D01*
X544623Y277321D01*
X544613Y277361D01*
X544598Y277406D01*
X544593Y277446D01*
X544583Y277486D01*
X544578Y277531D01*
Y277571D01*
X544573Y277616D01*
X544578Y277661D01*
Y277701D01*
X544583Y277746D01*
X544593Y277786D01*
X544598Y277826D01*
X544613Y277871D01*
X544623Y277911D01*
X544638Y277951D01*
X544658Y277991D01*
X544673Y278026D01*
X544693Y278066D01*
X544793Y278206D01*
X544823Y278236D01*
Y281666D01*
X544833Y281791D01*
X544873Y281916D01*
X544933Y282026D01*
X545013Y282126D01*
X545113Y282206D01*
X545223Y282266D01*
X545348Y282306D01*
X545473Y282316D01*
G37*
G36*
G01X550197D02*
X550322Y282306D01*
X550447Y282266D01*
X550557Y282206D01*
X550657Y282126D01*
X550737Y282026D01*
X550797Y281916D01*
X550837Y281791D01*
X550847Y281666D01*
Y278236D01*
X550877Y278206D01*
X550977Y278066D01*
X550997Y278026D01*
X551012Y277991D01*
X551032Y277951D01*
X551047Y277911D01*
X551057Y277871D01*
X551072Y277826D01*
X551077Y277786D01*
X551087Y277746D01*
X551092Y277701D01*
Y277661D01*
X551097Y277616D01*
X551092Y277571D01*
Y277531D01*
X551087Y277486D01*
X551077Y277446D01*
X551072Y277406D01*
X551057Y277361D01*
X551047Y277321D01*
X551032Y277281D01*
X551012Y277241D01*
X550997Y277206D01*
X550977Y277166D01*
X550877Y277026D01*
X550847Y276996D01*
Y275866D01*
X550837Y275741D01*
X550797Y275616D01*
X550737Y275506D01*
X550657Y275406D01*
X550557Y275326D01*
X550447Y275266D01*
X550322Y275226D01*
X550197Y275216D01*
X550072Y275226D01*
X549947Y275266D01*
X549837Y275326D01*
X549737Y275406D01*
X549657Y275506D01*
X549597Y275616D01*
X549557Y275741D01*
X549547Y275866D01*
Y276996D01*
X549517Y277026D01*
X549417Y277166D01*
X549397Y277206D01*
X549382Y277241D01*
X549362Y277281D01*
X549347Y277321D01*
X549337Y277361D01*
X549322Y277406D01*
X549317Y277446D01*
X549307Y277486D01*
X549302Y277531D01*
Y277571D01*
X549297Y277616D01*
X549302Y277661D01*
Y277701D01*
X549307Y277746D01*
X549317Y277786D01*
X549322Y277826D01*
X549337Y277871D01*
X549347Y277911D01*
X549362Y277951D01*
X549382Y277991D01*
X549397Y278026D01*
X549417Y278066D01*
X549517Y278206D01*
X549547Y278236D01*
Y281666D01*
X549557Y281791D01*
X549597Y281916D01*
X549657Y282026D01*
X549737Y282126D01*
X549837Y282206D01*
X549947Y282266D01*
X550072Y282306D01*
X550197Y282316D01*
G37*
G36*
G01X554922D02*
X555047Y282306D01*
X555172Y282266D01*
X555282Y282206D01*
X555382Y282126D01*
X555462Y282026D01*
X555522Y281916D01*
X555562Y281791D01*
X555572Y281666D01*
Y278236D01*
X555602Y278206D01*
X555702Y278066D01*
X555722Y278026D01*
X555737Y277991D01*
X555757Y277951D01*
X555772Y277911D01*
X555782Y277871D01*
X555797Y277826D01*
X555802Y277786D01*
X555812Y277746D01*
X555817Y277701D01*
Y277661D01*
X555822Y277616D01*
X555817Y277571D01*
Y277531D01*
X555812Y277486D01*
X555802Y277446D01*
X555797Y277406D01*
X555782Y277361D01*
X555772Y277321D01*
X555757Y277281D01*
X555737Y277241D01*
X555722Y277206D01*
X555702Y277166D01*
X555602Y277026D01*
X555572Y276996D01*
Y275866D01*
X555562Y275741D01*
X555522Y275616D01*
X555462Y275506D01*
X555382Y275406D01*
X555282Y275326D01*
X555172Y275266D01*
X555047Y275226D01*
X554922Y275216D01*
X554797Y275226D01*
X554672Y275266D01*
X554562Y275326D01*
X554462Y275406D01*
X554382Y275506D01*
X554322Y275616D01*
X554282Y275741D01*
X554272Y275866D01*
Y276996D01*
X554242Y277026D01*
X554142Y277166D01*
X554122Y277206D01*
X554107Y277241D01*
X554087Y277281D01*
X554072Y277321D01*
X554062Y277361D01*
X554047Y277406D01*
X554042Y277446D01*
X554032Y277486D01*
X554027Y277531D01*
Y277571D01*
X554022Y277616D01*
X554027Y277661D01*
Y277701D01*
X554032Y277746D01*
X554042Y277786D01*
X554047Y277826D01*
X554062Y277871D01*
X554072Y277911D01*
X554087Y277951D01*
X554107Y277991D01*
X554122Y278026D01*
X554142Y278066D01*
X554242Y278206D01*
X554272Y278236D01*
Y281666D01*
X554282Y281791D01*
X554322Y281916D01*
X554382Y282026D01*
X554462Y282126D01*
X554562Y282206D01*
X554672Y282266D01*
X554797Y282306D01*
X554922Y282316D01*
G37*
G36*
G01X559646D02*
X559771Y282306D01*
X559896Y282266D01*
X560006Y282206D01*
X560106Y282126D01*
X560186Y282026D01*
X560246Y281916D01*
X560286Y281791D01*
X560296Y281666D01*
Y278236D01*
X560326Y278206D01*
X560426Y278066D01*
X560446Y278026D01*
X560461Y277991D01*
X560481Y277951D01*
X560496Y277911D01*
X560506Y277871D01*
X560521Y277826D01*
X560526Y277786D01*
X560536Y277746D01*
X560541Y277701D01*
Y277661D01*
X560546Y277616D01*
X560541Y277571D01*
Y277531D01*
X560536Y277486D01*
X560526Y277446D01*
X560521Y277406D01*
X560506Y277361D01*
X560496Y277321D01*
X560481Y277281D01*
X560461Y277241D01*
X560446Y277206D01*
X560426Y277166D01*
X560326Y277026D01*
X560296Y276996D01*
Y275866D01*
X560286Y275741D01*
X560246Y275616D01*
X560186Y275506D01*
X560106Y275406D01*
X560006Y275326D01*
X559896Y275266D01*
X559771Y275226D01*
X559646Y275216D01*
X559521Y275226D01*
X559396Y275266D01*
X559286Y275326D01*
X559186Y275406D01*
X559106Y275506D01*
X559046Y275616D01*
X559006Y275741D01*
X558996Y275866D01*
Y276996D01*
X558966Y277026D01*
X558866Y277166D01*
X558846Y277206D01*
X558831Y277241D01*
X558811Y277281D01*
X558796Y277321D01*
X558786Y277361D01*
X558771Y277406D01*
X558766Y277446D01*
X558756Y277486D01*
X558751Y277531D01*
Y277571D01*
X558746Y277616D01*
X558751Y277661D01*
Y277701D01*
X558756Y277746D01*
X558766Y277786D01*
X558771Y277826D01*
X558786Y277871D01*
X558796Y277911D01*
X558811Y277951D01*
X558831Y277991D01*
X558846Y278026D01*
X558866Y278066D01*
X558966Y278206D01*
X558996Y278236D01*
Y281666D01*
X559006Y281791D01*
X559046Y281916D01*
X559106Y282026D01*
X559186Y282126D01*
X559286Y282206D01*
X559396Y282266D01*
X559521Y282306D01*
X559646Y282316D01*
G37*
G36*
G01X564370D02*
X564495Y282306D01*
X564620Y282266D01*
X564730Y282206D01*
X564830Y282126D01*
X564910Y282026D01*
X564970Y281916D01*
X565010Y281791D01*
X565020Y281666D01*
Y278236D01*
X565050Y278206D01*
X565150Y278066D01*
X565170Y278026D01*
X565185Y277991D01*
X565205Y277951D01*
X565220Y277911D01*
X565230Y277871D01*
X565245Y277826D01*
X565250Y277786D01*
X565260Y277746D01*
X565265Y277701D01*
Y277661D01*
X565270Y277616D01*
X565265Y277571D01*
Y277531D01*
X565260Y277486D01*
X565250Y277446D01*
X565245Y277406D01*
X565230Y277361D01*
X565220Y277321D01*
X565205Y277281D01*
X565185Y277241D01*
X565170Y277206D01*
X565150Y277166D01*
X565050Y277026D01*
X565020Y276996D01*
Y275866D01*
X565010Y275741D01*
X564970Y275616D01*
X564910Y275506D01*
X564830Y275406D01*
X564730Y275326D01*
X564620Y275266D01*
X564495Y275226D01*
X564370Y275216D01*
X564245Y275226D01*
X564120Y275266D01*
X564010Y275326D01*
X563910Y275406D01*
X563830Y275506D01*
X563770Y275616D01*
X563730Y275741D01*
X563720Y275866D01*
Y276996D01*
X563690Y277026D01*
X563590Y277166D01*
X563570Y277206D01*
X563555Y277241D01*
X563535Y277281D01*
X563520Y277321D01*
X563510Y277361D01*
X563495Y277406D01*
X563490Y277446D01*
X563480Y277486D01*
X563475Y277531D01*
Y277571D01*
X563470Y277616D01*
X563475Y277661D01*
Y277701D01*
X563480Y277746D01*
X563490Y277786D01*
X563495Y277826D01*
X563510Y277871D01*
X563520Y277911D01*
X563535Y277951D01*
X563555Y277991D01*
X563570Y278026D01*
X563590Y278066D01*
X563690Y278206D01*
X563720Y278236D01*
Y281666D01*
X563730Y281791D01*
X563770Y281916D01*
X563830Y282026D01*
X563910Y282126D01*
X564010Y282206D01*
X564120Y282266D01*
X564245Y282306D01*
X564370Y282316D01*
G37*
G36*
G01X569095D02*
X569220Y282306D01*
X569345Y282266D01*
X569455Y282206D01*
X569555Y282126D01*
X569635Y282026D01*
X569695Y281916D01*
X569735Y281791D01*
X569745Y281666D01*
Y278236D01*
X569775Y278206D01*
X569875Y278066D01*
X569895Y278026D01*
X569910Y277991D01*
X569930Y277951D01*
X569945Y277911D01*
X569955Y277871D01*
X569970Y277826D01*
X569975Y277786D01*
X569985Y277746D01*
X569990Y277701D01*
Y277661D01*
X569995Y277616D01*
X569990Y277571D01*
Y277531D01*
X569985Y277486D01*
X569975Y277446D01*
X569970Y277406D01*
X569955Y277361D01*
X569945Y277321D01*
X569930Y277281D01*
X569910Y277241D01*
X569895Y277206D01*
X569875Y277166D01*
X569775Y277026D01*
X569745Y276996D01*
Y275866D01*
X569735Y275741D01*
X569695Y275616D01*
X569635Y275506D01*
X569555Y275406D01*
X569455Y275326D01*
X569345Y275266D01*
X569220Y275226D01*
X569095Y275216D01*
X568970Y275226D01*
X568845Y275266D01*
X568735Y275326D01*
X568635Y275406D01*
X568555Y275506D01*
X568495Y275616D01*
X568455Y275741D01*
X568445Y275866D01*
Y276996D01*
X568415Y277026D01*
X568315Y277166D01*
X568295Y277206D01*
X568280Y277241D01*
X568260Y277281D01*
X568245Y277321D01*
X568235Y277361D01*
X568220Y277406D01*
X568215Y277446D01*
X568205Y277486D01*
X568200Y277531D01*
Y277571D01*
X568195Y277616D01*
X568200Y277661D01*
Y277701D01*
X568205Y277746D01*
X568215Y277786D01*
X568220Y277826D01*
X568235Y277871D01*
X568245Y277911D01*
X568260Y277951D01*
X568280Y277991D01*
X568295Y278026D01*
X568315Y278066D01*
X568415Y278206D01*
X568445Y278236D01*
Y281666D01*
X568455Y281791D01*
X568495Y281916D01*
X568555Y282026D01*
X568635Y282126D01*
X568735Y282206D01*
X568845Y282266D01*
X568970Y282306D01*
X569095Y282316D01*
G37*
G36*
G01X573819D02*
X573944Y282306D01*
X574069Y282266D01*
X574179Y282206D01*
X574279Y282126D01*
X574359Y282026D01*
X574419Y281916D01*
X574459Y281791D01*
X574469Y281666D01*
Y278236D01*
X574499Y278206D01*
X574599Y278066D01*
X574619Y278026D01*
X574634Y277991D01*
X574654Y277951D01*
X574669Y277911D01*
X574679Y277871D01*
X574694Y277826D01*
X574699Y277786D01*
X574709Y277746D01*
X574714Y277701D01*
Y277661D01*
X574719Y277616D01*
X574714Y277571D01*
Y277531D01*
X574709Y277486D01*
X574699Y277446D01*
X574694Y277406D01*
X574679Y277361D01*
X574669Y277321D01*
X574654Y277281D01*
X574634Y277241D01*
X574619Y277206D01*
X574599Y277166D01*
X574499Y277026D01*
X574469Y276996D01*
Y275866D01*
X574459Y275741D01*
X574419Y275616D01*
X574359Y275506D01*
X574279Y275406D01*
X574179Y275326D01*
X574069Y275266D01*
X573944Y275226D01*
X573819Y275216D01*
X573694Y275226D01*
X573569Y275266D01*
X573459Y275326D01*
X573359Y275406D01*
X573279Y275506D01*
X573219Y275616D01*
X573179Y275741D01*
X573169Y275866D01*
Y276996D01*
X573139Y277026D01*
X573039Y277166D01*
X573019Y277206D01*
X573004Y277241D01*
X572984Y277281D01*
X572969Y277321D01*
X572959Y277361D01*
X572944Y277406D01*
X572939Y277446D01*
X572929Y277486D01*
X572924Y277531D01*
Y277571D01*
X572919Y277616D01*
X572924Y277661D01*
Y277701D01*
X572929Y277746D01*
X572939Y277786D01*
X572944Y277826D01*
X572959Y277871D01*
X572969Y277911D01*
X572984Y277951D01*
X573004Y277991D01*
X573019Y278026D01*
X573039Y278066D01*
X573139Y278206D01*
X573169Y278236D01*
Y281666D01*
X573179Y281791D01*
X573219Y281916D01*
X573279Y282026D01*
X573359Y282126D01*
X573459Y282206D01*
X573569Y282266D01*
X573694Y282306D01*
X573819Y282316D01*
G37*
G36*
G01X578544D02*
X578669Y282306D01*
X578794Y282266D01*
X578904Y282206D01*
X579004Y282126D01*
X579084Y282026D01*
X579144Y281916D01*
X579184Y281791D01*
X579194Y281666D01*
Y278236D01*
X579224Y278206D01*
X579324Y278066D01*
X579344Y278026D01*
X579359Y277991D01*
X579379Y277951D01*
X579394Y277911D01*
X579404Y277871D01*
X579419Y277826D01*
X579424Y277786D01*
X579434Y277746D01*
X579439Y277701D01*
Y277661D01*
X579444Y277616D01*
X579439Y277571D01*
Y277531D01*
X579434Y277486D01*
X579424Y277446D01*
X579419Y277406D01*
X579404Y277361D01*
X579394Y277321D01*
X579379Y277281D01*
X579359Y277241D01*
X579344Y277206D01*
X579324Y277166D01*
X579224Y277026D01*
X579194Y276996D01*
Y275866D01*
X579184Y275741D01*
X579144Y275616D01*
X579084Y275506D01*
X579004Y275406D01*
X578904Y275326D01*
X578794Y275266D01*
X578669Y275226D01*
X578544Y275216D01*
X578419Y275226D01*
X578294Y275266D01*
X578184Y275326D01*
X578084Y275406D01*
X578004Y275506D01*
X577944Y275616D01*
X577904Y275741D01*
X577894Y275866D01*
Y276996D01*
X577864Y277026D01*
X577764Y277166D01*
X577744Y277206D01*
X577729Y277241D01*
X577709Y277281D01*
X577694Y277321D01*
X577684Y277361D01*
X577669Y277406D01*
X577664Y277446D01*
X577654Y277486D01*
X577649Y277531D01*
Y277571D01*
X577644Y277616D01*
X577649Y277661D01*
Y277701D01*
X577654Y277746D01*
X577664Y277786D01*
X577669Y277826D01*
X577684Y277871D01*
X577694Y277911D01*
X577709Y277951D01*
X577729Y277991D01*
X577744Y278026D01*
X577764Y278066D01*
X577864Y278206D01*
X577894Y278236D01*
Y281666D01*
X577904Y281791D01*
X577944Y281916D01*
X578004Y282026D01*
X578084Y282126D01*
X578184Y282206D01*
X578294Y282266D01*
X578419Y282306D01*
X578544Y282316D01*
G37*
G36*
G01X583268D02*
X583393Y282306D01*
X583518Y282266D01*
X583628Y282206D01*
X583728Y282126D01*
X583808Y282026D01*
X583868Y281916D01*
X583908Y281791D01*
X583918Y281666D01*
Y278236D01*
X583948Y278206D01*
X584048Y278066D01*
X584068Y278026D01*
X584083Y277991D01*
X584103Y277951D01*
X584118Y277911D01*
X584128Y277871D01*
X584143Y277826D01*
X584148Y277786D01*
X584158Y277746D01*
X584163Y277701D01*
Y277661D01*
X584168Y277616D01*
X584163Y277571D01*
Y277531D01*
X584158Y277486D01*
X584148Y277446D01*
X584143Y277406D01*
X584128Y277361D01*
X584118Y277321D01*
X584103Y277281D01*
X584083Y277241D01*
X584068Y277206D01*
X584048Y277166D01*
X583948Y277026D01*
X583918Y276996D01*
Y275866D01*
X583908Y275741D01*
X583868Y275616D01*
X583808Y275506D01*
X583728Y275406D01*
X583628Y275326D01*
X583518Y275266D01*
X583393Y275226D01*
X583268Y275216D01*
X583143Y275226D01*
X583018Y275266D01*
X582908Y275326D01*
X582808Y275406D01*
X582728Y275506D01*
X582668Y275616D01*
X582628Y275741D01*
X582618Y275866D01*
Y276996D01*
X582588Y277026D01*
X582488Y277166D01*
X582468Y277206D01*
X582453Y277241D01*
X582433Y277281D01*
X582418Y277321D01*
X582408Y277361D01*
X582393Y277406D01*
X582388Y277446D01*
X582378Y277486D01*
X582373Y277531D01*
Y277571D01*
X582368Y277616D01*
X582373Y277661D01*
Y277701D01*
X582378Y277746D01*
X582388Y277786D01*
X582393Y277826D01*
X582408Y277871D01*
X582418Y277911D01*
X582433Y277951D01*
X582453Y277991D01*
X582468Y278026D01*
X582488Y278066D01*
X582588Y278206D01*
X582618Y278236D01*
Y281666D01*
X582628Y281791D01*
X582668Y281916D01*
X582728Y282026D01*
X582808Y282126D01*
X582908Y282206D01*
X583018Y282266D01*
X583143Y282306D01*
X583268Y282316D01*
G37*
G36*
G01X587992D02*
X588117Y282306D01*
X588242Y282266D01*
X588352Y282206D01*
X588452Y282126D01*
X588532Y282026D01*
X588592Y281916D01*
X588632Y281791D01*
X588642Y281666D01*
Y278236D01*
X588672Y278206D01*
X588772Y278066D01*
X588792Y278026D01*
X588807Y277991D01*
X588827Y277951D01*
X588842Y277911D01*
X588852Y277871D01*
X588867Y277826D01*
X588872Y277786D01*
X588882Y277746D01*
X588887Y277701D01*
Y277661D01*
X588892Y277616D01*
X588887Y277571D01*
Y277531D01*
X588882Y277486D01*
X588872Y277446D01*
X588867Y277406D01*
X588852Y277361D01*
X588842Y277321D01*
X588827Y277281D01*
X588807Y277241D01*
X588792Y277206D01*
X588772Y277166D01*
X588672Y277026D01*
X588642Y276996D01*
Y275866D01*
X588632Y275741D01*
X588592Y275616D01*
X588532Y275506D01*
X588452Y275406D01*
X588352Y275326D01*
X588242Y275266D01*
X588117Y275226D01*
X587992Y275216D01*
X587867Y275226D01*
X587742Y275266D01*
X587632Y275326D01*
X587532Y275406D01*
X587452Y275506D01*
X587392Y275616D01*
X587352Y275741D01*
X587342Y275866D01*
Y276996D01*
X587312Y277026D01*
X587212Y277166D01*
X587192Y277206D01*
X587177Y277241D01*
X587157Y277281D01*
X587142Y277321D01*
X587132Y277361D01*
X587117Y277406D01*
X587112Y277446D01*
X587102Y277486D01*
X587097Y277531D01*
Y277571D01*
X587092Y277616D01*
X587097Y277661D01*
Y277701D01*
X587102Y277746D01*
X587112Y277786D01*
X587117Y277826D01*
X587132Y277871D01*
X587142Y277911D01*
X587157Y277951D01*
X587177Y277991D01*
X587192Y278026D01*
X587212Y278066D01*
X587312Y278206D01*
X587342Y278236D01*
Y281666D01*
X587352Y281791D01*
X587392Y281916D01*
X587452Y282026D01*
X587532Y282126D01*
X587632Y282206D01*
X587742Y282266D01*
X587867Y282306D01*
X587992Y282316D01*
G37*
G36*
G01X592717D02*
X592842Y282306D01*
X592967Y282266D01*
X593077Y282206D01*
X593177Y282126D01*
X593257Y282026D01*
X593317Y281916D01*
X593357Y281791D01*
X593367Y281666D01*
Y278236D01*
X593397Y278206D01*
X593497Y278066D01*
X593517Y278026D01*
X593532Y277991D01*
X593552Y277951D01*
X593567Y277911D01*
X593577Y277871D01*
X593592Y277826D01*
X593597Y277786D01*
X593607Y277746D01*
X593612Y277701D01*
Y277661D01*
X593617Y277616D01*
X593612Y277571D01*
Y277531D01*
X593607Y277486D01*
X593597Y277446D01*
X593592Y277406D01*
X593577Y277361D01*
X593567Y277321D01*
X593552Y277281D01*
X593532Y277241D01*
X593517Y277206D01*
X593497Y277166D01*
X593397Y277026D01*
X593367Y276996D01*
Y275866D01*
X593357Y275741D01*
X593317Y275616D01*
X593257Y275506D01*
X593177Y275406D01*
X593077Y275326D01*
X592967Y275266D01*
X592842Y275226D01*
X592717Y275216D01*
X592592Y275226D01*
X592467Y275266D01*
X592357Y275326D01*
X592257Y275406D01*
X592177Y275506D01*
X592117Y275616D01*
X592077Y275741D01*
X592067Y275866D01*
Y276996D01*
X592037Y277026D01*
X591937Y277166D01*
X591917Y277206D01*
X591902Y277241D01*
X591882Y277281D01*
X591867Y277321D01*
X591857Y277361D01*
X591842Y277406D01*
X591837Y277446D01*
X591827Y277486D01*
X591822Y277531D01*
Y277571D01*
X591817Y277616D01*
X591822Y277661D01*
Y277701D01*
X591827Y277746D01*
X591837Y277786D01*
X591842Y277826D01*
X591857Y277871D01*
X591867Y277911D01*
X591882Y277951D01*
X591902Y277991D01*
X591917Y278026D01*
X591937Y278066D01*
X592037Y278206D01*
X592067Y278236D01*
Y281666D01*
X592077Y281791D01*
X592117Y281916D01*
X592177Y282026D01*
X592257Y282126D01*
X592357Y282206D01*
X592467Y282266D01*
X592592Y282306D01*
X592717Y282316D01*
G37*
G36*
G01X597441D02*
X597566Y282306D01*
X597691Y282266D01*
X597801Y282206D01*
X597901Y282126D01*
X597981Y282026D01*
X598041Y281916D01*
X598081Y281791D01*
X598091Y281666D01*
Y278236D01*
X598121Y278206D01*
X598221Y278066D01*
X598241Y278026D01*
X598256Y277991D01*
X598276Y277951D01*
X598291Y277911D01*
X598301Y277871D01*
X598316Y277826D01*
X598321Y277786D01*
X598331Y277746D01*
X598336Y277701D01*
Y277661D01*
X598341Y277616D01*
X598336Y277571D01*
Y277531D01*
X598331Y277486D01*
X598321Y277446D01*
X598316Y277406D01*
X598301Y277361D01*
X598291Y277321D01*
X598276Y277281D01*
X598256Y277241D01*
X598241Y277206D01*
X598221Y277166D01*
X598121Y277026D01*
X598091Y276996D01*
Y275866D01*
X598081Y275741D01*
X598041Y275616D01*
X597981Y275506D01*
X597901Y275406D01*
X597801Y275326D01*
X597691Y275266D01*
X597566Y275226D01*
X597441Y275216D01*
X597316Y275226D01*
X597191Y275266D01*
X597081Y275326D01*
X596981Y275406D01*
X596901Y275506D01*
X596841Y275616D01*
X596801Y275741D01*
X596791Y275866D01*
Y276996D01*
X596761Y277026D01*
X596661Y277166D01*
X596641Y277206D01*
X596626Y277241D01*
X596606Y277281D01*
X596591Y277321D01*
X596581Y277361D01*
X596566Y277406D01*
X596561Y277446D01*
X596551Y277486D01*
X596546Y277531D01*
Y277571D01*
X596541Y277616D01*
X596546Y277661D01*
Y277701D01*
X596551Y277746D01*
X596561Y277786D01*
X596566Y277826D01*
X596581Y277871D01*
X596591Y277911D01*
X596606Y277951D01*
X596626Y277991D01*
X596641Y278026D01*
X596661Y278066D01*
X596761Y278206D01*
X596791Y278236D01*
Y281666D01*
X596801Y281791D01*
X596841Y281916D01*
X596901Y282026D01*
X596981Y282126D01*
X597081Y282206D01*
X597191Y282266D01*
X597316Y282306D01*
X597441Y282316D01*
G37*
G36*
G01X602166D02*
X602291Y282306D01*
X602416Y282266D01*
X602526Y282206D01*
X602626Y282126D01*
X602706Y282026D01*
X602766Y281916D01*
X602806Y281791D01*
X602816Y281666D01*
Y278236D01*
X602846Y278206D01*
X602946Y278066D01*
X602966Y278026D01*
X602981Y277991D01*
X603001Y277951D01*
X603016Y277911D01*
X603026Y277871D01*
X603041Y277826D01*
X603046Y277786D01*
X603056Y277746D01*
X603061Y277701D01*
Y277661D01*
X603066Y277616D01*
X603061Y277571D01*
Y277531D01*
X603056Y277486D01*
X603046Y277446D01*
X603041Y277406D01*
X603026Y277361D01*
X603016Y277321D01*
X603001Y277281D01*
X602981Y277241D01*
X602966Y277206D01*
X602946Y277166D01*
X602846Y277026D01*
X602816Y276996D01*
Y275866D01*
X602806Y275741D01*
X602766Y275616D01*
X602706Y275506D01*
X602626Y275406D01*
X602526Y275326D01*
X602416Y275266D01*
X602291Y275226D01*
X602166Y275216D01*
X602041Y275226D01*
X601916Y275266D01*
X601806Y275326D01*
X601706Y275406D01*
X601626Y275506D01*
X601566Y275616D01*
X601526Y275741D01*
X601516Y275866D01*
Y276996D01*
X601486Y277026D01*
X601386Y277166D01*
X601366Y277206D01*
X601351Y277241D01*
X601331Y277281D01*
X601316Y277321D01*
X601306Y277361D01*
X601291Y277406D01*
X601286Y277446D01*
X601276Y277486D01*
X601271Y277531D01*
Y277571D01*
X601266Y277616D01*
X601271Y277661D01*
Y277701D01*
X601276Y277746D01*
X601286Y277786D01*
X601291Y277826D01*
X601306Y277871D01*
X601316Y277911D01*
X601331Y277951D01*
X601351Y277991D01*
X601366Y278026D01*
X601386Y278066D01*
X601486Y278206D01*
X601516Y278236D01*
Y281666D01*
X601526Y281791D01*
X601566Y281916D01*
X601626Y282026D01*
X601706Y282126D01*
X601806Y282206D01*
X601916Y282266D01*
X602041Y282306D01*
X602166Y282316D01*
G37*
G36*
G01X606890D02*
X607015Y282306D01*
X607140Y282266D01*
X607250Y282206D01*
X607350Y282126D01*
X607430Y282026D01*
X607490Y281916D01*
X607530Y281791D01*
X607540Y281666D01*
Y278236D01*
X607570Y278206D01*
X607670Y278066D01*
X607690Y278026D01*
X607705Y277991D01*
X607725Y277951D01*
X607740Y277911D01*
X607750Y277871D01*
X607765Y277826D01*
X607770Y277786D01*
X607780Y277746D01*
X607785Y277701D01*
Y277661D01*
X607790Y277616D01*
X607785Y277571D01*
Y277531D01*
X607780Y277486D01*
X607770Y277446D01*
X607765Y277406D01*
X607750Y277361D01*
X607740Y277321D01*
X607725Y277281D01*
X607705Y277241D01*
X607690Y277206D01*
X607670Y277166D01*
X607570Y277026D01*
X607540Y276996D01*
Y275866D01*
X607530Y275741D01*
X607490Y275616D01*
X607430Y275506D01*
X607350Y275406D01*
X607250Y275326D01*
X607140Y275266D01*
X607015Y275226D01*
X606890Y275216D01*
X606765Y275226D01*
X606640Y275266D01*
X606530Y275326D01*
X606430Y275406D01*
X606350Y275506D01*
X606290Y275616D01*
X606250Y275741D01*
X606240Y275866D01*
Y276996D01*
X606210Y277026D01*
X606110Y277166D01*
X606090Y277206D01*
X606075Y277241D01*
X606055Y277281D01*
X606040Y277321D01*
X606030Y277361D01*
X606015Y277406D01*
X606010Y277446D01*
X606000Y277486D01*
X605995Y277531D01*
Y277571D01*
X605990Y277616D01*
X605995Y277661D01*
Y277701D01*
X606000Y277746D01*
X606010Y277786D01*
X606015Y277826D01*
X606030Y277871D01*
X606040Y277911D01*
X606055Y277951D01*
X606075Y277991D01*
X606090Y278026D01*
X606110Y278066D01*
X606210Y278206D01*
X606240Y278236D01*
Y281666D01*
X606250Y281791D01*
X606290Y281916D01*
X606350Y282026D01*
X606430Y282126D01*
X606530Y282206D01*
X606640Y282266D01*
X606765Y282306D01*
X606890Y282316D01*
G37*
G36*
G01X611614D02*
X611739Y282306D01*
X611864Y282266D01*
X611974Y282206D01*
X612074Y282126D01*
X612154Y282026D01*
X612214Y281916D01*
X612254Y281791D01*
X612264Y281666D01*
Y278236D01*
X612294Y278206D01*
X612394Y278066D01*
X612414Y278026D01*
X612429Y277991D01*
X612449Y277951D01*
X612464Y277911D01*
X612474Y277871D01*
X612489Y277826D01*
X612494Y277786D01*
X612504Y277746D01*
X612509Y277701D01*
Y277661D01*
X612514Y277616D01*
X612509Y277571D01*
Y277531D01*
X612504Y277486D01*
X612494Y277446D01*
X612489Y277406D01*
X612474Y277361D01*
X612464Y277321D01*
X612449Y277281D01*
X612429Y277241D01*
X612414Y277206D01*
X612394Y277166D01*
X612294Y277026D01*
X612264Y276996D01*
Y275866D01*
X612254Y275741D01*
X612214Y275616D01*
X612154Y275506D01*
X612074Y275406D01*
X611974Y275326D01*
X611864Y275266D01*
X611739Y275226D01*
X611614Y275216D01*
X611489Y275226D01*
X611364Y275266D01*
X611254Y275326D01*
X611154Y275406D01*
X611074Y275506D01*
X611014Y275616D01*
X610974Y275741D01*
X610964Y275866D01*
Y276996D01*
X610934Y277026D01*
X610834Y277166D01*
X610814Y277206D01*
X610799Y277241D01*
X610779Y277281D01*
X610764Y277321D01*
X610754Y277361D01*
X610739Y277406D01*
X610734Y277446D01*
X610724Y277486D01*
X610719Y277531D01*
Y277571D01*
X610714Y277616D01*
X610719Y277661D01*
Y277701D01*
X610724Y277746D01*
X610734Y277786D01*
X610739Y277826D01*
X610754Y277871D01*
X610764Y277911D01*
X610779Y277951D01*
X610799Y277991D01*
X610814Y278026D01*
X610834Y278066D01*
X610934Y278206D01*
X610964Y278236D01*
Y281666D01*
X610974Y281791D01*
X611014Y281916D01*
X611074Y282026D01*
X611154Y282126D01*
X611254Y282206D01*
X611364Y282266D01*
X611489Y282306D01*
X611614Y282316D01*
G37*
G36*
G01X616339D02*
X616464Y282306D01*
X616589Y282266D01*
X616699Y282206D01*
X616799Y282126D01*
X616879Y282026D01*
X616939Y281916D01*
X616979Y281791D01*
X616989Y281666D01*
Y278236D01*
X617019Y278206D01*
X617119Y278066D01*
X617139Y278026D01*
X617154Y277991D01*
X617174Y277951D01*
X617189Y277911D01*
X617199Y277871D01*
X617214Y277826D01*
X617219Y277786D01*
X617229Y277746D01*
X617234Y277701D01*
Y277661D01*
X617239Y277616D01*
X617234Y277571D01*
Y277531D01*
X617229Y277486D01*
X617219Y277446D01*
X617214Y277406D01*
X617199Y277361D01*
X617189Y277321D01*
X617174Y277281D01*
X617154Y277241D01*
X617139Y277206D01*
X617119Y277166D01*
X617019Y277026D01*
X616989Y276996D01*
Y275866D01*
X616979Y275741D01*
X616939Y275616D01*
X616879Y275506D01*
X616799Y275406D01*
X616699Y275326D01*
X616589Y275266D01*
X616464Y275226D01*
X616339Y275216D01*
X616214Y275226D01*
X616089Y275266D01*
X615979Y275326D01*
X615879Y275406D01*
X615799Y275506D01*
X615739Y275616D01*
X615699Y275741D01*
X615689Y275866D01*
Y276996D01*
X615659Y277026D01*
X615559Y277166D01*
X615539Y277206D01*
X615524Y277241D01*
X615504Y277281D01*
X615489Y277321D01*
X615479Y277361D01*
X615464Y277406D01*
X615459Y277446D01*
X615449Y277486D01*
X615444Y277531D01*
Y277571D01*
X615439Y277616D01*
X615444Y277661D01*
Y277701D01*
X615449Y277746D01*
X615459Y277786D01*
X615464Y277826D01*
X615479Y277871D01*
X615489Y277911D01*
X615504Y277951D01*
X615524Y277991D01*
X615539Y278026D01*
X615559Y278066D01*
X615659Y278206D01*
X615689Y278236D01*
Y281666D01*
X615699Y281791D01*
X615739Y281916D01*
X615799Y282026D01*
X615879Y282126D01*
X615979Y282206D01*
X616089Y282266D01*
X616214Y282306D01*
X616339Y282316D01*
G37*
G36*
G01X621063D02*
X621188Y282306D01*
X621313Y282266D01*
X621423Y282206D01*
X621523Y282126D01*
X621603Y282026D01*
X621663Y281916D01*
X621703Y281791D01*
X621713Y281666D01*
Y278236D01*
X621743Y278206D01*
X621843Y278066D01*
X621863Y278026D01*
X621878Y277991D01*
X621898Y277951D01*
X621913Y277911D01*
X621923Y277871D01*
X621938Y277826D01*
X621943Y277786D01*
X621953Y277746D01*
X621958Y277701D01*
Y277661D01*
X621963Y277616D01*
X621958Y277571D01*
Y277531D01*
X621953Y277486D01*
X621943Y277446D01*
X621938Y277406D01*
X621923Y277361D01*
X621913Y277321D01*
X621898Y277281D01*
X621878Y277241D01*
X621863Y277206D01*
X621843Y277166D01*
X621743Y277026D01*
X621713Y276996D01*
Y275866D01*
X621703Y275741D01*
X621663Y275616D01*
X621603Y275506D01*
X621523Y275406D01*
X621423Y275326D01*
X621313Y275266D01*
X621188Y275226D01*
X621063Y275216D01*
X620938Y275226D01*
X620813Y275266D01*
X620703Y275326D01*
X620603Y275406D01*
X620523Y275506D01*
X620463Y275616D01*
X620423Y275741D01*
X620413Y275866D01*
Y276996D01*
X620383Y277026D01*
X620283Y277166D01*
X620263Y277206D01*
X620248Y277241D01*
X620228Y277281D01*
X620213Y277321D01*
X620203Y277361D01*
X620188Y277406D01*
X620183Y277446D01*
X620173Y277486D01*
X620168Y277531D01*
Y277571D01*
X620163Y277616D01*
X620168Y277661D01*
Y277701D01*
X620173Y277746D01*
X620183Y277786D01*
X620188Y277826D01*
X620203Y277871D01*
X620213Y277911D01*
X620228Y277951D01*
X620248Y277991D01*
X620263Y278026D01*
X620283Y278066D01*
X620383Y278206D01*
X620413Y278236D01*
Y281666D01*
X620423Y281791D01*
X620463Y281916D01*
X620523Y282026D01*
X620603Y282126D01*
X620703Y282206D01*
X620813Y282266D01*
X620938Y282306D01*
X621063Y282316D01*
G37*
G36*
G01X625788D02*
X625913Y282306D01*
X626038Y282266D01*
X626148Y282206D01*
X626248Y282126D01*
X626328Y282026D01*
X626388Y281916D01*
X626428Y281791D01*
X626438Y281666D01*
Y278236D01*
X626468Y278206D01*
X626568Y278066D01*
X626588Y278026D01*
X626603Y277991D01*
X626623Y277951D01*
X626638Y277911D01*
X626648Y277871D01*
X626663Y277826D01*
X626668Y277786D01*
X626678Y277746D01*
X626683Y277701D01*
Y277661D01*
X626688Y277616D01*
X626683Y277571D01*
Y277531D01*
X626678Y277486D01*
X626668Y277446D01*
X626663Y277406D01*
X626648Y277361D01*
X626638Y277321D01*
X626623Y277281D01*
X626603Y277241D01*
X626588Y277206D01*
X626568Y277166D01*
X626468Y277026D01*
X626438Y276996D01*
Y275866D01*
X626428Y275741D01*
X626388Y275616D01*
X626328Y275506D01*
X626248Y275406D01*
X626148Y275326D01*
X626038Y275266D01*
X625913Y275226D01*
X625788Y275216D01*
X625663Y275226D01*
X625538Y275266D01*
X625428Y275326D01*
X625328Y275406D01*
X625248Y275506D01*
X625188Y275616D01*
X625148Y275741D01*
X625138Y275866D01*
Y276996D01*
X625108Y277026D01*
X625008Y277166D01*
X624988Y277206D01*
X624973Y277241D01*
X624953Y277281D01*
X624938Y277321D01*
X624928Y277361D01*
X624913Y277406D01*
X624908Y277446D01*
X624898Y277486D01*
X624893Y277531D01*
Y277571D01*
X624888Y277616D01*
X624893Y277661D01*
Y277701D01*
X624898Y277746D01*
X624908Y277786D01*
X624913Y277826D01*
X624928Y277871D01*
X624938Y277911D01*
X624953Y277951D01*
X624973Y277991D01*
X624988Y278026D01*
X625008Y278066D01*
X625108Y278206D01*
X625138Y278236D01*
Y281666D01*
X625148Y281791D01*
X625188Y281916D01*
X625248Y282026D01*
X625328Y282126D01*
X625428Y282206D01*
X625538Y282266D01*
X625663Y282306D01*
X625788Y282316D01*
G37*
G36*
G01X630512D02*
X630637Y282306D01*
X630762Y282266D01*
X630872Y282206D01*
X630972Y282126D01*
X631052Y282026D01*
X631112Y281916D01*
X631152Y281791D01*
X631162Y281666D01*
Y278236D01*
X631192Y278206D01*
X631292Y278066D01*
X631312Y278026D01*
X631327Y277991D01*
X631347Y277951D01*
X631362Y277911D01*
X631372Y277871D01*
X631387Y277826D01*
X631392Y277786D01*
X631402Y277746D01*
X631407Y277701D01*
Y277661D01*
X631412Y277616D01*
X631407Y277571D01*
Y277531D01*
X631402Y277486D01*
X631392Y277446D01*
X631387Y277406D01*
X631372Y277361D01*
X631362Y277321D01*
X631347Y277281D01*
X631327Y277241D01*
X631312Y277206D01*
X631292Y277166D01*
X631192Y277026D01*
X631162Y276996D01*
Y275866D01*
X631152Y275741D01*
X631112Y275616D01*
X631052Y275506D01*
X630972Y275406D01*
X630872Y275326D01*
X630762Y275266D01*
X630637Y275226D01*
X630512Y275216D01*
X630387Y275226D01*
X630262Y275266D01*
X630152Y275326D01*
X630052Y275406D01*
X629972Y275506D01*
X629912Y275616D01*
X629872Y275741D01*
X629862Y275866D01*
Y276996D01*
X629832Y277026D01*
X629732Y277166D01*
X629712Y277206D01*
X629697Y277241D01*
X629677Y277281D01*
X629662Y277321D01*
X629652Y277361D01*
X629637Y277406D01*
X629632Y277446D01*
X629622Y277486D01*
X629617Y277531D01*
Y277571D01*
X629612Y277616D01*
X629617Y277661D01*
Y277701D01*
X629622Y277746D01*
X629632Y277786D01*
X629637Y277826D01*
X629652Y277871D01*
X629662Y277911D01*
X629677Y277951D01*
X629697Y277991D01*
X629712Y278026D01*
X629732Y278066D01*
X629832Y278206D01*
X629862Y278236D01*
Y281666D01*
X629872Y281791D01*
X629912Y281916D01*
X629972Y282026D01*
X630052Y282126D01*
X630152Y282206D01*
X630262Y282266D01*
X630387Y282306D01*
X630512Y282316D01*
G37*
G36*
G01X635236D02*
X635361Y282306D01*
X635486Y282266D01*
X635596Y282206D01*
X635696Y282126D01*
X635776Y282026D01*
X635836Y281916D01*
X635876Y281791D01*
X635886Y281666D01*
Y278236D01*
X635916Y278206D01*
X636016Y278066D01*
X636036Y278026D01*
X636051Y277991D01*
X636071Y277951D01*
X636086Y277911D01*
X636096Y277871D01*
X636111Y277826D01*
X636116Y277786D01*
X636126Y277746D01*
X636131Y277701D01*
Y277661D01*
X636136Y277616D01*
X636131Y277571D01*
Y277531D01*
X636126Y277486D01*
X636116Y277446D01*
X636111Y277406D01*
X636096Y277361D01*
X636086Y277321D01*
X636071Y277281D01*
X636051Y277241D01*
X636036Y277206D01*
X636016Y277166D01*
X635916Y277026D01*
X635886Y276996D01*
Y275866D01*
X635876Y275741D01*
X635836Y275616D01*
X635776Y275506D01*
X635696Y275406D01*
X635596Y275326D01*
X635486Y275266D01*
X635361Y275226D01*
X635236Y275216D01*
X635111Y275226D01*
X634986Y275266D01*
X634876Y275326D01*
X634776Y275406D01*
X634696Y275506D01*
X634636Y275616D01*
X634596Y275741D01*
X634586Y275866D01*
Y276996D01*
X634556Y277026D01*
X634456Y277166D01*
X634436Y277206D01*
X634421Y277241D01*
X634401Y277281D01*
X634386Y277321D01*
X634376Y277361D01*
X634361Y277406D01*
X634356Y277446D01*
X634346Y277486D01*
X634341Y277531D01*
Y277571D01*
X634336Y277616D01*
X634341Y277661D01*
Y277701D01*
X634346Y277746D01*
X634356Y277786D01*
X634361Y277826D01*
X634376Y277871D01*
X634386Y277911D01*
X634401Y277951D01*
X634421Y277991D01*
X634436Y278026D01*
X634456Y278066D01*
X634556Y278206D01*
X634586Y278236D01*
Y281666D01*
X634596Y281791D01*
X634636Y281916D01*
X634696Y282026D01*
X634776Y282126D01*
X634876Y282206D01*
X634986Y282266D01*
X635111Y282306D01*
X635236Y282316D01*
G37*
G36*
G01X639961D02*
X640086Y282306D01*
X640211Y282266D01*
X640321Y282206D01*
X640421Y282126D01*
X640501Y282026D01*
X640561Y281916D01*
X640601Y281791D01*
X640611Y281666D01*
Y278236D01*
X640641Y278206D01*
X640741Y278066D01*
X640761Y278026D01*
X640776Y277991D01*
X640796Y277951D01*
X640811Y277911D01*
X640821Y277871D01*
X640836Y277826D01*
X640841Y277786D01*
X640851Y277746D01*
X640856Y277701D01*
Y277661D01*
X640861Y277616D01*
X640856Y277571D01*
Y277531D01*
X640851Y277486D01*
X640841Y277446D01*
X640836Y277406D01*
X640821Y277361D01*
X640811Y277321D01*
X640796Y277281D01*
X640776Y277241D01*
X640761Y277206D01*
X640741Y277166D01*
X640641Y277026D01*
X640611Y276996D01*
Y275866D01*
X640601Y275741D01*
X640561Y275616D01*
X640501Y275506D01*
X640421Y275406D01*
X640321Y275326D01*
X640211Y275266D01*
X640086Y275226D01*
X639961Y275216D01*
X639836Y275226D01*
X639711Y275266D01*
X639601Y275326D01*
X639501Y275406D01*
X639421Y275506D01*
X639361Y275616D01*
X639321Y275741D01*
X639311Y275866D01*
Y276996D01*
X639281Y277026D01*
X639181Y277166D01*
X639161Y277206D01*
X639146Y277241D01*
X639126Y277281D01*
X639111Y277321D01*
X639101Y277361D01*
X639086Y277406D01*
X639081Y277446D01*
X639071Y277486D01*
X639066Y277531D01*
Y277571D01*
X639061Y277616D01*
X639066Y277661D01*
Y277701D01*
X639071Y277746D01*
X639081Y277786D01*
X639086Y277826D01*
X639101Y277871D01*
X639111Y277911D01*
X639126Y277951D01*
X639146Y277991D01*
X639161Y278026D01*
X639181Y278066D01*
X639281Y278206D01*
X639311Y278236D01*
Y281666D01*
X639321Y281791D01*
X639361Y281916D01*
X639421Y282026D01*
X639501Y282126D01*
X639601Y282206D01*
X639711Y282266D01*
X639836Y282306D01*
X639961Y282316D01*
G37*
G36*
G01X644685D02*
X644810Y282306D01*
X644935Y282266D01*
X645045Y282206D01*
X645145Y282126D01*
X645225Y282026D01*
X645285Y281916D01*
X645325Y281791D01*
X645335Y281666D01*
Y278236D01*
X645365Y278206D01*
X645465Y278066D01*
X645485Y278026D01*
X645500Y277991D01*
X645520Y277951D01*
X645535Y277911D01*
X645545Y277871D01*
X645560Y277826D01*
X645565Y277786D01*
X645575Y277746D01*
X645580Y277701D01*
Y277661D01*
X645585Y277616D01*
X645580Y277571D01*
Y277531D01*
X645575Y277486D01*
X645565Y277446D01*
X645560Y277406D01*
X645545Y277361D01*
X645535Y277321D01*
X645520Y277281D01*
X645500Y277241D01*
X645485Y277206D01*
X645465Y277166D01*
X645365Y277026D01*
X645335Y276996D01*
Y275866D01*
X645325Y275741D01*
X645285Y275616D01*
X645225Y275506D01*
X645145Y275406D01*
X645045Y275326D01*
X644935Y275266D01*
X644810Y275226D01*
X644685Y275216D01*
X644560Y275226D01*
X644435Y275266D01*
X644325Y275326D01*
X644225Y275406D01*
X644145Y275506D01*
X644085Y275616D01*
X644045Y275741D01*
X644035Y275866D01*
Y276996D01*
X644005Y277026D01*
X643905Y277166D01*
X643885Y277206D01*
X643870Y277241D01*
X643850Y277281D01*
X643835Y277321D01*
X643825Y277361D01*
X643810Y277406D01*
X643805Y277446D01*
X643795Y277486D01*
X643790Y277531D01*
Y277571D01*
X643785Y277616D01*
X643790Y277661D01*
Y277701D01*
X643795Y277746D01*
X643805Y277786D01*
X643810Y277826D01*
X643825Y277871D01*
X643835Y277911D01*
X643850Y277951D01*
X643870Y277991D01*
X643885Y278026D01*
X643905Y278066D01*
X644005Y278206D01*
X644035Y278236D01*
Y281666D01*
X644045Y281791D01*
X644085Y281916D01*
X644145Y282026D01*
X644225Y282126D01*
X644325Y282206D01*
X644435Y282266D01*
X644560Y282306D01*
X644685Y282316D01*
G37*
G36*
G01X649410D02*
X649535Y282306D01*
X649660Y282266D01*
X649770Y282206D01*
X649870Y282126D01*
X649950Y282026D01*
X650010Y281916D01*
X650050Y281791D01*
X650060Y281666D01*
Y278236D01*
X650090Y278206D01*
X650190Y278066D01*
X650210Y278026D01*
X650225Y277991D01*
X650245Y277951D01*
X650260Y277911D01*
X650270Y277871D01*
X650285Y277826D01*
X650290Y277786D01*
X650300Y277746D01*
X650305Y277701D01*
Y277661D01*
X650310Y277616D01*
X650305Y277571D01*
Y277531D01*
X650300Y277486D01*
X650290Y277446D01*
X650285Y277406D01*
X650270Y277361D01*
X650260Y277321D01*
X650245Y277281D01*
X650225Y277241D01*
X650210Y277206D01*
X650190Y277166D01*
X650090Y277026D01*
X650060Y276996D01*
Y275866D01*
X650050Y275741D01*
X650010Y275616D01*
X649950Y275506D01*
X649870Y275406D01*
X649770Y275326D01*
X649660Y275266D01*
X649535Y275226D01*
X649410Y275216D01*
X649285Y275226D01*
X649160Y275266D01*
X649050Y275326D01*
X648950Y275406D01*
X648870Y275506D01*
X648810Y275616D01*
X648770Y275741D01*
X648760Y275866D01*
Y276996D01*
X648730Y277026D01*
X648630Y277166D01*
X648610Y277206D01*
X648595Y277241D01*
X648575Y277281D01*
X648560Y277321D01*
X648550Y277361D01*
X648535Y277406D01*
X648530Y277446D01*
X648520Y277486D01*
X648515Y277531D01*
Y277571D01*
X648510Y277616D01*
X648515Y277661D01*
Y277701D01*
X648520Y277746D01*
X648530Y277786D01*
X648535Y277826D01*
X648550Y277871D01*
X648560Y277911D01*
X648575Y277951D01*
X648595Y277991D01*
X648610Y278026D01*
X648630Y278066D01*
X648730Y278206D01*
X648760Y278236D01*
Y281666D01*
X648770Y281791D01*
X648810Y281916D01*
X648870Y282026D01*
X648950Y282126D01*
X649050Y282206D01*
X649160Y282266D01*
X649285Y282306D01*
X649410Y282316D01*
G37*
G36*
G01X654134D02*
X654259Y282306D01*
X654384Y282266D01*
X654494Y282206D01*
X654594Y282126D01*
X654674Y282026D01*
X654734Y281916D01*
X654774Y281791D01*
X654784Y281666D01*
Y278236D01*
X654814Y278206D01*
X654914Y278066D01*
X654934Y278026D01*
X654949Y277991D01*
X654969Y277951D01*
X654984Y277911D01*
X654994Y277871D01*
X655009Y277826D01*
X655014Y277786D01*
X655024Y277746D01*
X655029Y277701D01*
Y277661D01*
X655034Y277616D01*
X655029Y277571D01*
Y277531D01*
X655024Y277486D01*
X655014Y277446D01*
X655009Y277406D01*
X654994Y277361D01*
X654984Y277321D01*
X654969Y277281D01*
X654949Y277241D01*
X654934Y277206D01*
X654914Y277166D01*
X654814Y277026D01*
X654784Y276996D01*
Y275866D01*
X654774Y275741D01*
X654734Y275616D01*
X654674Y275506D01*
X654594Y275406D01*
X654494Y275326D01*
X654384Y275266D01*
X654259Y275226D01*
X654134Y275216D01*
X654009Y275226D01*
X653884Y275266D01*
X653774Y275326D01*
X653674Y275406D01*
X653594Y275506D01*
X653534Y275616D01*
X653494Y275741D01*
X653484Y275866D01*
Y276996D01*
X653454Y277026D01*
X653354Y277166D01*
X653334Y277206D01*
X653319Y277241D01*
X653299Y277281D01*
X653284Y277321D01*
X653274Y277361D01*
X653259Y277406D01*
X653254Y277446D01*
X653244Y277486D01*
X653239Y277531D01*
Y277571D01*
X653234Y277616D01*
X653239Y277661D01*
Y277701D01*
X653244Y277746D01*
X653254Y277786D01*
X653259Y277826D01*
X653274Y277871D01*
X653284Y277911D01*
X653299Y277951D01*
X653319Y277991D01*
X653334Y278026D01*
X653354Y278066D01*
X653454Y278206D01*
X653484Y278236D01*
Y281666D01*
X653494Y281791D01*
X653534Y281916D01*
X653594Y282026D01*
X653674Y282126D01*
X653774Y282206D01*
X653884Y282266D01*
X654009Y282306D01*
X654134Y282316D01*
G37*
G36*
G01X668307D02*
X668432Y282306D01*
X668557Y282266D01*
X668667Y282206D01*
X668767Y282126D01*
X668847Y282026D01*
X668907Y281916D01*
X668947Y281791D01*
X668957Y281666D01*
Y278236D01*
X668987Y278206D01*
X669087Y278066D01*
X669107Y278026D01*
X669122Y277991D01*
X669142Y277951D01*
X669157Y277911D01*
X669167Y277871D01*
X669182Y277826D01*
X669187Y277786D01*
X669197Y277746D01*
X669202Y277701D01*
Y277661D01*
X669207Y277616D01*
X669202Y277571D01*
Y277531D01*
X669197Y277486D01*
X669187Y277446D01*
X669182Y277406D01*
X669167Y277361D01*
X669157Y277321D01*
X669142Y277281D01*
X669122Y277241D01*
X669107Y277206D01*
X669087Y277166D01*
X668987Y277026D01*
X668957Y276996D01*
Y275866D01*
X668947Y275741D01*
X668907Y275616D01*
X668847Y275506D01*
X668767Y275406D01*
X668667Y275326D01*
X668557Y275266D01*
X668432Y275226D01*
X668307Y275216D01*
X668182Y275226D01*
X668057Y275266D01*
X667947Y275326D01*
X667847Y275406D01*
X667767Y275506D01*
X667707Y275616D01*
X667667Y275741D01*
X667657Y275866D01*
Y276996D01*
X667627Y277026D01*
X667527Y277166D01*
X667507Y277206D01*
X667492Y277241D01*
X667472Y277281D01*
X667457Y277321D01*
X667447Y277361D01*
X667432Y277406D01*
X667427Y277446D01*
X667417Y277486D01*
X667412Y277531D01*
Y277571D01*
X667407Y277616D01*
X667412Y277661D01*
Y277701D01*
X667417Y277746D01*
X667427Y277786D01*
X667432Y277826D01*
X667447Y277871D01*
X667457Y277911D01*
X667472Y277951D01*
X667492Y277991D01*
X667507Y278026D01*
X667527Y278066D01*
X667627Y278206D01*
X667657Y278236D01*
Y281666D01*
X667667Y281791D01*
X667707Y281916D01*
X667767Y282026D01*
X667847Y282126D01*
X667947Y282206D01*
X668057Y282266D01*
X668182Y282306D01*
X668307Y282316D01*
G37*
G36*
G01X673032D02*
X673157Y282306D01*
X673282Y282266D01*
X673392Y282206D01*
X673492Y282126D01*
X673572Y282026D01*
X673632Y281916D01*
X673672Y281791D01*
X673682Y281666D01*
Y278236D01*
X673712Y278206D01*
X673812Y278066D01*
X673832Y278026D01*
X673847Y277991D01*
X673867Y277951D01*
X673882Y277911D01*
X673892Y277871D01*
X673907Y277826D01*
X673912Y277786D01*
X673922Y277746D01*
X673927Y277701D01*
Y277661D01*
X673932Y277616D01*
X673927Y277571D01*
Y277531D01*
X673922Y277486D01*
X673912Y277446D01*
X673907Y277406D01*
X673892Y277361D01*
X673882Y277321D01*
X673867Y277281D01*
X673847Y277241D01*
X673832Y277206D01*
X673812Y277166D01*
X673712Y277026D01*
X673682Y276996D01*
Y275866D01*
X673672Y275741D01*
X673632Y275616D01*
X673572Y275506D01*
X673492Y275406D01*
X673392Y275326D01*
X673282Y275266D01*
X673157Y275226D01*
X673032Y275216D01*
X672907Y275226D01*
X672782Y275266D01*
X672672Y275326D01*
X672572Y275406D01*
X672492Y275506D01*
X672432Y275616D01*
X672392Y275741D01*
X672382Y275866D01*
Y276996D01*
X672352Y277026D01*
X672252Y277166D01*
X672232Y277206D01*
X672217Y277241D01*
X672197Y277281D01*
X672182Y277321D01*
X672172Y277361D01*
X672157Y277406D01*
X672152Y277446D01*
X672142Y277486D01*
X672137Y277531D01*
Y277571D01*
X672132Y277616D01*
X672137Y277661D01*
Y277701D01*
X672142Y277746D01*
X672152Y277786D01*
X672157Y277826D01*
X672172Y277871D01*
X672182Y277911D01*
X672197Y277951D01*
X672217Y277991D01*
X672232Y278026D01*
X672252Y278066D01*
X672352Y278206D01*
X672382Y278236D01*
Y281666D01*
X672392Y281791D01*
X672432Y281916D01*
X672492Y282026D01*
X672572Y282126D01*
X672672Y282206D01*
X672782Y282266D01*
X672907Y282306D01*
X673032Y282316D01*
G37*
G36*
G01X677756D02*
X677881Y282306D01*
X678006Y282266D01*
X678116Y282206D01*
X678216Y282126D01*
X678296Y282026D01*
X678356Y281916D01*
X678396Y281791D01*
X678406Y281666D01*
Y278236D01*
X678436Y278206D01*
X678536Y278066D01*
X678556Y278026D01*
X678571Y277991D01*
X678591Y277951D01*
X678606Y277911D01*
X678616Y277871D01*
X678631Y277826D01*
X678636Y277786D01*
X678646Y277746D01*
X678651Y277701D01*
Y277661D01*
X678656Y277616D01*
X678651Y277571D01*
Y277531D01*
X678646Y277486D01*
X678636Y277446D01*
X678631Y277406D01*
X678616Y277361D01*
X678606Y277321D01*
X678591Y277281D01*
X678571Y277241D01*
X678556Y277206D01*
X678536Y277166D01*
X678436Y277026D01*
X678406Y276996D01*
Y275866D01*
X678396Y275741D01*
X678356Y275616D01*
X678296Y275506D01*
X678216Y275406D01*
X678116Y275326D01*
X678006Y275266D01*
X677881Y275226D01*
X677756Y275216D01*
X677631Y275226D01*
X677506Y275266D01*
X677396Y275326D01*
X677296Y275406D01*
X677216Y275506D01*
X677156Y275616D01*
X677116Y275741D01*
X677106Y275866D01*
Y276996D01*
X677076Y277026D01*
X676976Y277166D01*
X676956Y277206D01*
X676941Y277241D01*
X676921Y277281D01*
X676906Y277321D01*
X676896Y277361D01*
X676881Y277406D01*
X676876Y277446D01*
X676866Y277486D01*
X676861Y277531D01*
Y277571D01*
X676856Y277616D01*
X676861Y277661D01*
Y277701D01*
X676866Y277746D01*
X676876Y277786D01*
X676881Y277826D01*
X676896Y277871D01*
X676906Y277911D01*
X676921Y277951D01*
X676941Y277991D01*
X676956Y278026D01*
X676976Y278066D01*
X677076Y278206D01*
X677106Y278236D01*
Y281666D01*
X677116Y281791D01*
X677156Y281916D01*
X677216Y282026D01*
X677296Y282126D01*
X677396Y282206D01*
X677506Y282266D01*
X677631Y282306D01*
X677756Y282316D01*
G37*
G36*
G01X682481D02*
X682606Y282306D01*
X682731Y282266D01*
X682841Y282206D01*
X682941Y282126D01*
X683021Y282026D01*
X683081Y281916D01*
X683121Y281791D01*
X683131Y281666D01*
Y278236D01*
X683161Y278206D01*
X683261Y278066D01*
X683281Y278026D01*
X683296Y277991D01*
X683316Y277951D01*
X683331Y277911D01*
X683341Y277871D01*
X683356Y277826D01*
X683361Y277786D01*
X683371Y277746D01*
X683376Y277701D01*
Y277661D01*
X683381Y277616D01*
X683376Y277571D01*
Y277531D01*
X683371Y277486D01*
X683361Y277446D01*
X683356Y277406D01*
X683341Y277361D01*
X683331Y277321D01*
X683316Y277281D01*
X683296Y277241D01*
X683281Y277206D01*
X683261Y277166D01*
X683161Y277026D01*
X683131Y276996D01*
Y275866D01*
X683121Y275741D01*
X683081Y275616D01*
X683021Y275506D01*
X682941Y275406D01*
X682841Y275326D01*
X682731Y275266D01*
X682606Y275226D01*
X682481Y275216D01*
X682356Y275226D01*
X682231Y275266D01*
X682121Y275326D01*
X682021Y275406D01*
X681941Y275506D01*
X681881Y275616D01*
X681841Y275741D01*
X681831Y275866D01*
Y276996D01*
X681801Y277026D01*
X681701Y277166D01*
X681681Y277206D01*
X681666Y277241D01*
X681646Y277281D01*
X681631Y277321D01*
X681621Y277361D01*
X681606Y277406D01*
X681601Y277446D01*
X681591Y277486D01*
X681586Y277531D01*
Y277571D01*
X681581Y277616D01*
X681586Y277661D01*
Y277701D01*
X681591Y277746D01*
X681601Y277786D01*
X681606Y277826D01*
X681621Y277871D01*
X681631Y277911D01*
X681646Y277951D01*
X681666Y277991D01*
X681681Y278026D01*
X681701Y278066D01*
X681801Y278206D01*
X681831Y278236D01*
Y281666D01*
X681841Y281791D01*
X681881Y281916D01*
X681941Y282026D01*
X682021Y282126D01*
X682121Y282206D01*
X682231Y282266D01*
X682356Y282306D01*
X682481Y282316D01*
G37*
G36*
G01X687205D02*
X687330Y282306D01*
X687455Y282266D01*
X687565Y282206D01*
X687665Y282126D01*
X687745Y282026D01*
X687805Y281916D01*
X687845Y281791D01*
X687855Y281666D01*
Y278236D01*
X687885Y278206D01*
X687985Y278066D01*
X688005Y278026D01*
X688020Y277991D01*
X688040Y277951D01*
X688055Y277911D01*
X688065Y277871D01*
X688080Y277826D01*
X688085Y277786D01*
X688095Y277746D01*
X688100Y277701D01*
Y277661D01*
X688105Y277616D01*
X688100Y277571D01*
Y277531D01*
X688095Y277486D01*
X688085Y277446D01*
X688080Y277406D01*
X688065Y277361D01*
X688055Y277321D01*
X688040Y277281D01*
X688020Y277241D01*
X688005Y277206D01*
X687985Y277166D01*
X687885Y277026D01*
X687855Y276996D01*
Y275866D01*
X687845Y275741D01*
X687805Y275616D01*
X687745Y275506D01*
X687665Y275406D01*
X687565Y275326D01*
X687455Y275266D01*
X687330Y275226D01*
X687205Y275216D01*
X687080Y275226D01*
X686955Y275266D01*
X686845Y275326D01*
X686745Y275406D01*
X686665Y275506D01*
X686605Y275616D01*
X686565Y275741D01*
X686555Y275866D01*
Y276996D01*
X686525Y277026D01*
X686425Y277166D01*
X686405Y277206D01*
X686390Y277241D01*
X686370Y277281D01*
X686355Y277321D01*
X686345Y277361D01*
X686330Y277406D01*
X686325Y277446D01*
X686315Y277486D01*
X686310Y277531D01*
Y277571D01*
X686305Y277616D01*
X686310Y277661D01*
Y277701D01*
X686315Y277746D01*
X686325Y277786D01*
X686330Y277826D01*
X686345Y277871D01*
X686355Y277911D01*
X686370Y277951D01*
X686390Y277991D01*
X686405Y278026D01*
X686425Y278066D01*
X686525Y278206D01*
X686555Y278236D01*
Y281666D01*
X686565Y281791D01*
X686605Y281916D01*
X686665Y282026D01*
X686745Y282126D01*
X686845Y282206D01*
X686955Y282266D01*
X687080Y282306D01*
X687205Y282316D01*
G37*
G36*
G01X691929D02*
X692054Y282306D01*
X692179Y282266D01*
X692289Y282206D01*
X692389Y282126D01*
X692469Y282026D01*
X692529Y281916D01*
X692569Y281791D01*
X692579Y281666D01*
Y278236D01*
X692609Y278206D01*
X692709Y278066D01*
X692729Y278026D01*
X692744Y277991D01*
X692764Y277951D01*
X692779Y277911D01*
X692789Y277871D01*
X692804Y277826D01*
X692809Y277786D01*
X692819Y277746D01*
X692824Y277701D01*
Y277661D01*
X692829Y277616D01*
X692824Y277571D01*
Y277531D01*
X692819Y277486D01*
X692809Y277446D01*
X692804Y277406D01*
X692789Y277361D01*
X692779Y277321D01*
X692764Y277281D01*
X692744Y277241D01*
X692729Y277206D01*
X692709Y277166D01*
X692609Y277026D01*
X692579Y276996D01*
Y275866D01*
X692569Y275741D01*
X692529Y275616D01*
X692469Y275506D01*
X692389Y275406D01*
X692289Y275326D01*
X692179Y275266D01*
X692054Y275226D01*
X691929Y275216D01*
X691804Y275226D01*
X691679Y275266D01*
X691569Y275326D01*
X691469Y275406D01*
X691389Y275506D01*
X691329Y275616D01*
X691289Y275741D01*
X691279Y275866D01*
Y276996D01*
X691249Y277026D01*
X691149Y277166D01*
X691129Y277206D01*
X691114Y277241D01*
X691094Y277281D01*
X691079Y277321D01*
X691069Y277361D01*
X691054Y277406D01*
X691049Y277446D01*
X691039Y277486D01*
X691034Y277531D01*
Y277571D01*
X691029Y277616D01*
X691034Y277661D01*
Y277701D01*
X691039Y277746D01*
X691049Y277786D01*
X691054Y277826D01*
X691069Y277871D01*
X691079Y277911D01*
X691094Y277951D01*
X691114Y277991D01*
X691129Y278026D01*
X691149Y278066D01*
X691249Y278206D01*
X691279Y278236D01*
Y281666D01*
X691289Y281791D01*
X691329Y281916D01*
X691389Y282026D01*
X691469Y282126D01*
X691569Y282206D01*
X691679Y282266D01*
X691804Y282306D01*
X691929Y282316D01*
G37*
G36*
G01X696654D02*
X696779Y282306D01*
X696904Y282266D01*
X697014Y282206D01*
X697114Y282126D01*
X697194Y282026D01*
X697254Y281916D01*
X697294Y281791D01*
X697304Y281666D01*
Y278236D01*
X697334Y278206D01*
X697434Y278066D01*
X697454Y278026D01*
X697469Y277991D01*
X697489Y277951D01*
X697504Y277911D01*
X697514Y277871D01*
X697529Y277826D01*
X697534Y277786D01*
X697544Y277746D01*
X697549Y277701D01*
Y277661D01*
X697554Y277616D01*
X697549Y277571D01*
Y277531D01*
X697544Y277486D01*
X697534Y277446D01*
X697529Y277406D01*
X697514Y277361D01*
X697504Y277321D01*
X697489Y277281D01*
X697469Y277241D01*
X697454Y277206D01*
X697434Y277166D01*
X697334Y277026D01*
X697304Y276996D01*
Y275866D01*
X697294Y275741D01*
X697254Y275616D01*
X697194Y275506D01*
X697114Y275406D01*
X697014Y275326D01*
X696904Y275266D01*
X696779Y275226D01*
X696654Y275216D01*
X696529Y275226D01*
X696404Y275266D01*
X696294Y275326D01*
X696194Y275406D01*
X696114Y275506D01*
X696054Y275616D01*
X696014Y275741D01*
X696004Y275866D01*
Y276996D01*
X695974Y277026D01*
X695874Y277166D01*
X695854Y277206D01*
X695839Y277241D01*
X695819Y277281D01*
X695804Y277321D01*
X695794Y277361D01*
X695779Y277406D01*
X695774Y277446D01*
X695764Y277486D01*
X695759Y277531D01*
Y277571D01*
X695754Y277616D01*
X695759Y277661D01*
Y277701D01*
X695764Y277746D01*
X695774Y277786D01*
X695779Y277826D01*
X695794Y277871D01*
X695804Y277911D01*
X695819Y277951D01*
X695839Y277991D01*
X695854Y278026D01*
X695874Y278066D01*
X695974Y278206D01*
X696004Y278236D01*
Y281666D01*
X696014Y281791D01*
X696054Y281916D01*
X696114Y282026D01*
X696194Y282126D01*
X696294Y282206D01*
X696404Y282266D01*
X696529Y282306D01*
X696654Y282316D01*
G37*
G36*
G01X701378D02*
X701503Y282306D01*
X701628Y282266D01*
X701738Y282206D01*
X701838Y282126D01*
X701918Y282026D01*
X701978Y281916D01*
X702018Y281791D01*
X702028Y281666D01*
Y278236D01*
X702058Y278206D01*
X702158Y278066D01*
X702178Y278026D01*
X702193Y277991D01*
X702213Y277951D01*
X702228Y277911D01*
X702238Y277871D01*
X702253Y277826D01*
X702258Y277786D01*
X702268Y277746D01*
X702273Y277701D01*
Y277661D01*
X702278Y277616D01*
X702273Y277571D01*
Y277531D01*
X702268Y277486D01*
X702258Y277446D01*
X702253Y277406D01*
X702238Y277361D01*
X702228Y277321D01*
X702213Y277281D01*
X702193Y277241D01*
X702178Y277206D01*
X702158Y277166D01*
X702058Y277026D01*
X702028Y276996D01*
Y275866D01*
X702018Y275741D01*
X701978Y275616D01*
X701918Y275506D01*
X701838Y275406D01*
X701738Y275326D01*
X701628Y275266D01*
X701503Y275226D01*
X701378Y275216D01*
X701253Y275226D01*
X701128Y275266D01*
X701018Y275326D01*
X700918Y275406D01*
X700838Y275506D01*
X700778Y275616D01*
X700738Y275741D01*
X700728Y275866D01*
Y276996D01*
X700698Y277026D01*
X700598Y277166D01*
X700578Y277206D01*
X700563Y277241D01*
X700543Y277281D01*
X700528Y277321D01*
X700518Y277361D01*
X700503Y277406D01*
X700498Y277446D01*
X700488Y277486D01*
X700483Y277531D01*
Y277571D01*
X700478Y277616D01*
X700483Y277661D01*
Y277701D01*
X700488Y277746D01*
X700498Y277786D01*
X700503Y277826D01*
X700518Y277871D01*
X700528Y277911D01*
X700543Y277951D01*
X700563Y277991D01*
X700578Y278026D01*
X700598Y278066D01*
X700698Y278206D01*
X700728Y278236D01*
Y281666D01*
X700738Y281791D01*
X700778Y281916D01*
X700838Y282026D01*
X700918Y282126D01*
X701018Y282206D01*
X701128Y282266D01*
X701253Y282306D01*
X701378Y282316D01*
G37*
G36*
G01X706103D02*
X706228Y282306D01*
X706353Y282266D01*
X706463Y282206D01*
X706563Y282126D01*
X706643Y282026D01*
X706703Y281916D01*
X706743Y281791D01*
X706753Y281666D01*
Y278236D01*
X706783Y278206D01*
X706883Y278066D01*
X706903Y278026D01*
X706918Y277991D01*
X706938Y277951D01*
X706953Y277911D01*
X706963Y277871D01*
X706978Y277826D01*
X706983Y277786D01*
X706993Y277746D01*
X706998Y277701D01*
Y277661D01*
X707003Y277616D01*
X706998Y277571D01*
Y277531D01*
X706993Y277486D01*
X706983Y277446D01*
X706978Y277406D01*
X706963Y277361D01*
X706953Y277321D01*
X706938Y277281D01*
X706918Y277241D01*
X706903Y277206D01*
X706883Y277166D01*
X706783Y277026D01*
X706753Y276996D01*
Y275866D01*
X706743Y275741D01*
X706703Y275616D01*
X706643Y275506D01*
X706563Y275406D01*
X706463Y275326D01*
X706353Y275266D01*
X706228Y275226D01*
X706103Y275216D01*
X705978Y275226D01*
X705853Y275266D01*
X705743Y275326D01*
X705643Y275406D01*
X705563Y275506D01*
X705503Y275616D01*
X705463Y275741D01*
X705453Y275866D01*
Y276996D01*
X705423Y277026D01*
X705323Y277166D01*
X705303Y277206D01*
X705288Y277241D01*
X705268Y277281D01*
X705253Y277321D01*
X705243Y277361D01*
X705228Y277406D01*
X705223Y277446D01*
X705213Y277486D01*
X705208Y277531D01*
Y277571D01*
X705203Y277616D01*
X705208Y277661D01*
Y277701D01*
X705213Y277746D01*
X705223Y277786D01*
X705228Y277826D01*
X705243Y277871D01*
X705253Y277911D01*
X705268Y277951D01*
X705288Y277991D01*
X705303Y278026D01*
X705323Y278066D01*
X705423Y278206D01*
X705453Y278236D01*
Y281666D01*
X705463Y281791D01*
X705503Y281916D01*
X705563Y282026D01*
X705643Y282126D01*
X705743Y282206D01*
X705853Y282266D01*
X705978Y282306D01*
X706103Y282316D01*
G37*
G36*
G01X710827D02*
X710952Y282306D01*
X711077Y282266D01*
X711187Y282206D01*
X711287Y282126D01*
X711367Y282026D01*
X711427Y281916D01*
X711467Y281791D01*
X711477Y281666D01*
Y278236D01*
X711507Y278206D01*
X711607Y278066D01*
X711627Y278026D01*
X711642Y277991D01*
X711662Y277951D01*
X711677Y277911D01*
X711687Y277871D01*
X711702Y277826D01*
X711707Y277786D01*
X711717Y277746D01*
X711722Y277701D01*
Y277661D01*
X711727Y277616D01*
X711722Y277571D01*
Y277531D01*
X711717Y277486D01*
X711707Y277446D01*
X711702Y277406D01*
X711687Y277361D01*
X711677Y277321D01*
X711662Y277281D01*
X711642Y277241D01*
X711627Y277206D01*
X711607Y277166D01*
X711507Y277026D01*
X711477Y276996D01*
Y275866D01*
X711467Y275741D01*
X711427Y275616D01*
X711367Y275506D01*
X711287Y275406D01*
X711187Y275326D01*
X711077Y275266D01*
X710952Y275226D01*
X710827Y275216D01*
X710702Y275226D01*
X710577Y275266D01*
X710467Y275326D01*
X710367Y275406D01*
X710287Y275506D01*
X710227Y275616D01*
X710187Y275741D01*
X710177Y275866D01*
Y276996D01*
X710147Y277026D01*
X710047Y277166D01*
X710027Y277206D01*
X710012Y277241D01*
X709992Y277281D01*
X709977Y277321D01*
X709967Y277361D01*
X709952Y277406D01*
X709947Y277446D01*
X709937Y277486D01*
X709932Y277531D01*
Y277571D01*
X709927Y277616D01*
X709932Y277661D01*
Y277701D01*
X709937Y277746D01*
X709947Y277786D01*
X709952Y277826D01*
X709967Y277871D01*
X709977Y277911D01*
X709992Y277951D01*
X710012Y277991D01*
X710027Y278026D01*
X710047Y278066D01*
X710147Y278206D01*
X710177Y278236D01*
Y281666D01*
X710187Y281791D01*
X710227Y281916D01*
X710287Y282026D01*
X710367Y282126D01*
X710467Y282206D01*
X710577Y282266D01*
X710702Y282306D01*
X710827Y282316D01*
G37*
G36*
G01X715551D02*
X715676Y282306D01*
X715801Y282266D01*
X715911Y282206D01*
X716011Y282126D01*
X716091Y282026D01*
X716151Y281916D01*
X716191Y281791D01*
X716201Y281666D01*
Y278236D01*
X716231Y278206D01*
X716331Y278066D01*
X716351Y278026D01*
X716366Y277991D01*
X716386Y277951D01*
X716401Y277911D01*
X716411Y277871D01*
X716426Y277826D01*
X716431Y277786D01*
X716441Y277746D01*
X716446Y277701D01*
Y277661D01*
X716451Y277616D01*
X716446Y277571D01*
Y277531D01*
X716441Y277486D01*
X716431Y277446D01*
X716426Y277406D01*
X716411Y277361D01*
X716401Y277321D01*
X716386Y277281D01*
X716366Y277241D01*
X716351Y277206D01*
X716331Y277166D01*
X716231Y277026D01*
X716201Y276996D01*
Y275866D01*
X716191Y275741D01*
X716151Y275616D01*
X716091Y275506D01*
X716011Y275406D01*
X715911Y275326D01*
X715801Y275266D01*
X715676Y275226D01*
X715551Y275216D01*
X715426Y275226D01*
X715301Y275266D01*
X715191Y275326D01*
X715091Y275406D01*
X715011Y275506D01*
X714951Y275616D01*
X714911Y275741D01*
X714901Y275866D01*
Y276996D01*
X714871Y277026D01*
X714771Y277166D01*
X714751Y277206D01*
X714736Y277241D01*
X714716Y277281D01*
X714701Y277321D01*
X714691Y277361D01*
X714676Y277406D01*
X714671Y277446D01*
X714661Y277486D01*
X714656Y277531D01*
Y277571D01*
X714651Y277616D01*
X714656Y277661D01*
Y277701D01*
X714661Y277746D01*
X714671Y277786D01*
X714676Y277826D01*
X714691Y277871D01*
X714701Y277911D01*
X714716Y277951D01*
X714736Y277991D01*
X714751Y278026D01*
X714771Y278066D01*
X714871Y278206D01*
X714901Y278236D01*
Y281666D01*
X714911Y281791D01*
X714951Y281916D01*
X715011Y282026D01*
X715091Y282126D01*
X715191Y282206D01*
X715301Y282266D01*
X715426Y282306D01*
X715551Y282316D01*
G37*
G36*
G01X720276D02*
X720401Y282306D01*
X720526Y282266D01*
X720636Y282206D01*
X720736Y282126D01*
X720816Y282026D01*
X720876Y281916D01*
X720916Y281791D01*
X720926Y281666D01*
Y278236D01*
X720956Y278206D01*
X721056Y278066D01*
X721076Y278026D01*
X721091Y277991D01*
X721111Y277951D01*
X721126Y277911D01*
X721136Y277871D01*
X721151Y277826D01*
X721156Y277786D01*
X721166Y277746D01*
X721171Y277701D01*
Y277661D01*
X721176Y277616D01*
X721171Y277571D01*
Y277531D01*
X721166Y277486D01*
X721156Y277446D01*
X721151Y277406D01*
X721136Y277361D01*
X721126Y277321D01*
X721111Y277281D01*
X721091Y277241D01*
X721076Y277206D01*
X721056Y277166D01*
X720956Y277026D01*
X720926Y276996D01*
Y275866D01*
X720916Y275741D01*
X720876Y275616D01*
X720816Y275506D01*
X720736Y275406D01*
X720636Y275326D01*
X720526Y275266D01*
X720401Y275226D01*
X720276Y275216D01*
X720151Y275226D01*
X720026Y275266D01*
X719916Y275326D01*
X719816Y275406D01*
X719736Y275506D01*
X719676Y275616D01*
X719636Y275741D01*
X719626Y275866D01*
Y276996D01*
X719596Y277026D01*
X719496Y277166D01*
X719476Y277206D01*
X719461Y277241D01*
X719441Y277281D01*
X719426Y277321D01*
X719416Y277361D01*
X719401Y277406D01*
X719396Y277446D01*
X719386Y277486D01*
X719381Y277531D01*
Y277571D01*
X719376Y277616D01*
X719381Y277661D01*
Y277701D01*
X719386Y277746D01*
X719396Y277786D01*
X719401Y277826D01*
X719416Y277871D01*
X719426Y277911D01*
X719441Y277951D01*
X719461Y277991D01*
X719476Y278026D01*
X719496Y278066D01*
X719596Y278206D01*
X719626Y278236D01*
Y281666D01*
X719636Y281791D01*
X719676Y281916D01*
X719736Y282026D01*
X719816Y282126D01*
X719916Y282206D01*
X720026Y282266D01*
X720151Y282306D01*
X720276Y282316D01*
G37*
G36*
G01X725000D02*
X725125Y282306D01*
X725250Y282266D01*
X725360Y282206D01*
X725460Y282126D01*
X725540Y282026D01*
X725600Y281916D01*
X725640Y281791D01*
X725650Y281666D01*
Y278236D01*
X725680Y278206D01*
X725780Y278066D01*
X725800Y278026D01*
X725815Y277991D01*
X725835Y277951D01*
X725850Y277911D01*
X725860Y277871D01*
X725875Y277826D01*
X725880Y277786D01*
X725890Y277746D01*
X725895Y277701D01*
Y277661D01*
X725900Y277616D01*
X725895Y277571D01*
Y277531D01*
X725890Y277486D01*
X725880Y277446D01*
X725875Y277406D01*
X725860Y277361D01*
X725850Y277321D01*
X725835Y277281D01*
X725815Y277241D01*
X725800Y277206D01*
X725780Y277166D01*
X725680Y277026D01*
X725650Y276996D01*
Y275866D01*
X725640Y275741D01*
X725600Y275616D01*
X725540Y275506D01*
X725460Y275406D01*
X725360Y275326D01*
X725250Y275266D01*
X725125Y275226D01*
X725000Y275216D01*
X724875Y275226D01*
X724750Y275266D01*
X724640Y275326D01*
X724540Y275406D01*
X724460Y275506D01*
X724400Y275616D01*
X724360Y275741D01*
X724350Y275866D01*
Y276996D01*
X724320Y277026D01*
X724220Y277166D01*
X724200Y277206D01*
X724185Y277241D01*
X724165Y277281D01*
X724150Y277321D01*
X724140Y277361D01*
X724125Y277406D01*
X724120Y277446D01*
X724110Y277486D01*
X724105Y277531D01*
Y277571D01*
X724100Y277616D01*
X724105Y277661D01*
Y277701D01*
X724110Y277746D01*
X724120Y277786D01*
X724125Y277826D01*
X724140Y277871D01*
X724150Y277911D01*
X724165Y277951D01*
X724185Y277991D01*
X724200Y278026D01*
X724220Y278066D01*
X724320Y278206D01*
X724350Y278236D01*
Y281666D01*
X724360Y281791D01*
X724400Y281916D01*
X724460Y282026D01*
X724540Y282126D01*
X724640Y282206D01*
X724750Y282266D01*
X724875Y282306D01*
X725000Y282316D01*
G37*
G36*
G01X729725D02*
X729850Y282306D01*
X729975Y282266D01*
X730085Y282206D01*
X730185Y282126D01*
X730265Y282026D01*
X730325Y281916D01*
X730365Y281791D01*
X730375Y281666D01*
Y278236D01*
X730405Y278206D01*
X730505Y278066D01*
X730525Y278026D01*
X730540Y277991D01*
X730560Y277951D01*
X730575Y277911D01*
X730585Y277871D01*
X730600Y277826D01*
X730605Y277786D01*
X730615Y277746D01*
X730620Y277701D01*
Y277661D01*
X730625Y277616D01*
X730620Y277571D01*
Y277531D01*
X730615Y277486D01*
X730605Y277446D01*
X730600Y277406D01*
X730585Y277361D01*
X730575Y277321D01*
X730560Y277281D01*
X730540Y277241D01*
X730525Y277206D01*
X730505Y277166D01*
X730405Y277026D01*
X730375Y276996D01*
Y275866D01*
X730365Y275741D01*
X730325Y275616D01*
X730265Y275506D01*
X730185Y275406D01*
X730085Y275326D01*
X729975Y275266D01*
X729850Y275226D01*
X729725Y275216D01*
X729600Y275226D01*
X729475Y275266D01*
X729365Y275326D01*
X729265Y275406D01*
X729185Y275506D01*
X729125Y275616D01*
X729085Y275741D01*
X729075Y275866D01*
Y276996D01*
X729045Y277026D01*
X728945Y277166D01*
X728925Y277206D01*
X728910Y277241D01*
X728890Y277281D01*
X728875Y277321D01*
X728865Y277361D01*
X728850Y277406D01*
X728845Y277446D01*
X728835Y277486D01*
X728830Y277531D01*
Y277571D01*
X728825Y277616D01*
X728830Y277661D01*
Y277701D01*
X728835Y277746D01*
X728845Y277786D01*
X728850Y277826D01*
X728865Y277871D01*
X728875Y277911D01*
X728890Y277951D01*
X728910Y277991D01*
X728925Y278026D01*
X728945Y278066D01*
X729045Y278206D01*
X729075Y278236D01*
Y281666D01*
X729085Y281791D01*
X729125Y281916D01*
X729185Y282026D01*
X729265Y282126D01*
X729365Y282206D01*
X729475Y282266D01*
X729600Y282306D01*
X729725Y282316D01*
G37*
G36*
G01X734449D02*
X734574Y282306D01*
X734699Y282266D01*
X734809Y282206D01*
X734909Y282126D01*
X734989Y282026D01*
X735049Y281916D01*
X735089Y281791D01*
X735099Y281666D01*
Y278236D01*
X735129Y278206D01*
X735229Y278066D01*
X735249Y278026D01*
X735264Y277991D01*
X735284Y277951D01*
X735299Y277911D01*
X735309Y277871D01*
X735324Y277826D01*
X735329Y277786D01*
X735339Y277746D01*
X735344Y277701D01*
Y277661D01*
X735349Y277616D01*
X735344Y277571D01*
Y277531D01*
X735339Y277486D01*
X735329Y277446D01*
X735324Y277406D01*
X735309Y277361D01*
X735299Y277321D01*
X735284Y277281D01*
X735264Y277241D01*
X735249Y277206D01*
X735229Y277166D01*
X735129Y277026D01*
X735099Y276996D01*
Y275866D01*
X735089Y275741D01*
X735049Y275616D01*
X734989Y275506D01*
X734909Y275406D01*
X734809Y275326D01*
X734699Y275266D01*
X734574Y275226D01*
X734449Y275216D01*
X734324Y275226D01*
X734199Y275266D01*
X734089Y275326D01*
X733989Y275406D01*
X733909Y275506D01*
X733849Y275616D01*
X733809Y275741D01*
X733799Y275866D01*
Y276996D01*
X733769Y277026D01*
X733669Y277166D01*
X733649Y277206D01*
X733634Y277241D01*
X733614Y277281D01*
X733599Y277321D01*
X733589Y277361D01*
X733574Y277406D01*
X733569Y277446D01*
X733559Y277486D01*
X733554Y277531D01*
Y277571D01*
X733549Y277616D01*
X733554Y277661D01*
Y277701D01*
X733559Y277746D01*
X733569Y277786D01*
X733574Y277826D01*
X733589Y277871D01*
X733599Y277911D01*
X733614Y277951D01*
X733634Y277991D01*
X733649Y278026D01*
X733669Y278066D01*
X733769Y278206D01*
X733799Y278236D01*
Y281666D01*
X733809Y281791D01*
X733849Y281916D01*
X733909Y282026D01*
X733989Y282126D01*
X734089Y282206D01*
X734199Y282266D01*
X734324Y282306D01*
X734449Y282316D01*
G37*
G36*
G01X739173D02*
X739298Y282306D01*
X739423Y282266D01*
X739533Y282206D01*
X739633Y282126D01*
X739713Y282026D01*
X739773Y281916D01*
X739813Y281791D01*
X739823Y281666D01*
Y278236D01*
X739853Y278206D01*
X739953Y278066D01*
X739973Y278026D01*
X739988Y277991D01*
X740008Y277951D01*
X740023Y277911D01*
X740033Y277871D01*
X740048Y277826D01*
X740053Y277786D01*
X740063Y277746D01*
X740068Y277701D01*
Y277661D01*
X740073Y277616D01*
X740068Y277571D01*
Y277531D01*
X740063Y277486D01*
X740053Y277446D01*
X740048Y277406D01*
X740033Y277361D01*
X740023Y277321D01*
X740008Y277281D01*
X739988Y277241D01*
X739973Y277206D01*
X739953Y277166D01*
X739853Y277026D01*
X739823Y276996D01*
Y275866D01*
X739813Y275741D01*
X739773Y275616D01*
X739713Y275506D01*
X739633Y275406D01*
X739533Y275326D01*
X739423Y275266D01*
X739298Y275226D01*
X739173Y275216D01*
X739048Y275226D01*
X738923Y275266D01*
X738813Y275326D01*
X738713Y275406D01*
X738633Y275506D01*
X738573Y275616D01*
X738533Y275741D01*
X738523Y275866D01*
Y276996D01*
X738493Y277026D01*
X738393Y277166D01*
X738373Y277206D01*
X738358Y277241D01*
X738338Y277281D01*
X738323Y277321D01*
X738313Y277361D01*
X738298Y277406D01*
X738293Y277446D01*
X738283Y277486D01*
X738278Y277531D01*
Y277571D01*
X738273Y277616D01*
X738278Y277661D01*
Y277701D01*
X738283Y277746D01*
X738293Y277786D01*
X738298Y277826D01*
X738313Y277871D01*
X738323Y277911D01*
X738338Y277951D01*
X738358Y277991D01*
X738373Y278026D01*
X738393Y278066D01*
X738493Y278206D01*
X738523Y278236D01*
Y281666D01*
X738533Y281791D01*
X738573Y281916D01*
X738633Y282026D01*
X738713Y282126D01*
X738813Y282206D01*
X738923Y282266D01*
X739048Y282306D01*
X739173Y282316D01*
G37*
G36*
G01X743898D02*
X744023Y282306D01*
X744148Y282266D01*
X744258Y282206D01*
X744358Y282126D01*
X744438Y282026D01*
X744498Y281916D01*
X744538Y281791D01*
X744548Y281666D01*
Y278236D01*
X744578Y278206D01*
X744678Y278066D01*
X744698Y278026D01*
X744713Y277991D01*
X744733Y277951D01*
X744748Y277911D01*
X744758Y277871D01*
X744773Y277826D01*
X744778Y277786D01*
X744788Y277746D01*
X744793Y277701D01*
Y277661D01*
X744798Y277616D01*
X744793Y277571D01*
Y277531D01*
X744788Y277486D01*
X744778Y277446D01*
X744773Y277406D01*
X744758Y277361D01*
X744748Y277321D01*
X744733Y277281D01*
X744713Y277241D01*
X744698Y277206D01*
X744678Y277166D01*
X744578Y277026D01*
X744548Y276996D01*
Y275866D01*
X744538Y275741D01*
X744498Y275616D01*
X744438Y275506D01*
X744358Y275406D01*
X744258Y275326D01*
X744148Y275266D01*
X744023Y275226D01*
X743898Y275216D01*
X743773Y275226D01*
X743648Y275266D01*
X743538Y275326D01*
X743438Y275406D01*
X743358Y275506D01*
X743298Y275616D01*
X743258Y275741D01*
X743248Y275866D01*
Y276996D01*
X743218Y277026D01*
X743118Y277166D01*
X743098Y277206D01*
X743083Y277241D01*
X743063Y277281D01*
X743048Y277321D01*
X743038Y277361D01*
X743023Y277406D01*
X743018Y277446D01*
X743008Y277486D01*
X743003Y277531D01*
Y277571D01*
X742998Y277616D01*
X743003Y277661D01*
Y277701D01*
X743008Y277746D01*
X743018Y277786D01*
X743023Y277826D01*
X743038Y277871D01*
X743048Y277911D01*
X743063Y277951D01*
X743083Y277991D01*
X743098Y278026D01*
X743118Y278066D01*
X743218Y278206D01*
X743248Y278236D01*
Y281666D01*
X743258Y281791D01*
X743298Y281916D01*
X743358Y282026D01*
X743438Y282126D01*
X743538Y282206D01*
X743648Y282266D01*
X743773Y282306D01*
X743898Y282316D01*
G37*
G36*
G01X748622D02*
X748747Y282306D01*
X748872Y282266D01*
X748982Y282206D01*
X749082Y282126D01*
X749162Y282026D01*
X749222Y281916D01*
X749262Y281791D01*
X749272Y281666D01*
Y278236D01*
X749302Y278206D01*
X749402Y278066D01*
X749422Y278026D01*
X749437Y277991D01*
X749457Y277951D01*
X749472Y277911D01*
X749482Y277871D01*
X749497Y277826D01*
X749502Y277786D01*
X749512Y277746D01*
X749517Y277701D01*
Y277661D01*
X749522Y277616D01*
X749517Y277571D01*
Y277531D01*
X749512Y277486D01*
X749502Y277446D01*
X749497Y277406D01*
X749482Y277361D01*
X749472Y277321D01*
X749457Y277281D01*
X749437Y277241D01*
X749422Y277206D01*
X749402Y277166D01*
X749302Y277026D01*
X749272Y276996D01*
Y275866D01*
X749262Y275741D01*
X749222Y275616D01*
X749162Y275506D01*
X749082Y275406D01*
X748982Y275326D01*
X748872Y275266D01*
X748747Y275226D01*
X748622Y275216D01*
X748497Y275226D01*
X748372Y275266D01*
X748262Y275326D01*
X748162Y275406D01*
X748082Y275506D01*
X748022Y275616D01*
X747982Y275741D01*
X747972Y275866D01*
Y276996D01*
X747942Y277026D01*
X747842Y277166D01*
X747822Y277206D01*
X747807Y277241D01*
X747787Y277281D01*
X747772Y277321D01*
X747762Y277361D01*
X747747Y277406D01*
X747742Y277446D01*
X747732Y277486D01*
X747727Y277531D01*
Y277571D01*
X747722Y277616D01*
X747727Y277661D01*
Y277701D01*
X747732Y277746D01*
X747742Y277786D01*
X747747Y277826D01*
X747762Y277871D01*
X747772Y277911D01*
X747787Y277951D01*
X747807Y277991D01*
X747822Y278026D01*
X747842Y278066D01*
X747942Y278206D01*
X747972Y278236D01*
Y281666D01*
X747982Y281791D01*
X748022Y281916D01*
X748082Y282026D01*
X748162Y282126D01*
X748262Y282206D01*
X748372Y282266D01*
X748497Y282306D01*
X748622Y282316D01*
G37*
G54D58*
X155720Y228500D03*
G54D77*
X281000Y152654D03*
Y162346D03*
G54D86*
X500787Y70042D03*
X494882Y215354D03*
X759055Y70042D03*
X753150Y215354D03*
G54D59*
X150989Y221000D03*
Y226000D03*
Y231000D03*
Y236000D03*
G54D95*
X520200Y105490D03*
Y103520D03*
Y101550D03*
Y121235D03*
Y119270D03*
Y117300D03*
Y115330D03*
Y113360D03*
Y111395D03*
Y109425D03*
Y107455D03*
Y135015D03*
Y133045D03*
Y131080D03*
Y129110D03*
Y127140D03*
Y125175D03*
Y123205D03*
Y150765D03*
Y148795D03*
Y146825D03*
Y144860D03*
Y142890D03*
Y140920D03*
Y138955D03*
Y136985D03*
Y166510D03*
Y164545D03*
Y162575D03*
Y160605D03*
Y158640D03*
Y156670D03*
Y154700D03*
Y152730D03*
Y170450D03*
Y168480D03*
X603800Y101550D03*
Y103520D03*
Y105490D03*
Y107455D03*
Y109425D03*
Y111395D03*
Y113360D03*
Y115330D03*
Y117300D03*
Y119270D03*
Y121235D03*
Y123205D03*
Y125175D03*
Y127140D03*
Y129110D03*
Y131080D03*
Y133045D03*
Y135015D03*
Y136985D03*
Y138955D03*
Y140920D03*
Y142890D03*
Y144860D03*
Y146825D03*
Y148795D03*
Y150765D03*
Y152730D03*
Y154700D03*
Y156670D03*
Y158640D03*
Y160605D03*
Y162575D03*
Y164545D03*
Y166510D03*
Y168480D03*
Y170450D03*
G54D68*
X184671Y234000D03*
X215329D03*
G54D69*
X194603Y105871D03*
Y120871D03*
Y115871D03*
Y110871D03*
X220893Y105871D03*
Y120871D03*
Y115871D03*
Y110871D03*
G54D96*
X527550Y94200D03*
X529520D03*
X531490D03*
X533455D03*
X535425D03*
X537395D03*
X539360D03*
X541330D03*
Y177800D03*
X539360D03*
X537395D03*
X535425D03*
X533455D03*
X531490D03*
X529520D03*
X527550D03*
X543300Y94200D03*
X545270D03*
X547235D03*
X549205D03*
X551175D03*
X553140D03*
X555110D03*
Y177800D03*
X553140D03*
X551175D03*
X549205D03*
X547235D03*
X545270D03*
X543300D03*
X557080Y94200D03*
X559045D03*
X561015D03*
X562985D03*
X564955D03*
X566920D03*
X568890D03*
X570860D03*
Y177800D03*
X568890D03*
X566920D03*
X564955D03*
X562985D03*
X561015D03*
X559045D03*
X557080D03*
X572825Y94200D03*
X574795D03*
X576765D03*
X578730D03*
X580700D03*
X582670D03*
X584640D03*
X586605D03*
Y177800D03*
X584640D03*
X582670D03*
X580700D03*
X578730D03*
X576765D03*
X574795D03*
X572825D03*
X588575Y94200D03*
X590545D03*
X592510D03*
X594480D03*
X596450D03*
Y177800D03*
X594480D03*
X592510D03*
X590545D03*
X588575D03*
G54D78*
X273791Y210500D03*
X288291Y53000D03*
X282209Y214240D03*
Y206760D03*
X296709Y56740D03*
Y49260D03*
X615791Y187000D03*
X624209Y183260D03*
Y190740D03*
G36*
G01X507677Y3080D02*
X507552Y3090D01*
X507427Y3130D01*
X507317Y3190D01*
X507217Y3270D01*
X507137Y3370D01*
X507077Y3480D01*
X507037Y3605D01*
X507027Y3730D01*
Y6160D01*
X506997Y6190D01*
X506897Y6330D01*
X506877Y6370D01*
X506862Y6405D01*
X506842Y6445D01*
X506827Y6485D01*
X506817Y6525D01*
X506802Y6570D01*
X506797Y6610D01*
X506787Y6650D01*
X506782Y6695D01*
Y6735D01*
X506777Y6780D01*
X506782Y6825D01*
Y6865D01*
X506787Y6910D01*
X506797Y6950D01*
X506802Y6990D01*
X506817Y7035D01*
X506827Y7075D01*
X506842Y7115D01*
X506862Y7155D01*
X506877Y7190D01*
X506897Y7230D01*
X506997Y7370D01*
X507027Y7400D01*
Y9530D01*
X507037Y9655D01*
X507077Y9780D01*
X507137Y9890D01*
X507217Y9990D01*
X507317Y10070D01*
X507427Y10130D01*
X507552Y10170D01*
X507677Y10180D01*
X507802Y10170D01*
X507927Y10130D01*
X508037Y10070D01*
X508137Y9990D01*
X508217Y9890D01*
X508277Y9780D01*
X508317Y9655D01*
X508327Y9530D01*
Y7405D01*
X508357Y7375D01*
X508382Y7340D01*
X508412Y7305D01*
X508432Y7270D01*
X508457Y7235D01*
X508497Y7155D01*
X508542Y7035D01*
X508552Y6995D01*
X508562Y6950D01*
X508567Y6910D01*
X508577Y6865D01*
Y6695D01*
X508567Y6650D01*
X508562Y6610D01*
X508552Y6565D01*
X508542Y6525D01*
X508497Y6405D01*
X508457Y6325D01*
X508432Y6290D01*
X508412Y6255D01*
X508382Y6220D01*
X508357Y6185D01*
X508327Y6155D01*
Y3730D01*
X508317Y3605D01*
X508277Y3480D01*
X508217Y3370D01*
X508137Y3270D01*
X508037Y3190D01*
X507927Y3130D01*
X507802Y3090D01*
X507677Y3080D01*
G37*
G36*
G01X521850D02*
X521725Y3090D01*
X521600Y3130D01*
X521490Y3190D01*
X521390Y3270D01*
X521310Y3370D01*
X521250Y3480D01*
X521210Y3605D01*
X521200Y3730D01*
Y6160D01*
X521170Y6190D01*
X521070Y6330D01*
X521050Y6370D01*
X521035Y6405D01*
X521015Y6445D01*
X521000Y6485D01*
X520990Y6525D01*
X520975Y6570D01*
X520970Y6610D01*
X520960Y6650D01*
X520955Y6695D01*
Y6735D01*
X520950Y6780D01*
X520955Y6825D01*
Y6865D01*
X520960Y6910D01*
X520970Y6950D01*
X520975Y6990D01*
X520990Y7035D01*
X521000Y7075D01*
X521015Y7115D01*
X521035Y7155D01*
X521050Y7190D01*
X521070Y7230D01*
X521170Y7370D01*
X521200Y7400D01*
Y9530D01*
X521210Y9655D01*
X521250Y9780D01*
X521310Y9890D01*
X521390Y9990D01*
X521490Y10070D01*
X521600Y10130D01*
X521725Y10170D01*
X521850Y10180D01*
X521975Y10170D01*
X522100Y10130D01*
X522210Y10070D01*
X522310Y9990D01*
X522390Y9890D01*
X522450Y9780D01*
X522490Y9655D01*
X522500Y9530D01*
Y7405D01*
X522530Y7375D01*
X522555Y7340D01*
X522585Y7305D01*
X522605Y7270D01*
X522630Y7235D01*
X522670Y7155D01*
X522715Y7035D01*
X522725Y6995D01*
X522735Y6950D01*
X522740Y6910D01*
X522750Y6865D01*
Y6695D01*
X522740Y6650D01*
X522735Y6610D01*
X522725Y6565D01*
X522715Y6525D01*
X522670Y6405D01*
X522630Y6325D01*
X522605Y6290D01*
X522585Y6255D01*
X522555Y6220D01*
X522530Y6185D01*
X522500Y6155D01*
Y3730D01*
X522490Y3605D01*
X522450Y3480D01*
X522390Y3370D01*
X522310Y3270D01*
X522210Y3190D01*
X522100Y3130D01*
X521975Y3090D01*
X521850Y3080D01*
G37*
G36*
G01X517126D02*
X517001Y3090D01*
X516876Y3130D01*
X516766Y3190D01*
X516666Y3270D01*
X516586Y3370D01*
X516526Y3480D01*
X516486Y3605D01*
X516476Y3730D01*
Y6160D01*
X516446Y6190D01*
X516346Y6330D01*
X516326Y6370D01*
X516311Y6405D01*
X516291Y6445D01*
X516276Y6485D01*
X516266Y6525D01*
X516251Y6570D01*
X516246Y6610D01*
X516236Y6650D01*
X516231Y6695D01*
Y6735D01*
X516226Y6780D01*
X516231Y6825D01*
Y6865D01*
X516236Y6910D01*
X516246Y6950D01*
X516251Y6990D01*
X516266Y7035D01*
X516276Y7075D01*
X516291Y7115D01*
X516311Y7155D01*
X516326Y7190D01*
X516346Y7230D01*
X516446Y7370D01*
X516476Y7400D01*
Y9530D01*
X516486Y9655D01*
X516526Y9780D01*
X516586Y9890D01*
X516666Y9990D01*
X516766Y10070D01*
X516876Y10130D01*
X517001Y10170D01*
X517126Y10180D01*
X517251Y10170D01*
X517376Y10130D01*
X517486Y10070D01*
X517586Y9990D01*
X517666Y9890D01*
X517726Y9780D01*
X517766Y9655D01*
X517776Y9530D01*
Y7405D01*
X517806Y7375D01*
X517831Y7340D01*
X517861Y7305D01*
X517881Y7270D01*
X517906Y7235D01*
X517946Y7155D01*
X517991Y7035D01*
X518001Y6995D01*
X518011Y6950D01*
X518016Y6910D01*
X518026Y6865D01*
Y6695D01*
X518016Y6650D01*
X518011Y6610D01*
X518001Y6565D01*
X517991Y6525D01*
X517946Y6405D01*
X517906Y6325D01*
X517881Y6290D01*
X517861Y6255D01*
X517831Y6220D01*
X517806Y6185D01*
X517776Y6155D01*
Y3730D01*
X517766Y3605D01*
X517726Y3480D01*
X517666Y3370D01*
X517586Y3270D01*
X517486Y3190D01*
X517376Y3130D01*
X517251Y3090D01*
X517126Y3080D01*
G37*
G36*
G01X512401D02*
X512276Y3090D01*
X512151Y3130D01*
X512041Y3190D01*
X511941Y3270D01*
X511861Y3370D01*
X511801Y3480D01*
X511761Y3605D01*
X511751Y3730D01*
Y6160D01*
X511721Y6190D01*
X511621Y6330D01*
X511601Y6370D01*
X511586Y6405D01*
X511566Y6445D01*
X511551Y6485D01*
X511541Y6525D01*
X511526Y6570D01*
X511521Y6610D01*
X511511Y6650D01*
X511506Y6695D01*
Y6735D01*
X511501Y6780D01*
X511506Y6825D01*
Y6865D01*
X511511Y6910D01*
X511521Y6950D01*
X511526Y6990D01*
X511541Y7035D01*
X511551Y7075D01*
X511566Y7115D01*
X511586Y7155D01*
X511601Y7190D01*
X511621Y7230D01*
X511721Y7370D01*
X511751Y7400D01*
Y9530D01*
X511761Y9655D01*
X511801Y9780D01*
X511861Y9890D01*
X511941Y9990D01*
X512041Y10070D01*
X512151Y10130D01*
X512276Y10170D01*
X512401Y10180D01*
X512526Y10170D01*
X512651Y10130D01*
X512761Y10070D01*
X512861Y9990D01*
X512941Y9890D01*
X513001Y9780D01*
X513041Y9655D01*
X513051Y9530D01*
Y7405D01*
X513081Y7375D01*
X513106Y7340D01*
X513136Y7305D01*
X513156Y7270D01*
X513181Y7235D01*
X513221Y7155D01*
X513266Y7035D01*
X513276Y6995D01*
X513286Y6950D01*
X513291Y6910D01*
X513301Y6865D01*
Y6695D01*
X513291Y6650D01*
X513286Y6610D01*
X513276Y6565D01*
X513266Y6525D01*
X513221Y6405D01*
X513181Y6325D01*
X513156Y6290D01*
X513136Y6255D01*
X513106Y6220D01*
X513081Y6185D01*
X513051Y6155D01*
Y3730D01*
X513041Y3605D01*
X513001Y3480D01*
X512941Y3370D01*
X512861Y3270D01*
X512761Y3190D01*
X512651Y3130D01*
X512526Y3090D01*
X512401Y3080D01*
G37*
G36*
G01X540748D02*
X540623Y3090D01*
X540498Y3130D01*
X540388Y3190D01*
X540288Y3270D01*
X540208Y3370D01*
X540148Y3480D01*
X540108Y3605D01*
X540098Y3730D01*
Y6160D01*
X540068Y6190D01*
X539968Y6330D01*
X539948Y6370D01*
X539933Y6405D01*
X539913Y6445D01*
X539898Y6485D01*
X539888Y6525D01*
X539873Y6570D01*
X539868Y6610D01*
X539858Y6650D01*
X539853Y6695D01*
Y6735D01*
X539848Y6780D01*
X539853Y6825D01*
Y6865D01*
X539858Y6910D01*
X539868Y6950D01*
X539873Y6990D01*
X539888Y7035D01*
X539898Y7075D01*
X539913Y7115D01*
X539933Y7155D01*
X539948Y7190D01*
X539968Y7230D01*
X540068Y7370D01*
X540098Y7400D01*
Y9530D01*
X540108Y9655D01*
X540148Y9780D01*
X540208Y9890D01*
X540288Y9990D01*
X540388Y10070D01*
X540498Y10130D01*
X540623Y10170D01*
X540748Y10180D01*
X540873Y10170D01*
X540998Y10130D01*
X541108Y10070D01*
X541208Y9990D01*
X541288Y9890D01*
X541348Y9780D01*
X541388Y9655D01*
X541398Y9530D01*
Y7405D01*
X541428Y7375D01*
X541453Y7340D01*
X541483Y7305D01*
X541503Y7270D01*
X541528Y7235D01*
X541568Y7155D01*
X541613Y7035D01*
X541623Y6995D01*
X541633Y6950D01*
X541638Y6910D01*
X541648Y6865D01*
Y6695D01*
X541638Y6650D01*
X541633Y6610D01*
X541623Y6565D01*
X541613Y6525D01*
X541568Y6405D01*
X541528Y6325D01*
X541503Y6290D01*
X541483Y6255D01*
X541453Y6220D01*
X541428Y6185D01*
X541398Y6155D01*
Y3730D01*
X541388Y3605D01*
X541348Y3480D01*
X541288Y3370D01*
X541208Y3270D01*
X541108Y3190D01*
X540998Y3130D01*
X540873Y3090D01*
X540748Y3080D01*
G37*
G36*
G01X536023D02*
X535898Y3090D01*
X535773Y3130D01*
X535663Y3190D01*
X535563Y3270D01*
X535483Y3370D01*
X535423Y3480D01*
X535383Y3605D01*
X535373Y3730D01*
Y6160D01*
X535343Y6190D01*
X535243Y6330D01*
X535223Y6370D01*
X535208Y6405D01*
X535188Y6445D01*
X535173Y6485D01*
X535163Y6525D01*
X535148Y6570D01*
X535143Y6610D01*
X535133Y6650D01*
X535128Y6695D01*
Y6735D01*
X535123Y6780D01*
X535128Y6825D01*
Y6865D01*
X535133Y6910D01*
X535143Y6950D01*
X535148Y6990D01*
X535163Y7035D01*
X535173Y7075D01*
X535188Y7115D01*
X535208Y7155D01*
X535223Y7190D01*
X535243Y7230D01*
X535343Y7370D01*
X535373Y7400D01*
Y9530D01*
X535383Y9655D01*
X535423Y9780D01*
X535483Y9890D01*
X535563Y9990D01*
X535663Y10070D01*
X535773Y10130D01*
X535898Y10170D01*
X536023Y10180D01*
X536148Y10170D01*
X536273Y10130D01*
X536383Y10070D01*
X536483Y9990D01*
X536563Y9890D01*
X536623Y9780D01*
X536663Y9655D01*
X536673Y9530D01*
Y7405D01*
X536703Y7375D01*
X536728Y7340D01*
X536758Y7305D01*
X536778Y7270D01*
X536803Y7235D01*
X536843Y7155D01*
X536888Y7035D01*
X536898Y6995D01*
X536908Y6950D01*
X536913Y6910D01*
X536923Y6865D01*
Y6695D01*
X536913Y6650D01*
X536908Y6610D01*
X536898Y6565D01*
X536888Y6525D01*
X536843Y6405D01*
X536803Y6325D01*
X536778Y6290D01*
X536758Y6255D01*
X536728Y6220D01*
X536703Y6185D01*
X536673Y6155D01*
Y3730D01*
X536663Y3605D01*
X536623Y3480D01*
X536563Y3370D01*
X536483Y3270D01*
X536383Y3190D01*
X536273Y3130D01*
X536148Y3090D01*
X536023Y3080D01*
G37*
G36*
G01X531299D02*
X531174Y3090D01*
X531049Y3130D01*
X530939Y3190D01*
X530839Y3270D01*
X530759Y3370D01*
X530699Y3480D01*
X530659Y3605D01*
X530649Y3730D01*
Y6160D01*
X530619Y6190D01*
X530519Y6330D01*
X530499Y6370D01*
X530484Y6405D01*
X530464Y6445D01*
X530449Y6485D01*
X530439Y6525D01*
X530424Y6570D01*
X530419Y6610D01*
X530409Y6650D01*
X530404Y6695D01*
Y6735D01*
X530399Y6780D01*
X530404Y6825D01*
Y6865D01*
X530409Y6910D01*
X530419Y6950D01*
X530424Y6990D01*
X530439Y7035D01*
X530449Y7075D01*
X530464Y7115D01*
X530484Y7155D01*
X530499Y7190D01*
X530519Y7230D01*
X530619Y7370D01*
X530649Y7400D01*
Y9530D01*
X530659Y9655D01*
X530699Y9780D01*
X530759Y9890D01*
X530839Y9990D01*
X530939Y10070D01*
X531049Y10130D01*
X531174Y10170D01*
X531299Y10180D01*
X531424Y10170D01*
X531549Y10130D01*
X531659Y10070D01*
X531759Y9990D01*
X531839Y9890D01*
X531899Y9780D01*
X531939Y9655D01*
X531949Y9530D01*
Y7405D01*
X531979Y7375D01*
X532004Y7340D01*
X532034Y7305D01*
X532054Y7270D01*
X532079Y7235D01*
X532119Y7155D01*
X532164Y7035D01*
X532174Y6995D01*
X532184Y6950D01*
X532189Y6910D01*
X532199Y6865D01*
Y6695D01*
X532189Y6650D01*
X532184Y6610D01*
X532174Y6565D01*
X532164Y6525D01*
X532119Y6405D01*
X532079Y6325D01*
X532054Y6290D01*
X532034Y6255D01*
X532004Y6220D01*
X531979Y6185D01*
X531949Y6155D01*
Y3730D01*
X531939Y3605D01*
X531899Y3480D01*
X531839Y3370D01*
X531759Y3270D01*
X531659Y3190D01*
X531549Y3130D01*
X531424Y3090D01*
X531299Y3080D01*
G37*
G36*
G01X526575D02*
X526450Y3090D01*
X526325Y3130D01*
X526215Y3190D01*
X526115Y3270D01*
X526035Y3370D01*
X525975Y3480D01*
X525935Y3605D01*
X525925Y3730D01*
Y6160D01*
X525895Y6190D01*
X525795Y6330D01*
X525775Y6370D01*
X525760Y6405D01*
X525740Y6445D01*
X525725Y6485D01*
X525715Y6525D01*
X525700Y6570D01*
X525695Y6610D01*
X525685Y6650D01*
X525680Y6695D01*
Y6735D01*
X525675Y6780D01*
X525680Y6825D01*
Y6865D01*
X525685Y6910D01*
X525695Y6950D01*
X525700Y6990D01*
X525715Y7035D01*
X525725Y7075D01*
X525740Y7115D01*
X525760Y7155D01*
X525775Y7190D01*
X525795Y7230D01*
X525895Y7370D01*
X525925Y7400D01*
Y9530D01*
X525935Y9655D01*
X525975Y9780D01*
X526035Y9890D01*
X526115Y9990D01*
X526215Y10070D01*
X526325Y10130D01*
X526450Y10170D01*
X526575Y10180D01*
X526700Y10170D01*
X526825Y10130D01*
X526935Y10070D01*
X527035Y9990D01*
X527115Y9890D01*
X527175Y9780D01*
X527215Y9655D01*
X527225Y9530D01*
Y7405D01*
X527255Y7375D01*
X527280Y7340D01*
X527310Y7305D01*
X527330Y7270D01*
X527355Y7235D01*
X527395Y7155D01*
X527440Y7035D01*
X527450Y6995D01*
X527460Y6950D01*
X527465Y6910D01*
X527475Y6865D01*
Y6695D01*
X527465Y6650D01*
X527460Y6610D01*
X527450Y6565D01*
X527440Y6525D01*
X527395Y6405D01*
X527355Y6325D01*
X527330Y6290D01*
X527310Y6255D01*
X527280Y6220D01*
X527255Y6185D01*
X527225Y6155D01*
Y3730D01*
X527215Y3605D01*
X527175Y3480D01*
X527115Y3370D01*
X527035Y3270D01*
X526935Y3190D01*
X526825Y3130D01*
X526700Y3090D01*
X526575Y3080D01*
G37*
G36*
G01X554921D02*
X554796Y3090D01*
X554671Y3130D01*
X554561Y3190D01*
X554461Y3270D01*
X554381Y3370D01*
X554321Y3480D01*
X554281Y3605D01*
X554271Y3730D01*
Y6160D01*
X554241Y6190D01*
X554141Y6330D01*
X554121Y6370D01*
X554106Y6405D01*
X554086Y6445D01*
X554071Y6485D01*
X554061Y6525D01*
X554046Y6570D01*
X554041Y6610D01*
X554031Y6650D01*
X554026Y6695D01*
Y6735D01*
X554021Y6780D01*
X554026Y6825D01*
Y6865D01*
X554031Y6910D01*
X554041Y6950D01*
X554046Y6990D01*
X554061Y7035D01*
X554071Y7075D01*
X554086Y7115D01*
X554106Y7155D01*
X554121Y7190D01*
X554141Y7230D01*
X554241Y7370D01*
X554271Y7400D01*
Y9530D01*
X554281Y9655D01*
X554321Y9780D01*
X554381Y9890D01*
X554461Y9990D01*
X554561Y10070D01*
X554671Y10130D01*
X554796Y10170D01*
X554921Y10180D01*
X555046Y10170D01*
X555171Y10130D01*
X555281Y10070D01*
X555381Y9990D01*
X555461Y9890D01*
X555521Y9780D01*
X555561Y9655D01*
X555571Y9530D01*
Y7405D01*
X555601Y7375D01*
X555626Y7340D01*
X555656Y7305D01*
X555676Y7270D01*
X555701Y7235D01*
X555741Y7155D01*
X555786Y7035D01*
X555796Y6995D01*
X555806Y6950D01*
X555811Y6910D01*
X555821Y6865D01*
Y6695D01*
X555811Y6650D01*
X555806Y6610D01*
X555796Y6565D01*
X555786Y6525D01*
X555741Y6405D01*
X555701Y6325D01*
X555676Y6290D01*
X555656Y6255D01*
X555626Y6220D01*
X555601Y6185D01*
X555571Y6155D01*
Y3730D01*
X555561Y3605D01*
X555521Y3480D01*
X555461Y3370D01*
X555381Y3270D01*
X555281Y3190D01*
X555171Y3130D01*
X555046Y3090D01*
X554921Y3080D01*
G37*
G36*
G01X550197D02*
X550072Y3090D01*
X549947Y3130D01*
X549837Y3190D01*
X549737Y3270D01*
X549657Y3370D01*
X549597Y3480D01*
X549557Y3605D01*
X549547Y3730D01*
Y6160D01*
X549517Y6190D01*
X549417Y6330D01*
X549397Y6370D01*
X549382Y6405D01*
X549362Y6445D01*
X549347Y6485D01*
X549337Y6525D01*
X549322Y6570D01*
X549317Y6610D01*
X549307Y6650D01*
X549302Y6695D01*
Y6735D01*
X549297Y6780D01*
X549302Y6825D01*
Y6865D01*
X549307Y6910D01*
X549317Y6950D01*
X549322Y6990D01*
X549337Y7035D01*
X549347Y7075D01*
X549362Y7115D01*
X549382Y7155D01*
X549397Y7190D01*
X549417Y7230D01*
X549517Y7370D01*
X549547Y7400D01*
Y9530D01*
X549557Y9655D01*
X549597Y9780D01*
X549657Y9890D01*
X549737Y9990D01*
X549837Y10070D01*
X549947Y10130D01*
X550072Y10170D01*
X550197Y10180D01*
X550322Y10170D01*
X550447Y10130D01*
X550557Y10070D01*
X550657Y9990D01*
X550737Y9890D01*
X550797Y9780D01*
X550837Y9655D01*
X550847Y9530D01*
Y7405D01*
X550877Y7375D01*
X550902Y7340D01*
X550932Y7305D01*
X550952Y7270D01*
X550977Y7235D01*
X551017Y7155D01*
X551062Y7035D01*
X551072Y6995D01*
X551082Y6950D01*
X551087Y6910D01*
X551097Y6865D01*
Y6695D01*
X551087Y6650D01*
X551082Y6610D01*
X551072Y6565D01*
X551062Y6525D01*
X551017Y6405D01*
X550977Y6325D01*
X550952Y6290D01*
X550932Y6255D01*
X550902Y6220D01*
X550877Y6185D01*
X550847Y6155D01*
Y3730D01*
X550837Y3605D01*
X550797Y3480D01*
X550737Y3370D01*
X550657Y3270D01*
X550557Y3190D01*
X550447Y3130D01*
X550322Y3090D01*
X550197Y3080D01*
G37*
G36*
G01X545472D02*
X545347Y3090D01*
X545222Y3130D01*
X545112Y3190D01*
X545012Y3270D01*
X544932Y3370D01*
X544872Y3480D01*
X544832Y3605D01*
X544822Y3730D01*
Y6160D01*
X544792Y6190D01*
X544692Y6330D01*
X544672Y6370D01*
X544657Y6405D01*
X544637Y6445D01*
X544622Y6485D01*
X544612Y6525D01*
X544597Y6570D01*
X544592Y6610D01*
X544582Y6650D01*
X544577Y6695D01*
Y6735D01*
X544572Y6780D01*
X544577Y6825D01*
Y6865D01*
X544582Y6910D01*
X544592Y6950D01*
X544597Y6990D01*
X544612Y7035D01*
X544622Y7075D01*
X544637Y7115D01*
X544657Y7155D01*
X544672Y7190D01*
X544692Y7230D01*
X544792Y7370D01*
X544822Y7400D01*
Y9530D01*
X544832Y9655D01*
X544872Y9780D01*
X544932Y9890D01*
X545012Y9990D01*
X545112Y10070D01*
X545222Y10130D01*
X545347Y10170D01*
X545472Y10180D01*
X545597Y10170D01*
X545722Y10130D01*
X545832Y10070D01*
X545932Y9990D01*
X546012Y9890D01*
X546072Y9780D01*
X546112Y9655D01*
X546122Y9530D01*
Y7405D01*
X546152Y7375D01*
X546177Y7340D01*
X546207Y7305D01*
X546227Y7270D01*
X546252Y7235D01*
X546292Y7155D01*
X546337Y7035D01*
X546347Y6995D01*
X546357Y6950D01*
X546362Y6910D01*
X546372Y6865D01*
Y6695D01*
X546362Y6650D01*
X546357Y6610D01*
X546347Y6565D01*
X546337Y6525D01*
X546292Y6405D01*
X546252Y6325D01*
X546227Y6290D01*
X546207Y6255D01*
X546177Y6220D01*
X546152Y6185D01*
X546122Y6155D01*
Y3730D01*
X546112Y3605D01*
X546072Y3480D01*
X546012Y3370D01*
X545932Y3270D01*
X545832Y3190D01*
X545722Y3130D01*
X545597Y3090D01*
X545472Y3080D01*
G37*
G36*
G01X569094D02*
X568969Y3090D01*
X568844Y3130D01*
X568734Y3190D01*
X568634Y3270D01*
X568554Y3370D01*
X568494Y3480D01*
X568454Y3605D01*
X568444Y3730D01*
Y6160D01*
X568414Y6190D01*
X568314Y6330D01*
X568294Y6370D01*
X568279Y6405D01*
X568259Y6445D01*
X568244Y6485D01*
X568234Y6525D01*
X568219Y6570D01*
X568214Y6610D01*
X568204Y6650D01*
X568199Y6695D01*
Y6735D01*
X568194Y6780D01*
X568199Y6825D01*
Y6865D01*
X568204Y6910D01*
X568214Y6950D01*
X568219Y6990D01*
X568234Y7035D01*
X568244Y7075D01*
X568259Y7115D01*
X568279Y7155D01*
X568294Y7190D01*
X568314Y7230D01*
X568414Y7370D01*
X568444Y7400D01*
Y9530D01*
X568454Y9655D01*
X568494Y9780D01*
X568554Y9890D01*
X568634Y9990D01*
X568734Y10070D01*
X568844Y10130D01*
X568969Y10170D01*
X569094Y10180D01*
X569219Y10170D01*
X569344Y10130D01*
X569454Y10070D01*
X569554Y9990D01*
X569634Y9890D01*
X569694Y9780D01*
X569734Y9655D01*
X569744Y9530D01*
Y7405D01*
X569774Y7375D01*
X569799Y7340D01*
X569829Y7305D01*
X569849Y7270D01*
X569874Y7235D01*
X569914Y7155D01*
X569959Y7035D01*
X569969Y6995D01*
X569979Y6950D01*
X569984Y6910D01*
X569994Y6865D01*
Y6695D01*
X569984Y6650D01*
X569979Y6610D01*
X569969Y6565D01*
X569959Y6525D01*
X569914Y6405D01*
X569874Y6325D01*
X569849Y6290D01*
X569829Y6255D01*
X569799Y6220D01*
X569774Y6185D01*
X569744Y6155D01*
Y3730D01*
X569734Y3605D01*
X569694Y3480D01*
X569634Y3370D01*
X569554Y3270D01*
X569454Y3190D01*
X569344Y3130D01*
X569219Y3090D01*
X569094Y3080D01*
G37*
G36*
G01X564370D02*
X564245Y3090D01*
X564120Y3130D01*
X564010Y3190D01*
X563910Y3270D01*
X563830Y3370D01*
X563770Y3480D01*
X563730Y3605D01*
X563720Y3730D01*
Y6160D01*
X563690Y6190D01*
X563590Y6330D01*
X563570Y6370D01*
X563555Y6405D01*
X563535Y6445D01*
X563520Y6485D01*
X563510Y6525D01*
X563495Y6570D01*
X563490Y6610D01*
X563480Y6650D01*
X563475Y6695D01*
Y6735D01*
X563470Y6780D01*
X563475Y6825D01*
Y6865D01*
X563480Y6910D01*
X563490Y6950D01*
X563495Y6990D01*
X563510Y7035D01*
X563520Y7075D01*
X563535Y7115D01*
X563555Y7155D01*
X563570Y7190D01*
X563590Y7230D01*
X563690Y7370D01*
X563720Y7400D01*
Y9530D01*
X563730Y9655D01*
X563770Y9780D01*
X563830Y9890D01*
X563910Y9990D01*
X564010Y10070D01*
X564120Y10130D01*
X564245Y10170D01*
X564370Y10180D01*
X564495Y10170D01*
X564620Y10130D01*
X564730Y10070D01*
X564830Y9990D01*
X564910Y9890D01*
X564970Y9780D01*
X565010Y9655D01*
X565020Y9530D01*
Y7405D01*
X565050Y7375D01*
X565075Y7340D01*
X565105Y7305D01*
X565125Y7270D01*
X565150Y7235D01*
X565190Y7155D01*
X565235Y7035D01*
X565245Y6995D01*
X565255Y6950D01*
X565260Y6910D01*
X565270Y6865D01*
Y6695D01*
X565260Y6650D01*
X565255Y6610D01*
X565245Y6565D01*
X565235Y6525D01*
X565190Y6405D01*
X565150Y6325D01*
X565125Y6290D01*
X565105Y6255D01*
X565075Y6220D01*
X565050Y6185D01*
X565020Y6155D01*
Y3730D01*
X565010Y3605D01*
X564970Y3480D01*
X564910Y3370D01*
X564830Y3270D01*
X564730Y3190D01*
X564620Y3130D01*
X564495Y3090D01*
X564370Y3080D01*
G37*
G36*
G01X559645D02*
X559520Y3090D01*
X559395Y3130D01*
X559285Y3190D01*
X559185Y3270D01*
X559105Y3370D01*
X559045Y3480D01*
X559005Y3605D01*
X558995Y3730D01*
Y6160D01*
X558965Y6190D01*
X558865Y6330D01*
X558845Y6370D01*
X558830Y6405D01*
X558810Y6445D01*
X558795Y6485D01*
X558785Y6525D01*
X558770Y6570D01*
X558765Y6610D01*
X558755Y6650D01*
X558750Y6695D01*
Y6735D01*
X558745Y6780D01*
X558750Y6825D01*
Y6865D01*
X558755Y6910D01*
X558765Y6950D01*
X558770Y6990D01*
X558785Y7035D01*
X558795Y7075D01*
X558810Y7115D01*
X558830Y7155D01*
X558845Y7190D01*
X558865Y7230D01*
X558965Y7370D01*
X558995Y7400D01*
Y9530D01*
X559005Y9655D01*
X559045Y9780D01*
X559105Y9890D01*
X559185Y9990D01*
X559285Y10070D01*
X559395Y10130D01*
X559520Y10170D01*
X559645Y10180D01*
X559770Y10170D01*
X559895Y10130D01*
X560005Y10070D01*
X560105Y9990D01*
X560185Y9890D01*
X560245Y9780D01*
X560285Y9655D01*
X560295Y9530D01*
Y7405D01*
X560325Y7375D01*
X560350Y7340D01*
X560380Y7305D01*
X560400Y7270D01*
X560425Y7235D01*
X560465Y7155D01*
X560510Y7035D01*
X560520Y6995D01*
X560530Y6950D01*
X560535Y6910D01*
X560545Y6865D01*
Y6695D01*
X560535Y6650D01*
X560530Y6610D01*
X560520Y6565D01*
X560510Y6525D01*
X560465Y6405D01*
X560425Y6325D01*
X560400Y6290D01*
X560380Y6255D01*
X560350Y6220D01*
X560325Y6185D01*
X560295Y6155D01*
Y3730D01*
X560285Y3605D01*
X560245Y3480D01*
X560185Y3370D01*
X560105Y3270D01*
X560005Y3190D01*
X559895Y3130D01*
X559770Y3090D01*
X559645Y3080D01*
G37*
G36*
G01X587992D02*
X587867Y3090D01*
X587742Y3130D01*
X587632Y3190D01*
X587532Y3270D01*
X587452Y3370D01*
X587392Y3480D01*
X587352Y3605D01*
X587342Y3730D01*
Y6160D01*
X587312Y6190D01*
X587212Y6330D01*
X587192Y6370D01*
X587177Y6405D01*
X587157Y6445D01*
X587142Y6485D01*
X587132Y6525D01*
X587117Y6570D01*
X587112Y6610D01*
X587102Y6650D01*
X587097Y6695D01*
Y6735D01*
X587092Y6780D01*
X587097Y6825D01*
Y6865D01*
X587102Y6910D01*
X587112Y6950D01*
X587117Y6990D01*
X587132Y7035D01*
X587142Y7075D01*
X587157Y7115D01*
X587177Y7155D01*
X587192Y7190D01*
X587212Y7230D01*
X587312Y7370D01*
X587342Y7400D01*
Y9530D01*
X587352Y9655D01*
X587392Y9780D01*
X587452Y9890D01*
X587532Y9990D01*
X587632Y10070D01*
X587742Y10130D01*
X587867Y10170D01*
X587992Y10180D01*
X588117Y10170D01*
X588242Y10130D01*
X588352Y10070D01*
X588452Y9990D01*
X588532Y9890D01*
X588592Y9780D01*
X588632Y9655D01*
X588642Y9530D01*
Y7405D01*
X588672Y7375D01*
X588697Y7340D01*
X588727Y7305D01*
X588747Y7270D01*
X588772Y7235D01*
X588812Y7155D01*
X588857Y7035D01*
X588867Y6995D01*
X588877Y6950D01*
X588882Y6910D01*
X588892Y6865D01*
Y6695D01*
X588882Y6650D01*
X588877Y6610D01*
X588867Y6565D01*
X588857Y6525D01*
X588812Y6405D01*
X588772Y6325D01*
X588747Y6290D01*
X588727Y6255D01*
X588697Y6220D01*
X588672Y6185D01*
X588642Y6155D01*
Y3730D01*
X588632Y3605D01*
X588592Y3480D01*
X588532Y3370D01*
X588452Y3270D01*
X588352Y3190D01*
X588242Y3130D01*
X588117Y3090D01*
X587992Y3080D01*
G37*
G36*
G01X583267D02*
X583142Y3090D01*
X583017Y3130D01*
X582907Y3190D01*
X582807Y3270D01*
X582727Y3370D01*
X582667Y3480D01*
X582627Y3605D01*
X582617Y3730D01*
Y6160D01*
X582587Y6190D01*
X582487Y6330D01*
X582467Y6370D01*
X582452Y6405D01*
X582432Y6445D01*
X582417Y6485D01*
X582407Y6525D01*
X582392Y6570D01*
X582387Y6610D01*
X582377Y6650D01*
X582372Y6695D01*
Y6735D01*
X582367Y6780D01*
X582372Y6825D01*
Y6865D01*
X582377Y6910D01*
X582387Y6950D01*
X582392Y6990D01*
X582407Y7035D01*
X582417Y7075D01*
X582432Y7115D01*
X582452Y7155D01*
X582467Y7190D01*
X582487Y7230D01*
X582587Y7370D01*
X582617Y7400D01*
Y9530D01*
X582627Y9655D01*
X582667Y9780D01*
X582727Y9890D01*
X582807Y9990D01*
X582907Y10070D01*
X583017Y10130D01*
X583142Y10170D01*
X583267Y10180D01*
X583392Y10170D01*
X583517Y10130D01*
X583627Y10070D01*
X583727Y9990D01*
X583807Y9890D01*
X583867Y9780D01*
X583907Y9655D01*
X583917Y9530D01*
Y7405D01*
X583947Y7375D01*
X583972Y7340D01*
X584002Y7305D01*
X584022Y7270D01*
X584047Y7235D01*
X584087Y7155D01*
X584132Y7035D01*
X584142Y6995D01*
X584152Y6950D01*
X584157Y6910D01*
X584167Y6865D01*
Y6695D01*
X584157Y6650D01*
X584152Y6610D01*
X584142Y6565D01*
X584132Y6525D01*
X584087Y6405D01*
X584047Y6325D01*
X584022Y6290D01*
X584002Y6255D01*
X583972Y6220D01*
X583947Y6185D01*
X583917Y6155D01*
Y3730D01*
X583907Y3605D01*
X583867Y3480D01*
X583807Y3370D01*
X583727Y3270D01*
X583627Y3190D01*
X583517Y3130D01*
X583392Y3090D01*
X583267Y3080D01*
G37*
G36*
G01X578543D02*
X578418Y3090D01*
X578293Y3130D01*
X578183Y3190D01*
X578083Y3270D01*
X578003Y3370D01*
X577943Y3480D01*
X577903Y3605D01*
X577893Y3730D01*
Y6160D01*
X577863Y6190D01*
X577763Y6330D01*
X577743Y6370D01*
X577728Y6405D01*
X577708Y6445D01*
X577693Y6485D01*
X577683Y6525D01*
X577668Y6570D01*
X577663Y6610D01*
X577653Y6650D01*
X577648Y6695D01*
Y6735D01*
X577643Y6780D01*
X577648Y6825D01*
Y6865D01*
X577653Y6910D01*
X577663Y6950D01*
X577668Y6990D01*
X577683Y7035D01*
X577693Y7075D01*
X577708Y7115D01*
X577728Y7155D01*
X577743Y7190D01*
X577763Y7230D01*
X577863Y7370D01*
X577893Y7400D01*
Y9530D01*
X577903Y9655D01*
X577943Y9780D01*
X578003Y9890D01*
X578083Y9990D01*
X578183Y10070D01*
X578293Y10130D01*
X578418Y10170D01*
X578543Y10180D01*
X578668Y10170D01*
X578793Y10130D01*
X578903Y10070D01*
X579003Y9990D01*
X579083Y9890D01*
X579143Y9780D01*
X579183Y9655D01*
X579193Y9530D01*
Y7405D01*
X579223Y7375D01*
X579248Y7340D01*
X579278Y7305D01*
X579298Y7270D01*
X579323Y7235D01*
X579363Y7155D01*
X579408Y7035D01*
X579418Y6995D01*
X579428Y6950D01*
X579433Y6910D01*
X579443Y6865D01*
Y6695D01*
X579433Y6650D01*
X579428Y6610D01*
X579418Y6565D01*
X579408Y6525D01*
X579363Y6405D01*
X579323Y6325D01*
X579298Y6290D01*
X579278Y6255D01*
X579248Y6220D01*
X579223Y6185D01*
X579193Y6155D01*
Y3730D01*
X579183Y3605D01*
X579143Y3480D01*
X579083Y3370D01*
X579003Y3270D01*
X578903Y3190D01*
X578793Y3130D01*
X578668Y3090D01*
X578543Y3080D01*
G37*
G36*
G01X573819D02*
X573694Y3090D01*
X573569Y3130D01*
X573459Y3190D01*
X573359Y3270D01*
X573279Y3370D01*
X573219Y3480D01*
X573179Y3605D01*
X573169Y3730D01*
Y6160D01*
X573139Y6190D01*
X573039Y6330D01*
X573019Y6370D01*
X573004Y6405D01*
X572984Y6445D01*
X572969Y6485D01*
X572959Y6525D01*
X572944Y6570D01*
X572939Y6610D01*
X572929Y6650D01*
X572924Y6695D01*
Y6735D01*
X572919Y6780D01*
X572924Y6825D01*
Y6865D01*
X572929Y6910D01*
X572939Y6950D01*
X572944Y6990D01*
X572959Y7035D01*
X572969Y7075D01*
X572984Y7115D01*
X573004Y7155D01*
X573019Y7190D01*
X573039Y7230D01*
X573139Y7370D01*
X573169Y7400D01*
Y9530D01*
X573179Y9655D01*
X573219Y9780D01*
X573279Y9890D01*
X573359Y9990D01*
X573459Y10070D01*
X573569Y10130D01*
X573694Y10170D01*
X573819Y10180D01*
X573944Y10170D01*
X574069Y10130D01*
X574179Y10070D01*
X574279Y9990D01*
X574359Y9890D01*
X574419Y9780D01*
X574459Y9655D01*
X574469Y9530D01*
Y7405D01*
X574499Y7375D01*
X574524Y7340D01*
X574554Y7305D01*
X574574Y7270D01*
X574599Y7235D01*
X574639Y7155D01*
X574684Y7035D01*
X574694Y6995D01*
X574704Y6950D01*
X574709Y6910D01*
X574719Y6865D01*
Y6695D01*
X574709Y6650D01*
X574704Y6610D01*
X574694Y6565D01*
X574684Y6525D01*
X574639Y6405D01*
X574599Y6325D01*
X574574Y6290D01*
X574554Y6255D01*
X574524Y6220D01*
X574499Y6185D01*
X574469Y6155D01*
Y3730D01*
X574459Y3605D01*
X574419Y3480D01*
X574359Y3370D01*
X574279Y3270D01*
X574179Y3190D01*
X574069Y3130D01*
X573944Y3090D01*
X573819Y3080D01*
G37*
G36*
G01X602165D02*
X602040Y3090D01*
X601915Y3130D01*
X601805Y3190D01*
X601705Y3270D01*
X601625Y3370D01*
X601565Y3480D01*
X601525Y3605D01*
X601515Y3730D01*
Y6160D01*
X601485Y6190D01*
X601385Y6330D01*
X601365Y6370D01*
X601350Y6405D01*
X601330Y6445D01*
X601315Y6485D01*
X601305Y6525D01*
X601290Y6570D01*
X601285Y6610D01*
X601275Y6650D01*
X601270Y6695D01*
Y6735D01*
X601265Y6780D01*
X601270Y6825D01*
Y6865D01*
X601275Y6910D01*
X601285Y6950D01*
X601290Y6990D01*
X601305Y7035D01*
X601315Y7075D01*
X601330Y7115D01*
X601350Y7155D01*
X601365Y7190D01*
X601385Y7230D01*
X601485Y7370D01*
X601515Y7400D01*
Y9530D01*
X601525Y9655D01*
X601565Y9780D01*
X601625Y9890D01*
X601705Y9990D01*
X601805Y10070D01*
X601915Y10130D01*
X602040Y10170D01*
X602165Y10180D01*
X602290Y10170D01*
X602415Y10130D01*
X602525Y10070D01*
X602625Y9990D01*
X602705Y9890D01*
X602765Y9780D01*
X602805Y9655D01*
X602815Y9530D01*
Y7405D01*
X602845Y7375D01*
X602870Y7340D01*
X602900Y7305D01*
X602920Y7270D01*
X602945Y7235D01*
X602985Y7155D01*
X603030Y7035D01*
X603040Y6995D01*
X603050Y6950D01*
X603055Y6910D01*
X603065Y6865D01*
Y6695D01*
X603055Y6650D01*
X603050Y6610D01*
X603040Y6565D01*
X603030Y6525D01*
X602985Y6405D01*
X602945Y6325D01*
X602920Y6290D01*
X602900Y6255D01*
X602870Y6220D01*
X602845Y6185D01*
X602815Y6155D01*
Y3730D01*
X602805Y3605D01*
X602765Y3480D01*
X602705Y3370D01*
X602625Y3270D01*
X602525Y3190D01*
X602415Y3130D01*
X602290Y3090D01*
X602165Y3080D01*
G37*
G36*
G01X616338D02*
X616213Y3090D01*
X616088Y3130D01*
X615978Y3190D01*
X615878Y3270D01*
X615798Y3370D01*
X615738Y3480D01*
X615698Y3605D01*
X615688Y3730D01*
Y6160D01*
X615658Y6190D01*
X615558Y6330D01*
X615538Y6370D01*
X615523Y6405D01*
X615503Y6445D01*
X615488Y6485D01*
X615478Y6525D01*
X615463Y6570D01*
X615458Y6610D01*
X615448Y6650D01*
X615443Y6695D01*
Y6735D01*
X615438Y6780D01*
X615443Y6825D01*
Y6865D01*
X615448Y6910D01*
X615458Y6950D01*
X615463Y6990D01*
X615478Y7035D01*
X615488Y7075D01*
X615503Y7115D01*
X615523Y7155D01*
X615538Y7190D01*
X615558Y7230D01*
X615658Y7370D01*
X615688Y7400D01*
Y9530D01*
X615698Y9655D01*
X615738Y9780D01*
X615798Y9890D01*
X615878Y9990D01*
X615978Y10070D01*
X616088Y10130D01*
X616213Y10170D01*
X616338Y10180D01*
X616463Y10170D01*
X616588Y10130D01*
X616698Y10070D01*
X616798Y9990D01*
X616878Y9890D01*
X616938Y9780D01*
X616978Y9655D01*
X616988Y9530D01*
Y7405D01*
X617018Y7375D01*
X617043Y7340D01*
X617073Y7305D01*
X617093Y7270D01*
X617118Y7235D01*
X617158Y7155D01*
X617203Y7035D01*
X617213Y6995D01*
X617223Y6950D01*
X617228Y6910D01*
X617238Y6865D01*
Y6695D01*
X617228Y6650D01*
X617223Y6610D01*
X617213Y6565D01*
X617203Y6525D01*
X617158Y6405D01*
X617118Y6325D01*
X617093Y6290D01*
X617073Y6255D01*
X617043Y6220D01*
X617018Y6185D01*
X616988Y6155D01*
Y3730D01*
X616978Y3605D01*
X616938Y3480D01*
X616878Y3370D01*
X616798Y3270D01*
X616698Y3190D01*
X616588Y3130D01*
X616463Y3090D01*
X616338Y3080D01*
G37*
G36*
G01X611614D02*
X611489Y3090D01*
X611364Y3130D01*
X611254Y3190D01*
X611154Y3270D01*
X611074Y3370D01*
X611014Y3480D01*
X610974Y3605D01*
X610964Y3730D01*
Y6160D01*
X610934Y6190D01*
X610834Y6330D01*
X610814Y6370D01*
X610799Y6405D01*
X610779Y6445D01*
X610764Y6485D01*
X610754Y6525D01*
X610739Y6570D01*
X610734Y6610D01*
X610724Y6650D01*
X610719Y6695D01*
Y6735D01*
X610714Y6780D01*
X610719Y6825D01*
Y6865D01*
X610724Y6910D01*
X610734Y6950D01*
X610739Y6990D01*
X610754Y7035D01*
X610764Y7075D01*
X610779Y7115D01*
X610799Y7155D01*
X610814Y7190D01*
X610834Y7230D01*
X610934Y7370D01*
X610964Y7400D01*
Y9530D01*
X610974Y9655D01*
X611014Y9780D01*
X611074Y9890D01*
X611154Y9990D01*
X611254Y10070D01*
X611364Y10130D01*
X611489Y10170D01*
X611614Y10180D01*
X611739Y10170D01*
X611864Y10130D01*
X611974Y10070D01*
X612074Y9990D01*
X612154Y9890D01*
X612214Y9780D01*
X612254Y9655D01*
X612264Y9530D01*
Y7405D01*
X612294Y7375D01*
X612319Y7340D01*
X612349Y7305D01*
X612369Y7270D01*
X612394Y7235D01*
X612434Y7155D01*
X612479Y7035D01*
X612489Y6995D01*
X612499Y6950D01*
X612504Y6910D01*
X612514Y6865D01*
Y6695D01*
X612504Y6650D01*
X612499Y6610D01*
X612489Y6565D01*
X612479Y6525D01*
X612434Y6405D01*
X612394Y6325D01*
X612369Y6290D01*
X612349Y6255D01*
X612319Y6220D01*
X612294Y6185D01*
X612264Y6155D01*
Y3730D01*
X612254Y3605D01*
X612214Y3480D01*
X612154Y3370D01*
X612074Y3270D01*
X611974Y3190D01*
X611864Y3130D01*
X611739Y3090D01*
X611614Y3080D01*
G37*
G36*
G01X606890D02*
X606765Y3090D01*
X606640Y3130D01*
X606530Y3190D01*
X606430Y3270D01*
X606350Y3370D01*
X606290Y3480D01*
X606250Y3605D01*
X606240Y3730D01*
Y6160D01*
X606210Y6190D01*
X606110Y6330D01*
X606090Y6370D01*
X606075Y6405D01*
X606055Y6445D01*
X606040Y6485D01*
X606030Y6525D01*
X606015Y6570D01*
X606010Y6610D01*
X606000Y6650D01*
X605995Y6695D01*
Y6735D01*
X605990Y6780D01*
X605995Y6825D01*
Y6865D01*
X606000Y6910D01*
X606010Y6950D01*
X606015Y6990D01*
X606030Y7035D01*
X606040Y7075D01*
X606055Y7115D01*
X606075Y7155D01*
X606090Y7190D01*
X606110Y7230D01*
X606210Y7370D01*
X606240Y7400D01*
Y9530D01*
X606250Y9655D01*
X606290Y9780D01*
X606350Y9890D01*
X606430Y9990D01*
X606530Y10070D01*
X606640Y10130D01*
X606765Y10170D01*
X606890Y10180D01*
X607015Y10170D01*
X607140Y10130D01*
X607250Y10070D01*
X607350Y9990D01*
X607430Y9890D01*
X607490Y9780D01*
X607530Y9655D01*
X607540Y9530D01*
Y7405D01*
X607570Y7375D01*
X607595Y7340D01*
X607625Y7305D01*
X607645Y7270D01*
X607670Y7235D01*
X607710Y7155D01*
X607755Y7035D01*
X607765Y6995D01*
X607775Y6950D01*
X607780Y6910D01*
X607790Y6865D01*
Y6695D01*
X607780Y6650D01*
X607775Y6610D01*
X607765Y6565D01*
X607755Y6525D01*
X607710Y6405D01*
X607670Y6325D01*
X607645Y6290D01*
X607625Y6255D01*
X607595Y6220D01*
X607570Y6185D01*
X607540Y6155D01*
Y3730D01*
X607530Y3605D01*
X607490Y3480D01*
X607430Y3370D01*
X607350Y3270D01*
X607250Y3190D01*
X607140Y3130D01*
X607015Y3090D01*
X606890Y3080D01*
G37*
G36*
G01X630512D02*
X630387Y3090D01*
X630262Y3130D01*
X630152Y3190D01*
X630052Y3270D01*
X629972Y3370D01*
X629912Y3480D01*
X629872Y3605D01*
X629862Y3730D01*
Y6160D01*
X629832Y6190D01*
X629732Y6330D01*
X629712Y6370D01*
X629697Y6405D01*
X629677Y6445D01*
X629662Y6485D01*
X629652Y6525D01*
X629637Y6570D01*
X629632Y6610D01*
X629622Y6650D01*
X629617Y6695D01*
Y6735D01*
X629612Y6780D01*
X629617Y6825D01*
Y6865D01*
X629622Y6910D01*
X629632Y6950D01*
X629637Y6990D01*
X629652Y7035D01*
X629662Y7075D01*
X629677Y7115D01*
X629697Y7155D01*
X629712Y7190D01*
X629732Y7230D01*
X629832Y7370D01*
X629862Y7400D01*
Y9530D01*
X629872Y9655D01*
X629912Y9780D01*
X629972Y9890D01*
X630052Y9990D01*
X630152Y10070D01*
X630262Y10130D01*
X630387Y10170D01*
X630512Y10180D01*
X630637Y10170D01*
X630762Y10130D01*
X630872Y10070D01*
X630972Y9990D01*
X631052Y9890D01*
X631112Y9780D01*
X631152Y9655D01*
X631162Y9530D01*
Y7405D01*
X631192Y7375D01*
X631217Y7340D01*
X631247Y7305D01*
X631267Y7270D01*
X631292Y7235D01*
X631332Y7155D01*
X631377Y7035D01*
X631387Y6995D01*
X631397Y6950D01*
X631402Y6910D01*
X631412Y6865D01*
Y6695D01*
X631402Y6650D01*
X631397Y6610D01*
X631387Y6565D01*
X631377Y6525D01*
X631332Y6405D01*
X631292Y6325D01*
X631267Y6290D01*
X631247Y6255D01*
X631217Y6220D01*
X631192Y6185D01*
X631162Y6155D01*
Y3730D01*
X631152Y3605D01*
X631112Y3480D01*
X631052Y3370D01*
X630972Y3270D01*
X630872Y3190D01*
X630762Y3130D01*
X630637Y3090D01*
X630512Y3080D01*
G37*
G36*
G01X625787D02*
X625662Y3090D01*
X625537Y3130D01*
X625427Y3190D01*
X625327Y3270D01*
X625247Y3370D01*
X625187Y3480D01*
X625147Y3605D01*
X625137Y3730D01*
Y6160D01*
X625107Y6190D01*
X625007Y6330D01*
X624987Y6370D01*
X624972Y6405D01*
X624952Y6445D01*
X624937Y6485D01*
X624927Y6525D01*
X624912Y6570D01*
X624907Y6610D01*
X624897Y6650D01*
X624892Y6695D01*
Y6735D01*
X624887Y6780D01*
X624892Y6825D01*
Y6865D01*
X624897Y6910D01*
X624907Y6950D01*
X624912Y6990D01*
X624927Y7035D01*
X624937Y7075D01*
X624952Y7115D01*
X624972Y7155D01*
X624987Y7190D01*
X625007Y7230D01*
X625107Y7370D01*
X625137Y7400D01*
Y9530D01*
X625147Y9655D01*
X625187Y9780D01*
X625247Y9890D01*
X625327Y9990D01*
X625427Y10070D01*
X625537Y10130D01*
X625662Y10170D01*
X625787Y10180D01*
X625912Y10170D01*
X626037Y10130D01*
X626147Y10070D01*
X626247Y9990D01*
X626327Y9890D01*
X626387Y9780D01*
X626427Y9655D01*
X626437Y9530D01*
Y7405D01*
X626467Y7375D01*
X626492Y7340D01*
X626522Y7305D01*
X626542Y7270D01*
X626567Y7235D01*
X626607Y7155D01*
X626652Y7035D01*
X626662Y6995D01*
X626672Y6950D01*
X626677Y6910D01*
X626687Y6865D01*
Y6695D01*
X626677Y6650D01*
X626672Y6610D01*
X626662Y6565D01*
X626652Y6525D01*
X626607Y6405D01*
X626567Y6325D01*
X626542Y6290D01*
X626522Y6255D01*
X626492Y6220D01*
X626467Y6185D01*
X626437Y6155D01*
Y3730D01*
X626427Y3605D01*
X626387Y3480D01*
X626327Y3370D01*
X626247Y3270D01*
X626147Y3190D01*
X626037Y3130D01*
X625912Y3090D01*
X625787Y3080D01*
G37*
G36*
G01X621063D02*
X620938Y3090D01*
X620813Y3130D01*
X620703Y3190D01*
X620603Y3270D01*
X620523Y3370D01*
X620463Y3480D01*
X620423Y3605D01*
X620413Y3730D01*
Y6160D01*
X620383Y6190D01*
X620283Y6330D01*
X620263Y6370D01*
X620248Y6405D01*
X620228Y6445D01*
X620213Y6485D01*
X620203Y6525D01*
X620188Y6570D01*
X620183Y6610D01*
X620173Y6650D01*
X620168Y6695D01*
Y6735D01*
X620163Y6780D01*
X620168Y6825D01*
Y6865D01*
X620173Y6910D01*
X620183Y6950D01*
X620188Y6990D01*
X620203Y7035D01*
X620213Y7075D01*
X620228Y7115D01*
X620248Y7155D01*
X620263Y7190D01*
X620283Y7230D01*
X620383Y7370D01*
X620413Y7400D01*
Y9530D01*
X620423Y9655D01*
X620463Y9780D01*
X620523Y9890D01*
X620603Y9990D01*
X620703Y10070D01*
X620813Y10130D01*
X620938Y10170D01*
X621063Y10180D01*
X621188Y10170D01*
X621313Y10130D01*
X621423Y10070D01*
X621523Y9990D01*
X621603Y9890D01*
X621663Y9780D01*
X621703Y9655D01*
X621713Y9530D01*
Y7405D01*
X621743Y7375D01*
X621768Y7340D01*
X621798Y7305D01*
X621818Y7270D01*
X621843Y7235D01*
X621883Y7155D01*
X621928Y7035D01*
X621938Y6995D01*
X621948Y6950D01*
X621953Y6910D01*
X621963Y6865D01*
Y6695D01*
X621953Y6650D01*
X621948Y6610D01*
X621938Y6565D01*
X621928Y6525D01*
X621883Y6405D01*
X621843Y6325D01*
X621818Y6290D01*
X621798Y6255D01*
X621768Y6220D01*
X621743Y6185D01*
X621713Y6155D01*
Y3730D01*
X621703Y3605D01*
X621663Y3480D01*
X621603Y3370D01*
X621523Y3270D01*
X621423Y3190D01*
X621313Y3130D01*
X621188Y3090D01*
X621063Y3080D01*
G37*
G36*
G01X649409D02*
X649284Y3090D01*
X649159Y3130D01*
X649049Y3190D01*
X648949Y3270D01*
X648869Y3370D01*
X648809Y3480D01*
X648769Y3605D01*
X648759Y3730D01*
Y6160D01*
X648729Y6190D01*
X648629Y6330D01*
X648609Y6370D01*
X648594Y6405D01*
X648574Y6445D01*
X648559Y6485D01*
X648549Y6525D01*
X648534Y6570D01*
X648529Y6610D01*
X648519Y6650D01*
X648514Y6695D01*
Y6735D01*
X648509Y6780D01*
X648514Y6825D01*
Y6865D01*
X648519Y6910D01*
X648529Y6950D01*
X648534Y6990D01*
X648549Y7035D01*
X648559Y7075D01*
X648574Y7115D01*
X648594Y7155D01*
X648609Y7190D01*
X648629Y7230D01*
X648729Y7370D01*
X648759Y7400D01*
Y9530D01*
X648769Y9655D01*
X648809Y9780D01*
X648869Y9890D01*
X648949Y9990D01*
X649049Y10070D01*
X649159Y10130D01*
X649284Y10170D01*
X649409Y10180D01*
X649534Y10170D01*
X649659Y10130D01*
X649769Y10070D01*
X649869Y9990D01*
X649949Y9890D01*
X650009Y9780D01*
X650049Y9655D01*
X650059Y9530D01*
Y7405D01*
X650089Y7375D01*
X650114Y7340D01*
X650144Y7305D01*
X650164Y7270D01*
X650189Y7235D01*
X650229Y7155D01*
X650274Y7035D01*
X650284Y6995D01*
X650294Y6950D01*
X650299Y6910D01*
X650309Y6865D01*
Y6695D01*
X650299Y6650D01*
X650294Y6610D01*
X650284Y6565D01*
X650274Y6525D01*
X650229Y6405D01*
X650189Y6325D01*
X650164Y6290D01*
X650144Y6255D01*
X650114Y6220D01*
X650089Y6185D01*
X650059Y6155D01*
Y3730D01*
X650049Y3605D01*
X650009Y3480D01*
X649949Y3370D01*
X649869Y3270D01*
X649769Y3190D01*
X649659Y3130D01*
X649534Y3090D01*
X649409Y3080D01*
G37*
G36*
G01X644685D02*
X644560Y3090D01*
X644435Y3130D01*
X644325Y3190D01*
X644225Y3270D01*
X644145Y3370D01*
X644085Y3480D01*
X644045Y3605D01*
X644035Y3730D01*
Y6160D01*
X644005Y6190D01*
X643905Y6330D01*
X643885Y6370D01*
X643870Y6405D01*
X643850Y6445D01*
X643835Y6485D01*
X643825Y6525D01*
X643810Y6570D01*
X643805Y6610D01*
X643795Y6650D01*
X643790Y6695D01*
Y6735D01*
X643785Y6780D01*
X643790Y6825D01*
Y6865D01*
X643795Y6910D01*
X643805Y6950D01*
X643810Y6990D01*
X643825Y7035D01*
X643835Y7075D01*
X643850Y7115D01*
X643870Y7155D01*
X643885Y7190D01*
X643905Y7230D01*
X644005Y7370D01*
X644035Y7400D01*
Y9530D01*
X644045Y9655D01*
X644085Y9780D01*
X644145Y9890D01*
X644225Y9990D01*
X644325Y10070D01*
X644435Y10130D01*
X644560Y10170D01*
X644685Y10180D01*
X644810Y10170D01*
X644935Y10130D01*
X645045Y10070D01*
X645145Y9990D01*
X645225Y9890D01*
X645285Y9780D01*
X645325Y9655D01*
X645335Y9530D01*
Y7405D01*
X645365Y7375D01*
X645390Y7340D01*
X645420Y7305D01*
X645440Y7270D01*
X645465Y7235D01*
X645505Y7155D01*
X645550Y7035D01*
X645560Y6995D01*
X645570Y6950D01*
X645575Y6910D01*
X645585Y6865D01*
Y6695D01*
X645575Y6650D01*
X645570Y6610D01*
X645560Y6565D01*
X645550Y6525D01*
X645505Y6405D01*
X645465Y6325D01*
X645440Y6290D01*
X645420Y6255D01*
X645390Y6220D01*
X645365Y6185D01*
X645335Y6155D01*
Y3730D01*
X645325Y3605D01*
X645285Y3480D01*
X645225Y3370D01*
X645145Y3270D01*
X645045Y3190D01*
X644935Y3130D01*
X644810Y3090D01*
X644685Y3080D01*
G37*
G36*
G01X639960D02*
X639835Y3090D01*
X639710Y3130D01*
X639600Y3190D01*
X639500Y3270D01*
X639420Y3370D01*
X639360Y3480D01*
X639320Y3605D01*
X639310Y3730D01*
Y6160D01*
X639280Y6190D01*
X639180Y6330D01*
X639160Y6370D01*
X639145Y6405D01*
X639125Y6445D01*
X639110Y6485D01*
X639100Y6525D01*
X639085Y6570D01*
X639080Y6610D01*
X639070Y6650D01*
X639065Y6695D01*
Y6735D01*
X639060Y6780D01*
X639065Y6825D01*
Y6865D01*
X639070Y6910D01*
X639080Y6950D01*
X639085Y6990D01*
X639100Y7035D01*
X639110Y7075D01*
X639125Y7115D01*
X639145Y7155D01*
X639160Y7190D01*
X639180Y7230D01*
X639280Y7370D01*
X639310Y7400D01*
Y9530D01*
X639320Y9655D01*
X639360Y9780D01*
X639420Y9890D01*
X639500Y9990D01*
X639600Y10070D01*
X639710Y10130D01*
X639835Y10170D01*
X639960Y10180D01*
X640085Y10170D01*
X640210Y10130D01*
X640320Y10070D01*
X640420Y9990D01*
X640500Y9890D01*
X640560Y9780D01*
X640600Y9655D01*
X640610Y9530D01*
Y7405D01*
X640640Y7375D01*
X640665Y7340D01*
X640695Y7305D01*
X640715Y7270D01*
X640740Y7235D01*
X640780Y7155D01*
X640825Y7035D01*
X640835Y6995D01*
X640845Y6950D01*
X640850Y6910D01*
X640860Y6865D01*
Y6695D01*
X640850Y6650D01*
X640845Y6610D01*
X640835Y6565D01*
X640825Y6525D01*
X640780Y6405D01*
X640740Y6325D01*
X640715Y6290D01*
X640695Y6255D01*
X640665Y6220D01*
X640640Y6185D01*
X640610Y6155D01*
Y3730D01*
X640600Y3605D01*
X640560Y3480D01*
X640500Y3370D01*
X640420Y3270D01*
X640320Y3190D01*
X640210Y3130D01*
X640085Y3090D01*
X639960Y3080D01*
G37*
G36*
G01X635236D02*
X635111Y3090D01*
X634986Y3130D01*
X634876Y3190D01*
X634776Y3270D01*
X634696Y3370D01*
X634636Y3480D01*
X634596Y3605D01*
X634586Y3730D01*
Y6160D01*
X634556Y6190D01*
X634456Y6330D01*
X634436Y6370D01*
X634421Y6405D01*
X634401Y6445D01*
X634386Y6485D01*
X634376Y6525D01*
X634361Y6570D01*
X634356Y6610D01*
X634346Y6650D01*
X634341Y6695D01*
Y6735D01*
X634336Y6780D01*
X634341Y6825D01*
Y6865D01*
X634346Y6910D01*
X634356Y6950D01*
X634361Y6990D01*
X634376Y7035D01*
X634386Y7075D01*
X634401Y7115D01*
X634421Y7155D01*
X634436Y7190D01*
X634456Y7230D01*
X634556Y7370D01*
X634586Y7400D01*
Y9530D01*
X634596Y9655D01*
X634636Y9780D01*
X634696Y9890D01*
X634776Y9990D01*
X634876Y10070D01*
X634986Y10130D01*
X635111Y10170D01*
X635236Y10180D01*
X635361Y10170D01*
X635486Y10130D01*
X635596Y10070D01*
X635696Y9990D01*
X635776Y9890D01*
X635836Y9780D01*
X635876Y9655D01*
X635886Y9530D01*
Y7405D01*
X635916Y7375D01*
X635941Y7340D01*
X635971Y7305D01*
X635991Y7270D01*
X636016Y7235D01*
X636056Y7155D01*
X636101Y7035D01*
X636111Y6995D01*
X636121Y6950D01*
X636126Y6910D01*
X636136Y6865D01*
Y6695D01*
X636126Y6650D01*
X636121Y6610D01*
X636111Y6565D01*
X636101Y6525D01*
X636056Y6405D01*
X636016Y6325D01*
X635991Y6290D01*
X635971Y6255D01*
X635941Y6220D01*
X635916Y6185D01*
X635886Y6155D01*
Y3730D01*
X635876Y3605D01*
X635836Y3480D01*
X635776Y3370D01*
X635696Y3270D01*
X635596Y3190D01*
X635486Y3130D01*
X635361Y3090D01*
X635236Y3080D01*
G37*
G36*
G01X663582D02*
X663457Y3090D01*
X663332Y3130D01*
X663222Y3190D01*
X663122Y3270D01*
X663042Y3370D01*
X662982Y3480D01*
X662942Y3605D01*
X662932Y3730D01*
Y6160D01*
X662902Y6190D01*
X662802Y6330D01*
X662782Y6370D01*
X662767Y6405D01*
X662747Y6445D01*
X662732Y6485D01*
X662722Y6525D01*
X662707Y6570D01*
X662702Y6610D01*
X662692Y6650D01*
X662687Y6695D01*
Y6735D01*
X662682Y6780D01*
X662687Y6825D01*
Y6865D01*
X662692Y6910D01*
X662702Y6950D01*
X662707Y6990D01*
X662722Y7035D01*
X662732Y7075D01*
X662747Y7115D01*
X662767Y7155D01*
X662782Y7190D01*
X662802Y7230D01*
X662902Y7370D01*
X662932Y7400D01*
Y9530D01*
X662942Y9655D01*
X662982Y9780D01*
X663042Y9890D01*
X663122Y9990D01*
X663222Y10070D01*
X663332Y10130D01*
X663457Y10170D01*
X663582Y10180D01*
X663707Y10170D01*
X663832Y10130D01*
X663942Y10070D01*
X664042Y9990D01*
X664122Y9890D01*
X664182Y9780D01*
X664222Y9655D01*
X664232Y9530D01*
Y7405D01*
X664262Y7375D01*
X664287Y7340D01*
X664317Y7305D01*
X664337Y7270D01*
X664362Y7235D01*
X664402Y7155D01*
X664447Y7035D01*
X664457Y6995D01*
X664467Y6950D01*
X664472Y6910D01*
X664482Y6865D01*
Y6695D01*
X664472Y6650D01*
X664467Y6610D01*
X664457Y6565D01*
X664447Y6525D01*
X664402Y6405D01*
X664362Y6325D01*
X664337Y6290D01*
X664317Y6255D01*
X664287Y6220D01*
X664262Y6185D01*
X664232Y6155D01*
Y3730D01*
X664222Y3605D01*
X664182Y3480D01*
X664122Y3370D01*
X664042Y3270D01*
X663942Y3190D01*
X663832Y3130D01*
X663707Y3090D01*
X663582Y3080D01*
G37*
G36*
G01X658858D02*
X658733Y3090D01*
X658608Y3130D01*
X658498Y3190D01*
X658398Y3270D01*
X658318Y3370D01*
X658258Y3480D01*
X658218Y3605D01*
X658208Y3730D01*
Y6160D01*
X658178Y6190D01*
X658078Y6330D01*
X658058Y6370D01*
X658043Y6405D01*
X658023Y6445D01*
X658008Y6485D01*
X657998Y6525D01*
X657983Y6570D01*
X657978Y6610D01*
X657968Y6650D01*
X657963Y6695D01*
Y6735D01*
X657958Y6780D01*
X657963Y6825D01*
Y6865D01*
X657968Y6910D01*
X657978Y6950D01*
X657983Y6990D01*
X657998Y7035D01*
X658008Y7075D01*
X658023Y7115D01*
X658043Y7155D01*
X658058Y7190D01*
X658078Y7230D01*
X658178Y7370D01*
X658208Y7400D01*
Y9530D01*
X658218Y9655D01*
X658258Y9780D01*
X658318Y9890D01*
X658398Y9990D01*
X658498Y10070D01*
X658608Y10130D01*
X658733Y10170D01*
X658858Y10180D01*
X658983Y10170D01*
X659108Y10130D01*
X659218Y10070D01*
X659318Y9990D01*
X659398Y9890D01*
X659458Y9780D01*
X659498Y9655D01*
X659508Y9530D01*
Y7405D01*
X659538Y7375D01*
X659563Y7340D01*
X659593Y7305D01*
X659613Y7270D01*
X659638Y7235D01*
X659678Y7155D01*
X659723Y7035D01*
X659733Y6995D01*
X659743Y6950D01*
X659748Y6910D01*
X659758Y6865D01*
Y6695D01*
X659748Y6650D01*
X659743Y6610D01*
X659733Y6565D01*
X659723Y6525D01*
X659678Y6405D01*
X659638Y6325D01*
X659613Y6290D01*
X659593Y6255D01*
X659563Y6220D01*
X659538Y6185D01*
X659508Y6155D01*
Y3730D01*
X659498Y3605D01*
X659458Y3480D01*
X659398Y3370D01*
X659318Y3270D01*
X659218Y3190D01*
X659108Y3130D01*
X658983Y3090D01*
X658858Y3080D01*
G37*
G36*
G01X654134D02*
X654009Y3090D01*
X653884Y3130D01*
X653774Y3190D01*
X653674Y3270D01*
X653594Y3370D01*
X653534Y3480D01*
X653494Y3605D01*
X653484Y3730D01*
Y6160D01*
X653454Y6190D01*
X653354Y6330D01*
X653334Y6370D01*
X653319Y6405D01*
X653299Y6445D01*
X653284Y6485D01*
X653274Y6525D01*
X653259Y6570D01*
X653254Y6610D01*
X653244Y6650D01*
X653239Y6695D01*
Y6735D01*
X653234Y6780D01*
X653239Y6825D01*
Y6865D01*
X653244Y6910D01*
X653254Y6950D01*
X653259Y6990D01*
X653274Y7035D01*
X653284Y7075D01*
X653299Y7115D01*
X653319Y7155D01*
X653334Y7190D01*
X653354Y7230D01*
X653454Y7370D01*
X653484Y7400D01*
Y9530D01*
X653494Y9655D01*
X653534Y9780D01*
X653594Y9890D01*
X653674Y9990D01*
X653774Y10070D01*
X653884Y10130D01*
X654009Y10170D01*
X654134Y10180D01*
X654259Y10170D01*
X654384Y10130D01*
X654494Y10070D01*
X654594Y9990D01*
X654674Y9890D01*
X654734Y9780D01*
X654774Y9655D01*
X654784Y9530D01*
Y7405D01*
X654814Y7375D01*
X654839Y7340D01*
X654869Y7305D01*
X654889Y7270D01*
X654914Y7235D01*
X654954Y7155D01*
X654999Y7035D01*
X655009Y6995D01*
X655019Y6950D01*
X655024Y6910D01*
X655034Y6865D01*
Y6695D01*
X655024Y6650D01*
X655019Y6610D01*
X655009Y6565D01*
X654999Y6525D01*
X654954Y6405D01*
X654914Y6325D01*
X654889Y6290D01*
X654869Y6255D01*
X654839Y6220D01*
X654814Y6185D01*
X654784Y6155D01*
Y3730D01*
X654774Y3605D01*
X654734Y3480D01*
X654674Y3370D01*
X654594Y3270D01*
X654494Y3190D01*
X654384Y3130D01*
X654259Y3090D01*
X654134Y3080D01*
G37*
G36*
G01X677756D02*
X677631Y3090D01*
X677506Y3130D01*
X677396Y3190D01*
X677296Y3270D01*
X677216Y3370D01*
X677156Y3480D01*
X677116Y3605D01*
X677106Y3730D01*
Y6160D01*
X677076Y6190D01*
X676976Y6330D01*
X676956Y6370D01*
X676941Y6405D01*
X676921Y6445D01*
X676906Y6485D01*
X676896Y6525D01*
X676881Y6570D01*
X676876Y6610D01*
X676866Y6650D01*
X676861Y6695D01*
Y6735D01*
X676856Y6780D01*
X676861Y6825D01*
Y6865D01*
X676866Y6910D01*
X676876Y6950D01*
X676881Y6990D01*
X676896Y7035D01*
X676906Y7075D01*
X676921Y7115D01*
X676941Y7155D01*
X676956Y7190D01*
X676976Y7230D01*
X677076Y7370D01*
X677106Y7400D01*
Y9530D01*
X677116Y9655D01*
X677156Y9780D01*
X677216Y9890D01*
X677296Y9990D01*
X677396Y10070D01*
X677506Y10130D01*
X677631Y10170D01*
X677756Y10180D01*
X677881Y10170D01*
X678006Y10130D01*
X678116Y10070D01*
X678216Y9990D01*
X678296Y9890D01*
X678356Y9780D01*
X678396Y9655D01*
X678406Y9530D01*
Y7405D01*
X678436Y7375D01*
X678461Y7340D01*
X678491Y7305D01*
X678511Y7270D01*
X678536Y7235D01*
X678576Y7155D01*
X678621Y7035D01*
X678631Y6995D01*
X678641Y6950D01*
X678646Y6910D01*
X678656Y6865D01*
Y6695D01*
X678646Y6650D01*
X678641Y6610D01*
X678631Y6565D01*
X678621Y6525D01*
X678576Y6405D01*
X678536Y6325D01*
X678511Y6290D01*
X678491Y6255D01*
X678461Y6220D01*
X678436Y6185D01*
X678406Y6155D01*
Y3730D01*
X678396Y3605D01*
X678356Y3480D01*
X678296Y3370D01*
X678216Y3270D01*
X678116Y3190D01*
X678006Y3130D01*
X677881Y3090D01*
X677756Y3080D01*
G37*
G36*
G01X673031D02*
X672906Y3090D01*
X672781Y3130D01*
X672671Y3190D01*
X672571Y3270D01*
X672491Y3370D01*
X672431Y3480D01*
X672391Y3605D01*
X672381Y3730D01*
Y6160D01*
X672351Y6190D01*
X672251Y6330D01*
X672231Y6370D01*
X672216Y6405D01*
X672196Y6445D01*
X672181Y6485D01*
X672171Y6525D01*
X672156Y6570D01*
X672151Y6610D01*
X672141Y6650D01*
X672136Y6695D01*
Y6735D01*
X672131Y6780D01*
X672136Y6825D01*
Y6865D01*
X672141Y6910D01*
X672151Y6950D01*
X672156Y6990D01*
X672171Y7035D01*
X672181Y7075D01*
X672196Y7115D01*
X672216Y7155D01*
X672231Y7190D01*
X672251Y7230D01*
X672351Y7370D01*
X672381Y7400D01*
Y9530D01*
X672391Y9655D01*
X672431Y9780D01*
X672491Y9890D01*
X672571Y9990D01*
X672671Y10070D01*
X672781Y10130D01*
X672906Y10170D01*
X673031Y10180D01*
X673156Y10170D01*
X673281Y10130D01*
X673391Y10070D01*
X673491Y9990D01*
X673571Y9890D01*
X673631Y9780D01*
X673671Y9655D01*
X673681Y9530D01*
Y7405D01*
X673711Y7375D01*
X673736Y7340D01*
X673766Y7305D01*
X673786Y7270D01*
X673811Y7235D01*
X673851Y7155D01*
X673896Y7035D01*
X673906Y6995D01*
X673916Y6950D01*
X673921Y6910D01*
X673931Y6865D01*
Y6695D01*
X673921Y6650D01*
X673916Y6610D01*
X673906Y6565D01*
X673896Y6525D01*
X673851Y6405D01*
X673811Y6325D01*
X673786Y6290D01*
X673766Y6255D01*
X673736Y6220D01*
X673711Y6185D01*
X673681Y6155D01*
Y3730D01*
X673671Y3605D01*
X673631Y3480D01*
X673571Y3370D01*
X673491Y3270D01*
X673391Y3190D01*
X673281Y3130D01*
X673156Y3090D01*
X673031Y3080D01*
G37*
G36*
G01X668307D02*
X668182Y3090D01*
X668057Y3130D01*
X667947Y3190D01*
X667847Y3270D01*
X667767Y3370D01*
X667707Y3480D01*
X667667Y3605D01*
X667657Y3730D01*
Y6160D01*
X667627Y6190D01*
X667527Y6330D01*
X667507Y6370D01*
X667492Y6405D01*
X667472Y6445D01*
X667457Y6485D01*
X667447Y6525D01*
X667432Y6570D01*
X667427Y6610D01*
X667417Y6650D01*
X667412Y6695D01*
Y6735D01*
X667407Y6780D01*
X667412Y6825D01*
Y6865D01*
X667417Y6910D01*
X667427Y6950D01*
X667432Y6990D01*
X667447Y7035D01*
X667457Y7075D01*
X667472Y7115D01*
X667492Y7155D01*
X667507Y7190D01*
X667527Y7230D01*
X667627Y7370D01*
X667657Y7400D01*
Y9530D01*
X667667Y9655D01*
X667707Y9780D01*
X667767Y9890D01*
X667847Y9990D01*
X667947Y10070D01*
X668057Y10130D01*
X668182Y10170D01*
X668307Y10180D01*
X668432Y10170D01*
X668557Y10130D01*
X668667Y10070D01*
X668767Y9990D01*
X668847Y9890D01*
X668907Y9780D01*
X668947Y9655D01*
X668957Y9530D01*
Y7405D01*
X668987Y7375D01*
X669012Y7340D01*
X669042Y7305D01*
X669062Y7270D01*
X669087Y7235D01*
X669127Y7155D01*
X669172Y7035D01*
X669182Y6995D01*
X669192Y6950D01*
X669197Y6910D01*
X669207Y6865D01*
Y6695D01*
X669197Y6650D01*
X669192Y6610D01*
X669182Y6565D01*
X669172Y6525D01*
X669127Y6405D01*
X669087Y6325D01*
X669062Y6290D01*
X669042Y6255D01*
X669012Y6220D01*
X668987Y6185D01*
X668957Y6155D01*
Y3730D01*
X668947Y3605D01*
X668907Y3480D01*
X668847Y3370D01*
X668767Y3270D01*
X668667Y3190D01*
X668557Y3130D01*
X668432Y3090D01*
X668307Y3080D01*
G37*
G36*
G01X691929D02*
X691804Y3090D01*
X691679Y3130D01*
X691569Y3190D01*
X691469Y3270D01*
X691389Y3370D01*
X691329Y3480D01*
X691289Y3605D01*
X691279Y3730D01*
Y6160D01*
X691249Y6190D01*
X691149Y6330D01*
X691129Y6370D01*
X691114Y6405D01*
X691094Y6445D01*
X691079Y6485D01*
X691069Y6525D01*
X691054Y6570D01*
X691049Y6610D01*
X691039Y6650D01*
X691034Y6695D01*
Y6735D01*
X691029Y6780D01*
X691034Y6825D01*
Y6865D01*
X691039Y6910D01*
X691049Y6950D01*
X691054Y6990D01*
X691069Y7035D01*
X691079Y7075D01*
X691094Y7115D01*
X691114Y7155D01*
X691129Y7190D01*
X691149Y7230D01*
X691249Y7370D01*
X691279Y7400D01*
Y9530D01*
X691289Y9655D01*
X691329Y9780D01*
X691389Y9890D01*
X691469Y9990D01*
X691569Y10070D01*
X691679Y10130D01*
X691804Y10170D01*
X691929Y10180D01*
X692054Y10170D01*
X692179Y10130D01*
X692289Y10070D01*
X692389Y9990D01*
X692469Y9890D01*
X692529Y9780D01*
X692569Y9655D01*
X692579Y9530D01*
Y7405D01*
X692609Y7375D01*
X692634Y7340D01*
X692664Y7305D01*
X692684Y7270D01*
X692709Y7235D01*
X692749Y7155D01*
X692794Y7035D01*
X692804Y6995D01*
X692814Y6950D01*
X692819Y6910D01*
X692829Y6865D01*
Y6695D01*
X692819Y6650D01*
X692814Y6610D01*
X692804Y6565D01*
X692794Y6525D01*
X692749Y6405D01*
X692709Y6325D01*
X692684Y6290D01*
X692664Y6255D01*
X692634Y6220D01*
X692609Y6185D01*
X692579Y6155D01*
Y3730D01*
X692569Y3605D01*
X692529Y3480D01*
X692469Y3370D01*
X692389Y3270D01*
X692289Y3190D01*
X692179Y3130D01*
X692054Y3090D01*
X691929Y3080D01*
G37*
G36*
G01X687204D02*
X687079Y3090D01*
X686954Y3130D01*
X686844Y3190D01*
X686744Y3270D01*
X686664Y3370D01*
X686604Y3480D01*
X686564Y3605D01*
X686554Y3730D01*
Y6160D01*
X686524Y6190D01*
X686424Y6330D01*
X686404Y6370D01*
X686389Y6405D01*
X686369Y6445D01*
X686354Y6485D01*
X686344Y6525D01*
X686329Y6570D01*
X686324Y6610D01*
X686314Y6650D01*
X686309Y6695D01*
Y6735D01*
X686304Y6780D01*
X686309Y6825D01*
Y6865D01*
X686314Y6910D01*
X686324Y6950D01*
X686329Y6990D01*
X686344Y7035D01*
X686354Y7075D01*
X686369Y7115D01*
X686389Y7155D01*
X686404Y7190D01*
X686424Y7230D01*
X686524Y7370D01*
X686554Y7400D01*
Y9530D01*
X686564Y9655D01*
X686604Y9780D01*
X686664Y9890D01*
X686744Y9990D01*
X686844Y10070D01*
X686954Y10130D01*
X687079Y10170D01*
X687204Y10180D01*
X687329Y10170D01*
X687454Y10130D01*
X687564Y10070D01*
X687664Y9990D01*
X687744Y9890D01*
X687804Y9780D01*
X687844Y9655D01*
X687854Y9530D01*
Y7405D01*
X687884Y7375D01*
X687909Y7340D01*
X687939Y7305D01*
X687959Y7270D01*
X687984Y7235D01*
X688024Y7155D01*
X688069Y7035D01*
X688079Y6995D01*
X688089Y6950D01*
X688094Y6910D01*
X688104Y6865D01*
Y6695D01*
X688094Y6650D01*
X688089Y6610D01*
X688079Y6565D01*
X688069Y6525D01*
X688024Y6405D01*
X687984Y6325D01*
X687959Y6290D01*
X687939Y6255D01*
X687909Y6220D01*
X687884Y6185D01*
X687854Y6155D01*
Y3730D01*
X687844Y3605D01*
X687804Y3480D01*
X687744Y3370D01*
X687664Y3270D01*
X687564Y3190D01*
X687454Y3130D01*
X687329Y3090D01*
X687204Y3080D01*
G37*
G36*
G01X682480D02*
X682355Y3090D01*
X682230Y3130D01*
X682120Y3190D01*
X682020Y3270D01*
X681940Y3370D01*
X681880Y3480D01*
X681840Y3605D01*
X681830Y3730D01*
Y6160D01*
X681800Y6190D01*
X681700Y6330D01*
X681680Y6370D01*
X681665Y6405D01*
X681645Y6445D01*
X681630Y6485D01*
X681620Y6525D01*
X681605Y6570D01*
X681600Y6610D01*
X681590Y6650D01*
X681585Y6695D01*
Y6735D01*
X681580Y6780D01*
X681585Y6825D01*
Y6865D01*
X681590Y6910D01*
X681600Y6950D01*
X681605Y6990D01*
X681620Y7035D01*
X681630Y7075D01*
X681645Y7115D01*
X681665Y7155D01*
X681680Y7190D01*
X681700Y7230D01*
X681800Y7370D01*
X681830Y7400D01*
Y9530D01*
X681840Y9655D01*
X681880Y9780D01*
X681940Y9890D01*
X682020Y9990D01*
X682120Y10070D01*
X682230Y10130D01*
X682355Y10170D01*
X682480Y10180D01*
X682605Y10170D01*
X682730Y10130D01*
X682840Y10070D01*
X682940Y9990D01*
X683020Y9890D01*
X683080Y9780D01*
X683120Y9655D01*
X683130Y9530D01*
Y7405D01*
X683160Y7375D01*
X683185Y7340D01*
X683215Y7305D01*
X683235Y7270D01*
X683260Y7235D01*
X683300Y7155D01*
X683345Y7035D01*
X683355Y6995D01*
X683365Y6950D01*
X683370Y6910D01*
X683380Y6865D01*
Y6695D01*
X683370Y6650D01*
X683365Y6610D01*
X683355Y6565D01*
X683345Y6525D01*
X683300Y6405D01*
X683260Y6325D01*
X683235Y6290D01*
X683215Y6255D01*
X683185Y6220D01*
X683160Y6185D01*
X683130Y6155D01*
Y3730D01*
X683120Y3605D01*
X683080Y3480D01*
X683020Y3370D01*
X682940Y3270D01*
X682840Y3190D01*
X682730Y3130D01*
X682605Y3090D01*
X682480Y3080D01*
G37*
G36*
G01X710827D02*
X710702Y3090D01*
X710577Y3130D01*
X710467Y3190D01*
X710367Y3270D01*
X710287Y3370D01*
X710227Y3480D01*
X710187Y3605D01*
X710177Y3730D01*
Y6160D01*
X710147Y6190D01*
X710047Y6330D01*
X710027Y6370D01*
X710012Y6405D01*
X709992Y6445D01*
X709977Y6485D01*
X709967Y6525D01*
X709952Y6570D01*
X709947Y6610D01*
X709937Y6650D01*
X709932Y6695D01*
Y6735D01*
X709927Y6780D01*
X709932Y6825D01*
Y6865D01*
X709937Y6910D01*
X709947Y6950D01*
X709952Y6990D01*
X709967Y7035D01*
X709977Y7075D01*
X709992Y7115D01*
X710012Y7155D01*
X710027Y7190D01*
X710047Y7230D01*
X710147Y7370D01*
X710177Y7400D01*
Y9530D01*
X710187Y9655D01*
X710227Y9780D01*
X710287Y9890D01*
X710367Y9990D01*
X710467Y10070D01*
X710577Y10130D01*
X710702Y10170D01*
X710827Y10180D01*
X710952Y10170D01*
X711077Y10130D01*
X711187Y10070D01*
X711287Y9990D01*
X711367Y9890D01*
X711427Y9780D01*
X711467Y9655D01*
X711477Y9530D01*
Y7405D01*
X711507Y7375D01*
X711532Y7340D01*
X711562Y7305D01*
X711582Y7270D01*
X711607Y7235D01*
X711647Y7155D01*
X711692Y7035D01*
X711702Y6995D01*
X711712Y6950D01*
X711717Y6910D01*
X711727Y6865D01*
Y6695D01*
X711717Y6650D01*
X711712Y6610D01*
X711702Y6565D01*
X711692Y6525D01*
X711647Y6405D01*
X711607Y6325D01*
X711582Y6290D01*
X711562Y6255D01*
X711532Y6220D01*
X711507Y6185D01*
X711477Y6155D01*
Y3730D01*
X711467Y3605D01*
X711427Y3480D01*
X711367Y3370D01*
X711287Y3270D01*
X711187Y3190D01*
X711077Y3130D01*
X710952Y3090D01*
X710827Y3080D01*
G37*
G36*
G01X706102D02*
X705977Y3090D01*
X705852Y3130D01*
X705742Y3190D01*
X705642Y3270D01*
X705562Y3370D01*
X705502Y3480D01*
X705462Y3605D01*
X705452Y3730D01*
Y6160D01*
X705422Y6190D01*
X705322Y6330D01*
X705302Y6370D01*
X705287Y6405D01*
X705267Y6445D01*
X705252Y6485D01*
X705242Y6525D01*
X705227Y6570D01*
X705222Y6610D01*
X705212Y6650D01*
X705207Y6695D01*
Y6735D01*
X705202Y6780D01*
X705207Y6825D01*
Y6865D01*
X705212Y6910D01*
X705222Y6950D01*
X705227Y6990D01*
X705242Y7035D01*
X705252Y7075D01*
X705267Y7115D01*
X705287Y7155D01*
X705302Y7190D01*
X705322Y7230D01*
X705422Y7370D01*
X705452Y7400D01*
Y9530D01*
X705462Y9655D01*
X705502Y9780D01*
X705562Y9890D01*
X705642Y9990D01*
X705742Y10070D01*
X705852Y10130D01*
X705977Y10170D01*
X706102Y10180D01*
X706227Y10170D01*
X706352Y10130D01*
X706462Y10070D01*
X706562Y9990D01*
X706642Y9890D01*
X706702Y9780D01*
X706742Y9655D01*
X706752Y9530D01*
Y7405D01*
X706782Y7375D01*
X706807Y7340D01*
X706837Y7305D01*
X706857Y7270D01*
X706882Y7235D01*
X706922Y7155D01*
X706967Y7035D01*
X706977Y6995D01*
X706987Y6950D01*
X706992Y6910D01*
X707002Y6865D01*
Y6695D01*
X706992Y6650D01*
X706987Y6610D01*
X706977Y6565D01*
X706967Y6525D01*
X706922Y6405D01*
X706882Y6325D01*
X706857Y6290D01*
X706837Y6255D01*
X706807Y6220D01*
X706782Y6185D01*
X706752Y6155D01*
Y3730D01*
X706742Y3605D01*
X706702Y3480D01*
X706642Y3370D01*
X706562Y3270D01*
X706462Y3190D01*
X706352Y3130D01*
X706227Y3090D01*
X706102Y3080D01*
G37*
G36*
G01X701378D02*
X701253Y3090D01*
X701128Y3130D01*
X701018Y3190D01*
X700918Y3270D01*
X700838Y3370D01*
X700778Y3480D01*
X700738Y3605D01*
X700728Y3730D01*
Y6160D01*
X700698Y6190D01*
X700598Y6330D01*
X700578Y6370D01*
X700563Y6405D01*
X700543Y6445D01*
X700528Y6485D01*
X700518Y6525D01*
X700503Y6570D01*
X700498Y6610D01*
X700488Y6650D01*
X700483Y6695D01*
Y6735D01*
X700478Y6780D01*
X700483Y6825D01*
Y6865D01*
X700488Y6910D01*
X700498Y6950D01*
X700503Y6990D01*
X700518Y7035D01*
X700528Y7075D01*
X700543Y7115D01*
X700563Y7155D01*
X700578Y7190D01*
X700598Y7230D01*
X700698Y7370D01*
X700728Y7400D01*
Y9530D01*
X700738Y9655D01*
X700778Y9780D01*
X700838Y9890D01*
X700918Y9990D01*
X701018Y10070D01*
X701128Y10130D01*
X701253Y10170D01*
X701378Y10180D01*
X701503Y10170D01*
X701628Y10130D01*
X701738Y10070D01*
X701838Y9990D01*
X701918Y9890D01*
X701978Y9780D01*
X702018Y9655D01*
X702028Y9530D01*
Y7405D01*
X702058Y7375D01*
X702083Y7340D01*
X702113Y7305D01*
X702133Y7270D01*
X702158Y7235D01*
X702198Y7155D01*
X702243Y7035D01*
X702253Y6995D01*
X702263Y6950D01*
X702268Y6910D01*
X702278Y6865D01*
Y6695D01*
X702268Y6650D01*
X702263Y6610D01*
X702253Y6565D01*
X702243Y6525D01*
X702198Y6405D01*
X702158Y6325D01*
X702133Y6290D01*
X702113Y6255D01*
X702083Y6220D01*
X702058Y6185D01*
X702028Y6155D01*
Y3730D01*
X702018Y3605D01*
X701978Y3480D01*
X701918Y3370D01*
X701838Y3270D01*
X701738Y3190D01*
X701628Y3130D01*
X701503Y3090D01*
X701378Y3080D01*
G37*
G36*
G01X696653D02*
X696528Y3090D01*
X696403Y3130D01*
X696293Y3190D01*
X696193Y3270D01*
X696113Y3370D01*
X696053Y3480D01*
X696013Y3605D01*
X696003Y3730D01*
Y6160D01*
X695973Y6190D01*
X695873Y6330D01*
X695853Y6370D01*
X695838Y6405D01*
X695818Y6445D01*
X695803Y6485D01*
X695793Y6525D01*
X695778Y6570D01*
X695773Y6610D01*
X695763Y6650D01*
X695758Y6695D01*
Y6735D01*
X695753Y6780D01*
X695758Y6825D01*
Y6865D01*
X695763Y6910D01*
X695773Y6950D01*
X695778Y6990D01*
X695793Y7035D01*
X695803Y7075D01*
X695818Y7115D01*
X695838Y7155D01*
X695853Y7190D01*
X695873Y7230D01*
X695973Y7370D01*
X696003Y7400D01*
Y9530D01*
X696013Y9655D01*
X696053Y9780D01*
X696113Y9890D01*
X696193Y9990D01*
X696293Y10070D01*
X696403Y10130D01*
X696528Y10170D01*
X696653Y10180D01*
X696778Y10170D01*
X696903Y10130D01*
X697013Y10070D01*
X697113Y9990D01*
X697193Y9890D01*
X697253Y9780D01*
X697293Y9655D01*
X697303Y9530D01*
Y7405D01*
X697333Y7375D01*
X697358Y7340D01*
X697388Y7305D01*
X697408Y7270D01*
X697433Y7235D01*
X697473Y7155D01*
X697518Y7035D01*
X697528Y6995D01*
X697538Y6950D01*
X697543Y6910D01*
X697553Y6865D01*
Y6695D01*
X697543Y6650D01*
X697538Y6610D01*
X697528Y6565D01*
X697518Y6525D01*
X697473Y6405D01*
X697433Y6325D01*
X697408Y6290D01*
X697388Y6255D01*
X697358Y6220D01*
X697333Y6185D01*
X697303Y6155D01*
Y3730D01*
X697293Y3605D01*
X697253Y3480D01*
X697193Y3370D01*
X697113Y3270D01*
X697013Y3190D01*
X696903Y3130D01*
X696778Y3090D01*
X696653Y3080D01*
G37*
G36*
G01X725000D02*
X724875Y3090D01*
X724750Y3130D01*
X724640Y3190D01*
X724540Y3270D01*
X724460Y3370D01*
X724400Y3480D01*
X724360Y3605D01*
X724350Y3730D01*
Y6160D01*
X724320Y6190D01*
X724220Y6330D01*
X724200Y6370D01*
X724185Y6405D01*
X724165Y6445D01*
X724150Y6485D01*
X724140Y6525D01*
X724125Y6570D01*
X724120Y6610D01*
X724110Y6650D01*
X724105Y6695D01*
Y6735D01*
X724100Y6780D01*
X724105Y6825D01*
Y6865D01*
X724110Y6910D01*
X724120Y6950D01*
X724125Y6990D01*
X724140Y7035D01*
X724150Y7075D01*
X724165Y7115D01*
X724185Y7155D01*
X724200Y7190D01*
X724220Y7230D01*
X724320Y7370D01*
X724350Y7400D01*
Y9530D01*
X724360Y9655D01*
X724400Y9780D01*
X724460Y9890D01*
X724540Y9990D01*
X724640Y10070D01*
X724750Y10130D01*
X724875Y10170D01*
X725000Y10180D01*
X725125Y10170D01*
X725250Y10130D01*
X725360Y10070D01*
X725460Y9990D01*
X725540Y9890D01*
X725600Y9780D01*
X725640Y9655D01*
X725650Y9530D01*
Y7405D01*
X725680Y7375D01*
X725705Y7340D01*
X725735Y7305D01*
X725755Y7270D01*
X725780Y7235D01*
X725820Y7155D01*
X725865Y7035D01*
X725875Y6995D01*
X725885Y6950D01*
X725890Y6910D01*
X725900Y6865D01*
Y6695D01*
X725890Y6650D01*
X725885Y6610D01*
X725875Y6565D01*
X725865Y6525D01*
X725820Y6405D01*
X725780Y6325D01*
X725755Y6290D01*
X725735Y6255D01*
X725705Y6220D01*
X725680Y6185D01*
X725650Y6155D01*
Y3730D01*
X725640Y3605D01*
X725600Y3480D01*
X725540Y3370D01*
X725460Y3270D01*
X725360Y3190D01*
X725250Y3130D01*
X725125Y3090D01*
X725000Y3080D01*
G37*
G36*
G01X720275D02*
X720150Y3090D01*
X720025Y3130D01*
X719915Y3190D01*
X719815Y3270D01*
X719735Y3370D01*
X719675Y3480D01*
X719635Y3605D01*
X719625Y3730D01*
Y6160D01*
X719595Y6190D01*
X719495Y6330D01*
X719475Y6370D01*
X719460Y6405D01*
X719440Y6445D01*
X719425Y6485D01*
X719415Y6525D01*
X719400Y6570D01*
X719395Y6610D01*
X719385Y6650D01*
X719380Y6695D01*
Y6735D01*
X719375Y6780D01*
X719380Y6825D01*
Y6865D01*
X719385Y6910D01*
X719395Y6950D01*
X719400Y6990D01*
X719415Y7035D01*
X719425Y7075D01*
X719440Y7115D01*
X719460Y7155D01*
X719475Y7190D01*
X719495Y7230D01*
X719595Y7370D01*
X719625Y7400D01*
Y9530D01*
X719635Y9655D01*
X719675Y9780D01*
X719735Y9890D01*
X719815Y9990D01*
X719915Y10070D01*
X720025Y10130D01*
X720150Y10170D01*
X720275Y10180D01*
X720400Y10170D01*
X720525Y10130D01*
X720635Y10070D01*
X720735Y9990D01*
X720815Y9890D01*
X720875Y9780D01*
X720915Y9655D01*
X720925Y9530D01*
Y7405D01*
X720955Y7375D01*
X720980Y7340D01*
X721010Y7305D01*
X721030Y7270D01*
X721055Y7235D01*
X721095Y7155D01*
X721140Y7035D01*
X721150Y6995D01*
X721160Y6950D01*
X721165Y6910D01*
X721175Y6865D01*
Y6695D01*
X721165Y6650D01*
X721160Y6610D01*
X721150Y6565D01*
X721140Y6525D01*
X721095Y6405D01*
X721055Y6325D01*
X721030Y6290D01*
X721010Y6255D01*
X720980Y6220D01*
X720955Y6185D01*
X720925Y6155D01*
Y3730D01*
X720915Y3605D01*
X720875Y3480D01*
X720815Y3370D01*
X720735Y3270D01*
X720635Y3190D01*
X720525Y3130D01*
X720400Y3090D01*
X720275Y3080D01*
G37*
G36*
G01X715551D02*
X715426Y3090D01*
X715301Y3130D01*
X715191Y3190D01*
X715091Y3270D01*
X715011Y3370D01*
X714951Y3480D01*
X714911Y3605D01*
X714901Y3730D01*
Y6160D01*
X714871Y6190D01*
X714771Y6330D01*
X714751Y6370D01*
X714736Y6405D01*
X714716Y6445D01*
X714701Y6485D01*
X714691Y6525D01*
X714676Y6570D01*
X714671Y6610D01*
X714661Y6650D01*
X714656Y6695D01*
Y6735D01*
X714651Y6780D01*
X714656Y6825D01*
Y6865D01*
X714661Y6910D01*
X714671Y6950D01*
X714676Y6990D01*
X714691Y7035D01*
X714701Y7075D01*
X714716Y7115D01*
X714736Y7155D01*
X714751Y7190D01*
X714771Y7230D01*
X714871Y7370D01*
X714901Y7400D01*
Y9530D01*
X714911Y9655D01*
X714951Y9780D01*
X715011Y9890D01*
X715091Y9990D01*
X715191Y10070D01*
X715301Y10130D01*
X715426Y10170D01*
X715551Y10180D01*
X715676Y10170D01*
X715801Y10130D01*
X715911Y10070D01*
X716011Y9990D01*
X716091Y9890D01*
X716151Y9780D01*
X716191Y9655D01*
X716201Y9530D01*
Y7405D01*
X716231Y7375D01*
X716256Y7340D01*
X716286Y7305D01*
X716306Y7270D01*
X716331Y7235D01*
X716371Y7155D01*
X716416Y7035D01*
X716426Y6995D01*
X716436Y6950D01*
X716441Y6910D01*
X716451Y6865D01*
Y6695D01*
X716441Y6650D01*
X716436Y6610D01*
X716426Y6565D01*
X716416Y6525D01*
X716371Y6405D01*
X716331Y6325D01*
X716306Y6290D01*
X716286Y6255D01*
X716256Y6220D01*
X716231Y6185D01*
X716201Y6155D01*
Y3730D01*
X716191Y3605D01*
X716151Y3480D01*
X716091Y3370D01*
X716011Y3270D01*
X715911Y3190D01*
X715801Y3130D01*
X715676Y3090D01*
X715551Y3080D01*
G37*
G36*
G01X739173D02*
X739048Y3090D01*
X738923Y3130D01*
X738813Y3190D01*
X738713Y3270D01*
X738633Y3370D01*
X738573Y3480D01*
X738533Y3605D01*
X738523Y3730D01*
Y6160D01*
X738493Y6190D01*
X738393Y6330D01*
X738373Y6370D01*
X738358Y6405D01*
X738338Y6445D01*
X738323Y6485D01*
X738313Y6525D01*
X738298Y6570D01*
X738293Y6610D01*
X738283Y6650D01*
X738278Y6695D01*
Y6735D01*
X738273Y6780D01*
X738278Y6825D01*
Y6865D01*
X738283Y6910D01*
X738293Y6950D01*
X738298Y6990D01*
X738313Y7035D01*
X738323Y7075D01*
X738338Y7115D01*
X738358Y7155D01*
X738373Y7190D01*
X738393Y7230D01*
X738493Y7370D01*
X738523Y7400D01*
Y9530D01*
X738533Y9655D01*
X738573Y9780D01*
X738633Y9890D01*
X738713Y9990D01*
X738813Y10070D01*
X738923Y10130D01*
X739048Y10170D01*
X739173Y10180D01*
X739298Y10170D01*
X739423Y10130D01*
X739533Y10070D01*
X739633Y9990D01*
X739713Y9890D01*
X739773Y9780D01*
X739813Y9655D01*
X739823Y9530D01*
Y7405D01*
X739853Y7375D01*
X739878Y7340D01*
X739908Y7305D01*
X739928Y7270D01*
X739953Y7235D01*
X739993Y7155D01*
X740038Y7035D01*
X740048Y6995D01*
X740058Y6950D01*
X740063Y6910D01*
X740073Y6865D01*
Y6695D01*
X740063Y6650D01*
X740058Y6610D01*
X740048Y6565D01*
X740038Y6525D01*
X739993Y6405D01*
X739953Y6325D01*
X739928Y6290D01*
X739908Y6255D01*
X739878Y6220D01*
X739853Y6185D01*
X739823Y6155D01*
Y3730D01*
X739813Y3605D01*
X739773Y3480D01*
X739713Y3370D01*
X739633Y3270D01*
X739533Y3190D01*
X739423Y3130D01*
X739298Y3090D01*
X739173Y3080D01*
G37*
G36*
G01X734449D02*
X734324Y3090D01*
X734199Y3130D01*
X734089Y3190D01*
X733989Y3270D01*
X733909Y3370D01*
X733849Y3480D01*
X733809Y3605D01*
X733799Y3730D01*
Y6160D01*
X733769Y6190D01*
X733669Y6330D01*
X733649Y6370D01*
X733634Y6405D01*
X733614Y6445D01*
X733599Y6485D01*
X733589Y6525D01*
X733574Y6570D01*
X733569Y6610D01*
X733559Y6650D01*
X733554Y6695D01*
Y6735D01*
X733549Y6780D01*
X733554Y6825D01*
Y6865D01*
X733559Y6910D01*
X733569Y6950D01*
X733574Y6990D01*
X733589Y7035D01*
X733599Y7075D01*
X733614Y7115D01*
X733634Y7155D01*
X733649Y7190D01*
X733669Y7230D01*
X733769Y7370D01*
X733799Y7400D01*
Y9530D01*
X733809Y9655D01*
X733849Y9780D01*
X733909Y9890D01*
X733989Y9990D01*
X734089Y10070D01*
X734199Y10130D01*
X734324Y10170D01*
X734449Y10180D01*
X734574Y10170D01*
X734699Y10130D01*
X734809Y10070D01*
X734909Y9990D01*
X734989Y9890D01*
X735049Y9780D01*
X735089Y9655D01*
X735099Y9530D01*
Y7405D01*
X735129Y7375D01*
X735154Y7340D01*
X735184Y7305D01*
X735204Y7270D01*
X735229Y7235D01*
X735269Y7155D01*
X735314Y7035D01*
X735324Y6995D01*
X735334Y6950D01*
X735339Y6910D01*
X735349Y6865D01*
Y6695D01*
X735339Y6650D01*
X735334Y6610D01*
X735324Y6565D01*
X735314Y6525D01*
X735269Y6405D01*
X735229Y6325D01*
X735204Y6290D01*
X735184Y6255D01*
X735154Y6220D01*
X735129Y6185D01*
X735099Y6155D01*
Y3730D01*
X735089Y3605D01*
X735049Y3480D01*
X734989Y3370D01*
X734909Y3270D01*
X734809Y3190D01*
X734699Y3130D01*
X734574Y3090D01*
X734449Y3080D01*
G37*
G36*
G01X729724D02*
X729599Y3090D01*
X729474Y3130D01*
X729364Y3190D01*
X729264Y3270D01*
X729184Y3370D01*
X729124Y3480D01*
X729084Y3605D01*
X729074Y3730D01*
Y6160D01*
X729044Y6190D01*
X728944Y6330D01*
X728924Y6370D01*
X728909Y6405D01*
X728889Y6445D01*
X728874Y6485D01*
X728864Y6525D01*
X728849Y6570D01*
X728844Y6610D01*
X728834Y6650D01*
X728829Y6695D01*
Y6735D01*
X728824Y6780D01*
X728829Y6825D01*
Y6865D01*
X728834Y6910D01*
X728844Y6950D01*
X728849Y6990D01*
X728864Y7035D01*
X728874Y7075D01*
X728889Y7115D01*
X728909Y7155D01*
X728924Y7190D01*
X728944Y7230D01*
X729044Y7370D01*
X729074Y7400D01*
Y9530D01*
X729084Y9655D01*
X729124Y9780D01*
X729184Y9890D01*
X729264Y9990D01*
X729364Y10070D01*
X729474Y10130D01*
X729599Y10170D01*
X729724Y10180D01*
X729849Y10170D01*
X729974Y10130D01*
X730084Y10070D01*
X730184Y9990D01*
X730264Y9890D01*
X730324Y9780D01*
X730364Y9655D01*
X730374Y9530D01*
Y7405D01*
X730404Y7375D01*
X730429Y7340D01*
X730459Y7305D01*
X730479Y7270D01*
X730504Y7235D01*
X730544Y7155D01*
X730589Y7035D01*
X730599Y6995D01*
X730609Y6950D01*
X730614Y6910D01*
X730624Y6865D01*
Y6695D01*
X730614Y6650D01*
X730609Y6610D01*
X730599Y6565D01*
X730589Y6525D01*
X730544Y6405D01*
X730504Y6325D01*
X730479Y6290D01*
X730459Y6255D01*
X730429Y6220D01*
X730404Y6185D01*
X730374Y6155D01*
Y3730D01*
X730364Y3605D01*
X730324Y3480D01*
X730264Y3370D01*
X730184Y3270D01*
X730084Y3190D01*
X729974Y3130D01*
X729849Y3090D01*
X729724Y3080D01*
G37*
G36*
G01X753346D02*
X753221Y3090D01*
X753096Y3130D01*
X752986Y3190D01*
X752886Y3270D01*
X752806Y3370D01*
X752746Y3480D01*
X752706Y3605D01*
X752696Y3730D01*
Y6160D01*
X752666Y6190D01*
X752566Y6330D01*
X752546Y6370D01*
X752531Y6405D01*
X752511Y6445D01*
X752496Y6485D01*
X752486Y6525D01*
X752471Y6570D01*
X752466Y6610D01*
X752456Y6650D01*
X752451Y6695D01*
Y6735D01*
X752446Y6780D01*
X752451Y6825D01*
Y6865D01*
X752456Y6910D01*
X752466Y6950D01*
X752471Y6990D01*
X752486Y7035D01*
X752496Y7075D01*
X752511Y7115D01*
X752531Y7155D01*
X752546Y7190D01*
X752566Y7230D01*
X752666Y7370D01*
X752696Y7400D01*
Y9530D01*
X752706Y9655D01*
X752746Y9780D01*
X752806Y9890D01*
X752886Y9990D01*
X752986Y10070D01*
X753096Y10130D01*
X753221Y10170D01*
X753346Y10180D01*
X753471Y10170D01*
X753596Y10130D01*
X753706Y10070D01*
X753806Y9990D01*
X753886Y9890D01*
X753946Y9780D01*
X753986Y9655D01*
X753996Y9530D01*
Y7405D01*
X754026Y7375D01*
X754051Y7340D01*
X754081Y7305D01*
X754101Y7270D01*
X754126Y7235D01*
X754166Y7155D01*
X754211Y7035D01*
X754221Y6995D01*
X754231Y6950D01*
X754236Y6910D01*
X754246Y6865D01*
Y6695D01*
X754236Y6650D01*
X754231Y6610D01*
X754221Y6565D01*
X754211Y6525D01*
X754166Y6405D01*
X754126Y6325D01*
X754101Y6290D01*
X754081Y6255D01*
X754051Y6220D01*
X754026Y6185D01*
X753996Y6155D01*
Y3730D01*
X753986Y3605D01*
X753946Y3480D01*
X753886Y3370D01*
X753806Y3270D01*
X753706Y3190D01*
X753596Y3130D01*
X753471Y3090D01*
X753346Y3080D01*
G37*
G36*
G01X748622D02*
X748497Y3090D01*
X748372Y3130D01*
X748262Y3190D01*
X748162Y3270D01*
X748082Y3370D01*
X748022Y3480D01*
X747982Y3605D01*
X747972Y3730D01*
Y6160D01*
X747942Y6190D01*
X747842Y6330D01*
X747822Y6370D01*
X747807Y6405D01*
X747787Y6445D01*
X747772Y6485D01*
X747762Y6525D01*
X747747Y6570D01*
X747742Y6610D01*
X747732Y6650D01*
X747727Y6695D01*
Y6735D01*
X747722Y6780D01*
X747727Y6825D01*
Y6865D01*
X747732Y6910D01*
X747742Y6950D01*
X747747Y6990D01*
X747762Y7035D01*
X747772Y7075D01*
X747787Y7115D01*
X747807Y7155D01*
X747822Y7190D01*
X747842Y7230D01*
X747942Y7370D01*
X747972Y7400D01*
Y9530D01*
X747982Y9655D01*
X748022Y9780D01*
X748082Y9890D01*
X748162Y9990D01*
X748262Y10070D01*
X748372Y10130D01*
X748497Y10170D01*
X748622Y10180D01*
X748747Y10170D01*
X748872Y10130D01*
X748982Y10070D01*
X749082Y9990D01*
X749162Y9890D01*
X749222Y9780D01*
X749262Y9655D01*
X749272Y9530D01*
Y7405D01*
X749302Y7375D01*
X749327Y7340D01*
X749357Y7305D01*
X749377Y7270D01*
X749402Y7235D01*
X749442Y7155D01*
X749487Y7035D01*
X749497Y6995D01*
X749507Y6950D01*
X749512Y6910D01*
X749522Y6865D01*
Y6695D01*
X749512Y6650D01*
X749507Y6610D01*
X749497Y6565D01*
X749487Y6525D01*
X749442Y6405D01*
X749402Y6325D01*
X749377Y6290D01*
X749357Y6255D01*
X749327Y6220D01*
X749302Y6185D01*
X749272Y6155D01*
Y3730D01*
X749262Y3605D01*
X749222Y3480D01*
X749162Y3370D01*
X749082Y3270D01*
X748982Y3190D01*
X748872Y3130D01*
X748747Y3090D01*
X748622Y3080D01*
G37*
G36*
G01X743897D02*
X743772Y3090D01*
X743647Y3130D01*
X743537Y3190D01*
X743437Y3270D01*
X743357Y3370D01*
X743297Y3480D01*
X743257Y3605D01*
X743247Y3730D01*
Y6160D01*
X743217Y6190D01*
X743117Y6330D01*
X743097Y6370D01*
X743082Y6405D01*
X743062Y6445D01*
X743047Y6485D01*
X743037Y6525D01*
X743022Y6570D01*
X743017Y6610D01*
X743007Y6650D01*
X743002Y6695D01*
Y6735D01*
X742997Y6780D01*
X743002Y6825D01*
Y6865D01*
X743007Y6910D01*
X743017Y6950D01*
X743022Y6990D01*
X743037Y7035D01*
X743047Y7075D01*
X743062Y7115D01*
X743082Y7155D01*
X743097Y7190D01*
X743117Y7230D01*
X743217Y7370D01*
X743247Y7400D01*
Y9530D01*
X743257Y9655D01*
X743297Y9780D01*
X743357Y9890D01*
X743437Y9990D01*
X743537Y10070D01*
X743647Y10130D01*
X743772Y10170D01*
X743897Y10180D01*
X744022Y10170D01*
X744147Y10130D01*
X744257Y10070D01*
X744357Y9990D01*
X744437Y9890D01*
X744497Y9780D01*
X744537Y9655D01*
X744547Y9530D01*
Y7405D01*
X744577Y7375D01*
X744602Y7340D01*
X744632Y7305D01*
X744652Y7270D01*
X744677Y7235D01*
X744717Y7155D01*
X744762Y7035D01*
X744772Y6995D01*
X744782Y6950D01*
X744787Y6910D01*
X744797Y6865D01*
Y6695D01*
X744787Y6650D01*
X744782Y6610D01*
X744772Y6565D01*
X744762Y6525D01*
X744717Y6405D01*
X744677Y6325D01*
X744652Y6290D01*
X744632Y6255D01*
X744602Y6220D01*
X744577Y6185D01*
X744547Y6155D01*
Y3730D01*
X744537Y3605D01*
X744497Y3480D01*
X744437Y3370D01*
X744357Y3270D01*
X744257Y3190D01*
X744147Y3130D01*
X744022Y3090D01*
X743897Y3080D01*
G37*
G54D79*
X280950Y243180D03*
Y240620D03*
Y238060D03*
Y235500D03*
Y232945D03*
Y250855D03*
Y248300D03*
Y245740D03*
X302650Y232945D03*
Y235500D03*
Y238060D03*
Y240620D03*
Y243180D03*
Y245740D03*
Y248300D03*
Y250855D03*
X575150Y211560D03*
Y209000D03*
Y206445D03*
Y224355D03*
Y221800D03*
Y219240D03*
Y216680D03*
Y214120D03*
X596850Y206445D03*
Y209000D03*
Y211560D03*
Y214120D03*
Y216680D03*
Y219240D03*
Y221800D03*
Y224355D03*
G54D97*
X540960Y222285D03*
G36*
G01X510039Y3080D02*
X509914Y3090D01*
X509789Y3130D01*
X509679Y3190D01*
X509579Y3270D01*
X509499Y3370D01*
X509439Y3480D01*
X509399Y3605D01*
X509389Y3730D01*
Y7160D01*
X509359Y7190D01*
X509259Y7330D01*
X509239Y7370D01*
X509224Y7405D01*
X509204Y7445D01*
X509189Y7485D01*
X509179Y7525D01*
X509164Y7570D01*
X509159Y7610D01*
X509149Y7650D01*
X509144Y7695D01*
Y7735D01*
X509139Y7780D01*
X509144Y7825D01*
Y7865D01*
X509149Y7910D01*
X509159Y7950D01*
X509164Y7990D01*
X509179Y8035D01*
X509189Y8075D01*
X509204Y8115D01*
X509224Y8155D01*
X509239Y8190D01*
X509259Y8230D01*
X509359Y8370D01*
X509389Y8400D01*
Y9530D01*
X509399Y9655D01*
X509439Y9780D01*
X509499Y9890D01*
X509579Y9990D01*
X509679Y10070D01*
X509789Y10130D01*
X509914Y10170D01*
X510039Y10180D01*
X510164Y10170D01*
X510289Y10130D01*
X510399Y10070D01*
X510499Y9990D01*
X510579Y9890D01*
X510639Y9780D01*
X510679Y9655D01*
X510689Y9530D01*
Y8400D01*
X510719Y8370D01*
X510819Y8230D01*
X510839Y8190D01*
X510854Y8155D01*
X510874Y8115D01*
X510889Y8075D01*
X510899Y8035D01*
X510914Y7990D01*
X510919Y7950D01*
X510929Y7910D01*
X510934Y7865D01*
Y7825D01*
X510939Y7780D01*
X510934Y7735D01*
Y7695D01*
X510929Y7650D01*
X510919Y7610D01*
X510914Y7570D01*
X510899Y7525D01*
X510889Y7485D01*
X510874Y7445D01*
X510854Y7405D01*
X510839Y7370D01*
X510819Y7330D01*
X510719Y7190D01*
X510689Y7160D01*
Y3730D01*
X510679Y3605D01*
X510639Y3480D01*
X510579Y3370D01*
X510499Y3270D01*
X510399Y3190D01*
X510289Y3130D01*
X510164Y3090D01*
X510039Y3080D01*
G37*
G36*
G01X505315D02*
X505190Y3090D01*
X505065Y3130D01*
X504955Y3190D01*
X504855Y3270D01*
X504775Y3370D01*
X504715Y3480D01*
X504675Y3605D01*
X504665Y3730D01*
Y7160D01*
X504635Y7190D01*
X504535Y7330D01*
X504515Y7370D01*
X504500Y7405D01*
X504480Y7445D01*
X504465Y7485D01*
X504455Y7525D01*
X504440Y7570D01*
X504435Y7610D01*
X504425Y7650D01*
X504420Y7695D01*
Y7735D01*
X504415Y7780D01*
X504420Y7825D01*
Y7865D01*
X504425Y7910D01*
X504435Y7950D01*
X504440Y7990D01*
X504455Y8035D01*
X504465Y8075D01*
X504480Y8115D01*
X504500Y8155D01*
X504515Y8190D01*
X504535Y8230D01*
X504635Y8370D01*
X504665Y8400D01*
Y9530D01*
X504675Y9655D01*
X504715Y9780D01*
X504775Y9890D01*
X504855Y9990D01*
X504955Y10070D01*
X505065Y10130D01*
X505190Y10170D01*
X505315Y10180D01*
X505440Y10170D01*
X505565Y10130D01*
X505675Y10070D01*
X505775Y9990D01*
X505855Y9890D01*
X505915Y9780D01*
X505955Y9655D01*
X505965Y9530D01*
Y8400D01*
X505995Y8370D01*
X506095Y8230D01*
X506115Y8190D01*
X506130Y8155D01*
X506150Y8115D01*
X506165Y8075D01*
X506175Y8035D01*
X506190Y7990D01*
X506195Y7950D01*
X506205Y7910D01*
X506210Y7865D01*
Y7825D01*
X506215Y7780D01*
X506210Y7735D01*
Y7695D01*
X506205Y7650D01*
X506195Y7610D01*
X506190Y7570D01*
X506175Y7525D01*
X506165Y7485D01*
X506150Y7445D01*
X506130Y7405D01*
X506115Y7370D01*
X506095Y7330D01*
X505995Y7190D01*
X505965Y7160D01*
Y3730D01*
X505955Y3605D01*
X505915Y3480D01*
X505855Y3370D01*
X505775Y3270D01*
X505675Y3190D01*
X505565Y3130D01*
X505440Y3090D01*
X505315Y3080D01*
G37*
G36*
G01X524212D02*
X524087Y3090D01*
X523962Y3130D01*
X523852Y3190D01*
X523752Y3270D01*
X523672Y3370D01*
X523612Y3480D01*
X523572Y3605D01*
X523562Y3730D01*
Y7160D01*
X523532Y7190D01*
X523432Y7330D01*
X523412Y7370D01*
X523397Y7405D01*
X523377Y7445D01*
X523362Y7485D01*
X523352Y7525D01*
X523337Y7570D01*
X523332Y7610D01*
X523322Y7650D01*
X523317Y7695D01*
Y7735D01*
X523312Y7780D01*
X523317Y7825D01*
Y7865D01*
X523322Y7910D01*
X523332Y7950D01*
X523337Y7990D01*
X523352Y8035D01*
X523362Y8075D01*
X523377Y8115D01*
X523397Y8155D01*
X523412Y8190D01*
X523432Y8230D01*
X523532Y8370D01*
X523562Y8400D01*
Y9530D01*
X523572Y9655D01*
X523612Y9780D01*
X523672Y9890D01*
X523752Y9990D01*
X523852Y10070D01*
X523962Y10130D01*
X524087Y10170D01*
X524212Y10180D01*
X524337Y10170D01*
X524462Y10130D01*
X524572Y10070D01*
X524672Y9990D01*
X524752Y9890D01*
X524812Y9780D01*
X524852Y9655D01*
X524862Y9530D01*
Y8400D01*
X524892Y8370D01*
X524992Y8230D01*
X525012Y8190D01*
X525027Y8155D01*
X525047Y8115D01*
X525062Y8075D01*
X525072Y8035D01*
X525087Y7990D01*
X525092Y7950D01*
X525102Y7910D01*
X525107Y7865D01*
Y7825D01*
X525112Y7780D01*
X525107Y7735D01*
Y7695D01*
X525102Y7650D01*
X525092Y7610D01*
X525087Y7570D01*
X525072Y7525D01*
X525062Y7485D01*
X525047Y7445D01*
X525027Y7405D01*
X525012Y7370D01*
X524992Y7330D01*
X524892Y7190D01*
X524862Y7160D01*
Y3730D01*
X524852Y3605D01*
X524812Y3480D01*
X524752Y3370D01*
X524672Y3270D01*
X524572Y3190D01*
X524462Y3130D01*
X524337Y3090D01*
X524212Y3080D01*
G37*
G36*
G01X519488D02*
X519363Y3090D01*
X519238Y3130D01*
X519128Y3190D01*
X519028Y3270D01*
X518948Y3370D01*
X518888Y3480D01*
X518848Y3605D01*
X518838Y3730D01*
Y7160D01*
X518808Y7190D01*
X518708Y7330D01*
X518688Y7370D01*
X518673Y7405D01*
X518653Y7445D01*
X518638Y7485D01*
X518628Y7525D01*
X518613Y7570D01*
X518608Y7610D01*
X518598Y7650D01*
X518593Y7695D01*
Y7735D01*
X518588Y7780D01*
X518593Y7825D01*
Y7865D01*
X518598Y7910D01*
X518608Y7950D01*
X518613Y7990D01*
X518628Y8035D01*
X518638Y8075D01*
X518653Y8115D01*
X518673Y8155D01*
X518688Y8190D01*
X518708Y8230D01*
X518808Y8370D01*
X518838Y8400D01*
Y9530D01*
X518848Y9655D01*
X518888Y9780D01*
X518948Y9890D01*
X519028Y9990D01*
X519128Y10070D01*
X519238Y10130D01*
X519363Y10170D01*
X519488Y10180D01*
X519613Y10170D01*
X519738Y10130D01*
X519848Y10070D01*
X519948Y9990D01*
X520028Y9890D01*
X520088Y9780D01*
X520128Y9655D01*
X520138Y9530D01*
Y8400D01*
X520168Y8370D01*
X520268Y8230D01*
X520288Y8190D01*
X520303Y8155D01*
X520323Y8115D01*
X520338Y8075D01*
X520348Y8035D01*
X520363Y7990D01*
X520368Y7950D01*
X520378Y7910D01*
X520383Y7865D01*
Y7825D01*
X520388Y7780D01*
X520383Y7735D01*
Y7695D01*
X520378Y7650D01*
X520368Y7610D01*
X520363Y7570D01*
X520348Y7525D01*
X520338Y7485D01*
X520323Y7445D01*
X520303Y7405D01*
X520288Y7370D01*
X520268Y7330D01*
X520168Y7190D01*
X520138Y7160D01*
Y3730D01*
X520128Y3605D01*
X520088Y3480D01*
X520028Y3370D01*
X519948Y3270D01*
X519848Y3190D01*
X519738Y3130D01*
X519613Y3090D01*
X519488Y3080D01*
G37*
G36*
G01X514764D02*
X514639Y3090D01*
X514514Y3130D01*
X514404Y3190D01*
X514304Y3270D01*
X514224Y3370D01*
X514164Y3480D01*
X514124Y3605D01*
X514114Y3730D01*
Y7160D01*
X514084Y7190D01*
X513984Y7330D01*
X513964Y7370D01*
X513949Y7405D01*
X513929Y7445D01*
X513914Y7485D01*
X513904Y7525D01*
X513889Y7570D01*
X513884Y7610D01*
X513874Y7650D01*
X513869Y7695D01*
Y7735D01*
X513864Y7780D01*
X513869Y7825D01*
Y7865D01*
X513874Y7910D01*
X513884Y7950D01*
X513889Y7990D01*
X513904Y8035D01*
X513914Y8075D01*
X513929Y8115D01*
X513949Y8155D01*
X513964Y8190D01*
X513984Y8230D01*
X514084Y8370D01*
X514114Y8400D01*
Y9530D01*
X514124Y9655D01*
X514164Y9780D01*
X514224Y9890D01*
X514304Y9990D01*
X514404Y10070D01*
X514514Y10130D01*
X514639Y10170D01*
X514764Y10180D01*
X514889Y10170D01*
X515014Y10130D01*
X515124Y10070D01*
X515224Y9990D01*
X515304Y9890D01*
X515364Y9780D01*
X515404Y9655D01*
X515414Y9530D01*
Y8400D01*
X515444Y8370D01*
X515544Y8230D01*
X515564Y8190D01*
X515579Y8155D01*
X515599Y8115D01*
X515614Y8075D01*
X515624Y8035D01*
X515639Y7990D01*
X515644Y7950D01*
X515654Y7910D01*
X515659Y7865D01*
Y7825D01*
X515664Y7780D01*
X515659Y7735D01*
Y7695D01*
X515654Y7650D01*
X515644Y7610D01*
X515639Y7570D01*
X515624Y7525D01*
X515614Y7485D01*
X515599Y7445D01*
X515579Y7405D01*
X515564Y7370D01*
X515544Y7330D01*
X515444Y7190D01*
X515414Y7160D01*
Y3730D01*
X515404Y3605D01*
X515364Y3480D01*
X515304Y3370D01*
X515224Y3270D01*
X515124Y3190D01*
X515014Y3130D01*
X514889Y3090D01*
X514764Y3080D01*
G37*
G36*
G01X538386D02*
X538261Y3090D01*
X538136Y3130D01*
X538026Y3190D01*
X537926Y3270D01*
X537846Y3370D01*
X537786Y3480D01*
X537746Y3605D01*
X537736Y3730D01*
Y7160D01*
X537706Y7190D01*
X537606Y7330D01*
X537586Y7370D01*
X537571Y7405D01*
X537551Y7445D01*
X537536Y7485D01*
X537526Y7525D01*
X537511Y7570D01*
X537506Y7610D01*
X537496Y7650D01*
X537491Y7695D01*
Y7735D01*
X537486Y7780D01*
X537491Y7825D01*
Y7865D01*
X537496Y7910D01*
X537506Y7950D01*
X537511Y7990D01*
X537526Y8035D01*
X537536Y8075D01*
X537551Y8115D01*
X537571Y8155D01*
X537586Y8190D01*
X537606Y8230D01*
X537706Y8370D01*
X537736Y8400D01*
Y9530D01*
X537746Y9655D01*
X537786Y9780D01*
X537846Y9890D01*
X537926Y9990D01*
X538026Y10070D01*
X538136Y10130D01*
X538261Y10170D01*
X538386Y10180D01*
X538511Y10170D01*
X538636Y10130D01*
X538746Y10070D01*
X538846Y9990D01*
X538926Y9890D01*
X538986Y9780D01*
X539026Y9655D01*
X539036Y9530D01*
Y8400D01*
X539066Y8370D01*
X539166Y8230D01*
X539186Y8190D01*
X539201Y8155D01*
X539221Y8115D01*
X539236Y8075D01*
X539246Y8035D01*
X539261Y7990D01*
X539266Y7950D01*
X539276Y7910D01*
X539281Y7865D01*
Y7825D01*
X539286Y7780D01*
X539281Y7735D01*
Y7695D01*
X539276Y7650D01*
X539266Y7610D01*
X539261Y7570D01*
X539246Y7525D01*
X539236Y7485D01*
X539221Y7445D01*
X539201Y7405D01*
X539186Y7370D01*
X539166Y7330D01*
X539066Y7190D01*
X539036Y7160D01*
Y3730D01*
X539026Y3605D01*
X538986Y3480D01*
X538926Y3370D01*
X538846Y3270D01*
X538746Y3190D01*
X538636Y3130D01*
X538511Y3090D01*
X538386Y3080D01*
G37*
G36*
G01X533661D02*
X533536Y3090D01*
X533411Y3130D01*
X533301Y3190D01*
X533201Y3270D01*
X533121Y3370D01*
X533061Y3480D01*
X533021Y3605D01*
X533011Y3730D01*
Y7160D01*
X532981Y7190D01*
X532881Y7330D01*
X532861Y7370D01*
X532846Y7405D01*
X532826Y7445D01*
X532811Y7485D01*
X532801Y7525D01*
X532786Y7570D01*
X532781Y7610D01*
X532771Y7650D01*
X532766Y7695D01*
Y7735D01*
X532761Y7780D01*
X532766Y7825D01*
Y7865D01*
X532771Y7910D01*
X532781Y7950D01*
X532786Y7990D01*
X532801Y8035D01*
X532811Y8075D01*
X532826Y8115D01*
X532846Y8155D01*
X532861Y8190D01*
X532881Y8230D01*
X532981Y8370D01*
X533011Y8400D01*
Y9530D01*
X533021Y9655D01*
X533061Y9780D01*
X533121Y9890D01*
X533201Y9990D01*
X533301Y10070D01*
X533411Y10130D01*
X533536Y10170D01*
X533661Y10180D01*
X533786Y10170D01*
X533911Y10130D01*
X534021Y10070D01*
X534121Y9990D01*
X534201Y9890D01*
X534261Y9780D01*
X534301Y9655D01*
X534311Y9530D01*
Y8400D01*
X534341Y8370D01*
X534441Y8230D01*
X534461Y8190D01*
X534476Y8155D01*
X534496Y8115D01*
X534511Y8075D01*
X534521Y8035D01*
X534536Y7990D01*
X534541Y7950D01*
X534551Y7910D01*
X534556Y7865D01*
Y7825D01*
X534561Y7780D01*
X534556Y7735D01*
Y7695D01*
X534551Y7650D01*
X534541Y7610D01*
X534536Y7570D01*
X534521Y7525D01*
X534511Y7485D01*
X534496Y7445D01*
X534476Y7405D01*
X534461Y7370D01*
X534441Y7330D01*
X534341Y7190D01*
X534311Y7160D01*
Y3730D01*
X534301Y3605D01*
X534261Y3480D01*
X534201Y3370D01*
X534121Y3270D01*
X534021Y3190D01*
X533911Y3130D01*
X533786Y3090D01*
X533661Y3080D01*
G37*
G36*
G01X528937D02*
X528812Y3090D01*
X528687Y3130D01*
X528577Y3190D01*
X528477Y3270D01*
X528397Y3370D01*
X528337Y3480D01*
X528297Y3605D01*
X528287Y3730D01*
Y7160D01*
X528257Y7190D01*
X528157Y7330D01*
X528137Y7370D01*
X528122Y7405D01*
X528102Y7445D01*
X528087Y7485D01*
X528077Y7525D01*
X528062Y7570D01*
X528057Y7610D01*
X528047Y7650D01*
X528042Y7695D01*
Y7735D01*
X528037Y7780D01*
X528042Y7825D01*
Y7865D01*
X528047Y7910D01*
X528057Y7950D01*
X528062Y7990D01*
X528077Y8035D01*
X528087Y8075D01*
X528102Y8115D01*
X528122Y8155D01*
X528137Y8190D01*
X528157Y8230D01*
X528257Y8370D01*
X528287Y8400D01*
Y9530D01*
X528297Y9655D01*
X528337Y9780D01*
X528397Y9890D01*
X528477Y9990D01*
X528577Y10070D01*
X528687Y10130D01*
X528812Y10170D01*
X528937Y10180D01*
X529062Y10170D01*
X529187Y10130D01*
X529297Y10070D01*
X529397Y9990D01*
X529477Y9890D01*
X529537Y9780D01*
X529577Y9655D01*
X529587Y9530D01*
Y8400D01*
X529617Y8370D01*
X529717Y8230D01*
X529737Y8190D01*
X529752Y8155D01*
X529772Y8115D01*
X529787Y8075D01*
X529797Y8035D01*
X529812Y7990D01*
X529817Y7950D01*
X529827Y7910D01*
X529832Y7865D01*
Y7825D01*
X529837Y7780D01*
X529832Y7735D01*
Y7695D01*
X529827Y7650D01*
X529817Y7610D01*
X529812Y7570D01*
X529797Y7525D01*
X529787Y7485D01*
X529772Y7445D01*
X529752Y7405D01*
X529737Y7370D01*
X529717Y7330D01*
X529617Y7190D01*
X529587Y7160D01*
Y3730D01*
X529577Y3605D01*
X529537Y3480D01*
X529477Y3370D01*
X529397Y3270D01*
X529297Y3190D01*
X529187Y3130D01*
X529062Y3090D01*
X528937Y3080D01*
G37*
G36*
G01X557283D02*
X557158Y3090D01*
X557033Y3130D01*
X556923Y3190D01*
X556823Y3270D01*
X556743Y3370D01*
X556683Y3480D01*
X556643Y3605D01*
X556633Y3730D01*
Y7160D01*
X556603Y7190D01*
X556503Y7330D01*
X556483Y7370D01*
X556468Y7405D01*
X556448Y7445D01*
X556433Y7485D01*
X556423Y7525D01*
X556408Y7570D01*
X556403Y7610D01*
X556393Y7650D01*
X556388Y7695D01*
Y7735D01*
X556383Y7780D01*
X556388Y7825D01*
Y7865D01*
X556393Y7910D01*
X556403Y7950D01*
X556408Y7990D01*
X556423Y8035D01*
X556433Y8075D01*
X556448Y8115D01*
X556468Y8155D01*
X556483Y8190D01*
X556503Y8230D01*
X556603Y8370D01*
X556633Y8400D01*
Y9530D01*
X556643Y9655D01*
X556683Y9780D01*
X556743Y9890D01*
X556823Y9990D01*
X556923Y10070D01*
X557033Y10130D01*
X557158Y10170D01*
X557283Y10180D01*
X557408Y10170D01*
X557533Y10130D01*
X557643Y10070D01*
X557743Y9990D01*
X557823Y9890D01*
X557883Y9780D01*
X557923Y9655D01*
X557933Y9530D01*
Y8400D01*
X557963Y8370D01*
X558063Y8230D01*
X558083Y8190D01*
X558098Y8155D01*
X558118Y8115D01*
X558133Y8075D01*
X558143Y8035D01*
X558158Y7990D01*
X558163Y7950D01*
X558173Y7910D01*
X558178Y7865D01*
Y7825D01*
X558183Y7780D01*
X558178Y7735D01*
Y7695D01*
X558173Y7650D01*
X558163Y7610D01*
X558158Y7570D01*
X558143Y7525D01*
X558133Y7485D01*
X558118Y7445D01*
X558098Y7405D01*
X558083Y7370D01*
X558063Y7330D01*
X557963Y7190D01*
X557933Y7160D01*
Y3730D01*
X557923Y3605D01*
X557883Y3480D01*
X557823Y3370D01*
X557743Y3270D01*
X557643Y3190D01*
X557533Y3130D01*
X557408Y3090D01*
X557283Y3080D01*
G37*
G36*
G01X552559D02*
X552434Y3090D01*
X552309Y3130D01*
X552199Y3190D01*
X552099Y3270D01*
X552019Y3370D01*
X551959Y3480D01*
X551919Y3605D01*
X551909Y3730D01*
Y7160D01*
X551879Y7190D01*
X551779Y7330D01*
X551759Y7370D01*
X551744Y7405D01*
X551724Y7445D01*
X551709Y7485D01*
X551699Y7525D01*
X551684Y7570D01*
X551679Y7610D01*
X551669Y7650D01*
X551664Y7695D01*
Y7735D01*
X551659Y7780D01*
X551664Y7825D01*
Y7865D01*
X551669Y7910D01*
X551679Y7950D01*
X551684Y7990D01*
X551699Y8035D01*
X551709Y8075D01*
X551724Y8115D01*
X551744Y8155D01*
X551759Y8190D01*
X551779Y8230D01*
X551879Y8370D01*
X551909Y8400D01*
Y9530D01*
X551919Y9655D01*
X551959Y9780D01*
X552019Y9890D01*
X552099Y9990D01*
X552199Y10070D01*
X552309Y10130D01*
X552434Y10170D01*
X552559Y10180D01*
X552684Y10170D01*
X552809Y10130D01*
X552919Y10070D01*
X553019Y9990D01*
X553099Y9890D01*
X553159Y9780D01*
X553199Y9655D01*
X553209Y9530D01*
Y8400D01*
X553239Y8370D01*
X553339Y8230D01*
X553359Y8190D01*
X553374Y8155D01*
X553394Y8115D01*
X553409Y8075D01*
X553419Y8035D01*
X553434Y7990D01*
X553439Y7950D01*
X553449Y7910D01*
X553454Y7865D01*
Y7825D01*
X553459Y7780D01*
X553454Y7735D01*
Y7695D01*
X553449Y7650D01*
X553439Y7610D01*
X553434Y7570D01*
X553419Y7525D01*
X553409Y7485D01*
X553394Y7445D01*
X553374Y7405D01*
X553359Y7370D01*
X553339Y7330D01*
X553239Y7190D01*
X553209Y7160D01*
Y3730D01*
X553199Y3605D01*
X553159Y3480D01*
X553099Y3370D01*
X553019Y3270D01*
X552919Y3190D01*
X552809Y3130D01*
X552684Y3090D01*
X552559Y3080D01*
G37*
G36*
G01X547834D02*
X547709Y3090D01*
X547584Y3130D01*
X547474Y3190D01*
X547374Y3270D01*
X547294Y3370D01*
X547234Y3480D01*
X547194Y3605D01*
X547184Y3730D01*
Y7160D01*
X547154Y7190D01*
X547054Y7330D01*
X547034Y7370D01*
X547019Y7405D01*
X546999Y7445D01*
X546984Y7485D01*
X546974Y7525D01*
X546959Y7570D01*
X546954Y7610D01*
X546944Y7650D01*
X546939Y7695D01*
Y7735D01*
X546934Y7780D01*
X546939Y7825D01*
Y7865D01*
X546944Y7910D01*
X546954Y7950D01*
X546959Y7990D01*
X546974Y8035D01*
X546984Y8075D01*
X546999Y8115D01*
X547019Y8155D01*
X547034Y8190D01*
X547054Y8230D01*
X547154Y8370D01*
X547184Y8400D01*
Y9530D01*
X547194Y9655D01*
X547234Y9780D01*
X547294Y9890D01*
X547374Y9990D01*
X547474Y10070D01*
X547584Y10130D01*
X547709Y10170D01*
X547834Y10180D01*
X547959Y10170D01*
X548084Y10130D01*
X548194Y10070D01*
X548294Y9990D01*
X548374Y9890D01*
X548434Y9780D01*
X548474Y9655D01*
X548484Y9530D01*
Y8400D01*
X548514Y8370D01*
X548614Y8230D01*
X548634Y8190D01*
X548649Y8155D01*
X548669Y8115D01*
X548684Y8075D01*
X548694Y8035D01*
X548709Y7990D01*
X548714Y7950D01*
X548724Y7910D01*
X548729Y7865D01*
Y7825D01*
X548734Y7780D01*
X548729Y7735D01*
Y7695D01*
X548724Y7650D01*
X548714Y7610D01*
X548709Y7570D01*
X548694Y7525D01*
X548684Y7485D01*
X548669Y7445D01*
X548649Y7405D01*
X548634Y7370D01*
X548614Y7330D01*
X548514Y7190D01*
X548484Y7160D01*
Y3730D01*
X548474Y3605D01*
X548434Y3480D01*
X548374Y3370D01*
X548294Y3270D01*
X548194Y3190D01*
X548084Y3130D01*
X547959Y3090D01*
X547834Y3080D01*
G37*
G36*
G01X543110D02*
X542985Y3090D01*
X542860Y3130D01*
X542750Y3190D01*
X542650Y3270D01*
X542570Y3370D01*
X542510Y3480D01*
X542470Y3605D01*
X542460Y3730D01*
Y7160D01*
X542430Y7190D01*
X542330Y7330D01*
X542310Y7370D01*
X542295Y7405D01*
X542275Y7445D01*
X542260Y7485D01*
X542250Y7525D01*
X542235Y7570D01*
X542230Y7610D01*
X542220Y7650D01*
X542215Y7695D01*
Y7735D01*
X542210Y7780D01*
X542215Y7825D01*
Y7865D01*
X542220Y7910D01*
X542230Y7950D01*
X542235Y7990D01*
X542250Y8035D01*
X542260Y8075D01*
X542275Y8115D01*
X542295Y8155D01*
X542310Y8190D01*
X542330Y8230D01*
X542430Y8370D01*
X542460Y8400D01*
Y9530D01*
X542470Y9655D01*
X542510Y9780D01*
X542570Y9890D01*
X542650Y9990D01*
X542750Y10070D01*
X542860Y10130D01*
X542985Y10170D01*
X543110Y10180D01*
X543235Y10170D01*
X543360Y10130D01*
X543470Y10070D01*
X543570Y9990D01*
X543650Y9890D01*
X543710Y9780D01*
X543750Y9655D01*
X543760Y9530D01*
Y8400D01*
X543790Y8370D01*
X543890Y8230D01*
X543910Y8190D01*
X543925Y8155D01*
X543945Y8115D01*
X543960Y8075D01*
X543970Y8035D01*
X543985Y7990D01*
X543990Y7950D01*
X544000Y7910D01*
X544005Y7865D01*
Y7825D01*
X544010Y7780D01*
X544005Y7735D01*
Y7695D01*
X544000Y7650D01*
X543990Y7610D01*
X543985Y7570D01*
X543970Y7525D01*
X543960Y7485D01*
X543945Y7445D01*
X543925Y7405D01*
X543910Y7370D01*
X543890Y7330D01*
X543790Y7190D01*
X543760Y7160D01*
Y3730D01*
X543750Y3605D01*
X543710Y3480D01*
X543650Y3370D01*
X543570Y3270D01*
X543470Y3190D01*
X543360Y3130D01*
X543235Y3090D01*
X543110Y3080D01*
G37*
G36*
G01X571456D02*
X571331Y3090D01*
X571206Y3130D01*
X571096Y3190D01*
X570996Y3270D01*
X570916Y3370D01*
X570856Y3480D01*
X570816Y3605D01*
X570806Y3730D01*
Y7160D01*
X570776Y7190D01*
X570676Y7330D01*
X570656Y7370D01*
X570641Y7405D01*
X570621Y7445D01*
X570606Y7485D01*
X570596Y7525D01*
X570581Y7570D01*
X570576Y7610D01*
X570566Y7650D01*
X570561Y7695D01*
Y7735D01*
X570556Y7780D01*
X570561Y7825D01*
Y7865D01*
X570566Y7910D01*
X570576Y7950D01*
X570581Y7990D01*
X570596Y8035D01*
X570606Y8075D01*
X570621Y8115D01*
X570641Y8155D01*
X570656Y8190D01*
X570676Y8230D01*
X570776Y8370D01*
X570806Y8400D01*
Y9530D01*
X570816Y9655D01*
X570856Y9780D01*
X570916Y9890D01*
X570996Y9990D01*
X571096Y10070D01*
X571206Y10130D01*
X571331Y10170D01*
X571456Y10180D01*
X571581Y10170D01*
X571706Y10130D01*
X571816Y10070D01*
X571916Y9990D01*
X571996Y9890D01*
X572056Y9780D01*
X572096Y9655D01*
X572106Y9530D01*
Y8400D01*
X572136Y8370D01*
X572236Y8230D01*
X572256Y8190D01*
X572271Y8155D01*
X572291Y8115D01*
X572306Y8075D01*
X572316Y8035D01*
X572331Y7990D01*
X572336Y7950D01*
X572346Y7910D01*
X572351Y7865D01*
Y7825D01*
X572356Y7780D01*
X572351Y7735D01*
Y7695D01*
X572346Y7650D01*
X572336Y7610D01*
X572331Y7570D01*
X572316Y7525D01*
X572306Y7485D01*
X572291Y7445D01*
X572271Y7405D01*
X572256Y7370D01*
X572236Y7330D01*
X572136Y7190D01*
X572106Y7160D01*
Y3730D01*
X572096Y3605D01*
X572056Y3480D01*
X571996Y3370D01*
X571916Y3270D01*
X571816Y3190D01*
X571706Y3130D01*
X571581Y3090D01*
X571456Y3080D01*
G37*
G36*
G01X566732D02*
X566607Y3090D01*
X566482Y3130D01*
X566372Y3190D01*
X566272Y3270D01*
X566192Y3370D01*
X566132Y3480D01*
X566092Y3605D01*
X566082Y3730D01*
Y7160D01*
X566052Y7190D01*
X565952Y7330D01*
X565932Y7370D01*
X565917Y7405D01*
X565897Y7445D01*
X565882Y7485D01*
X565872Y7525D01*
X565857Y7570D01*
X565852Y7610D01*
X565842Y7650D01*
X565837Y7695D01*
Y7735D01*
X565832Y7780D01*
X565837Y7825D01*
Y7865D01*
X565842Y7910D01*
X565852Y7950D01*
X565857Y7990D01*
X565872Y8035D01*
X565882Y8075D01*
X565897Y8115D01*
X565917Y8155D01*
X565932Y8190D01*
X565952Y8230D01*
X566052Y8370D01*
X566082Y8400D01*
Y9530D01*
X566092Y9655D01*
X566132Y9780D01*
X566192Y9890D01*
X566272Y9990D01*
X566372Y10070D01*
X566482Y10130D01*
X566607Y10170D01*
X566732Y10180D01*
X566857Y10170D01*
X566982Y10130D01*
X567092Y10070D01*
X567192Y9990D01*
X567272Y9890D01*
X567332Y9780D01*
X567372Y9655D01*
X567382Y9530D01*
Y8400D01*
X567412Y8370D01*
X567512Y8230D01*
X567532Y8190D01*
X567547Y8155D01*
X567567Y8115D01*
X567582Y8075D01*
X567592Y8035D01*
X567607Y7990D01*
X567612Y7950D01*
X567622Y7910D01*
X567627Y7865D01*
Y7825D01*
X567632Y7780D01*
X567627Y7735D01*
Y7695D01*
X567622Y7650D01*
X567612Y7610D01*
X567607Y7570D01*
X567592Y7525D01*
X567582Y7485D01*
X567567Y7445D01*
X567547Y7405D01*
X567532Y7370D01*
X567512Y7330D01*
X567412Y7190D01*
X567382Y7160D01*
Y3730D01*
X567372Y3605D01*
X567332Y3480D01*
X567272Y3370D01*
X567192Y3270D01*
X567092Y3190D01*
X566982Y3130D01*
X566857Y3090D01*
X566732Y3080D01*
G37*
G36*
G01X562008D02*
X561883Y3090D01*
X561758Y3130D01*
X561648Y3190D01*
X561548Y3270D01*
X561468Y3370D01*
X561408Y3480D01*
X561368Y3605D01*
X561358Y3730D01*
Y7160D01*
X561328Y7190D01*
X561228Y7330D01*
X561208Y7370D01*
X561193Y7405D01*
X561173Y7445D01*
X561158Y7485D01*
X561148Y7525D01*
X561133Y7570D01*
X561128Y7610D01*
X561118Y7650D01*
X561113Y7695D01*
Y7735D01*
X561108Y7780D01*
X561113Y7825D01*
Y7865D01*
X561118Y7910D01*
X561128Y7950D01*
X561133Y7990D01*
X561148Y8035D01*
X561158Y8075D01*
X561173Y8115D01*
X561193Y8155D01*
X561208Y8190D01*
X561228Y8230D01*
X561328Y8370D01*
X561358Y8400D01*
Y9530D01*
X561368Y9655D01*
X561408Y9780D01*
X561468Y9890D01*
X561548Y9990D01*
X561648Y10070D01*
X561758Y10130D01*
X561883Y10170D01*
X562008Y10180D01*
X562133Y10170D01*
X562258Y10130D01*
X562368Y10070D01*
X562468Y9990D01*
X562548Y9890D01*
X562608Y9780D01*
X562648Y9655D01*
X562658Y9530D01*
Y8400D01*
X562688Y8370D01*
X562788Y8230D01*
X562808Y8190D01*
X562823Y8155D01*
X562843Y8115D01*
X562858Y8075D01*
X562868Y8035D01*
X562883Y7990D01*
X562888Y7950D01*
X562898Y7910D01*
X562903Y7865D01*
Y7825D01*
X562908Y7780D01*
X562903Y7735D01*
Y7695D01*
X562898Y7650D01*
X562888Y7610D01*
X562883Y7570D01*
X562868Y7525D01*
X562858Y7485D01*
X562843Y7445D01*
X562823Y7405D01*
X562808Y7370D01*
X562788Y7330D01*
X562688Y7190D01*
X562658Y7160D01*
Y3730D01*
X562648Y3605D01*
X562608Y3480D01*
X562548Y3370D01*
X562468Y3270D01*
X562368Y3190D01*
X562258Y3130D01*
X562133Y3090D01*
X562008Y3080D01*
G37*
G36*
G01X585630D02*
X585505Y3090D01*
X585380Y3130D01*
X585270Y3190D01*
X585170Y3270D01*
X585090Y3370D01*
X585030Y3480D01*
X584990Y3605D01*
X584980Y3730D01*
Y7160D01*
X584950Y7190D01*
X584850Y7330D01*
X584830Y7370D01*
X584815Y7405D01*
X584795Y7445D01*
X584780Y7485D01*
X584770Y7525D01*
X584755Y7570D01*
X584750Y7610D01*
X584740Y7650D01*
X584735Y7695D01*
Y7735D01*
X584730Y7780D01*
X584735Y7825D01*
Y7865D01*
X584740Y7910D01*
X584750Y7950D01*
X584755Y7990D01*
X584770Y8035D01*
X584780Y8075D01*
X584795Y8115D01*
X584815Y8155D01*
X584830Y8190D01*
X584850Y8230D01*
X584950Y8370D01*
X584980Y8400D01*
Y9530D01*
X584990Y9655D01*
X585030Y9780D01*
X585090Y9890D01*
X585170Y9990D01*
X585270Y10070D01*
X585380Y10130D01*
X585505Y10170D01*
X585630Y10180D01*
X585755Y10170D01*
X585880Y10130D01*
X585990Y10070D01*
X586090Y9990D01*
X586170Y9890D01*
X586230Y9780D01*
X586270Y9655D01*
X586280Y9530D01*
Y8400D01*
X586310Y8370D01*
X586410Y8230D01*
X586430Y8190D01*
X586445Y8155D01*
X586465Y8115D01*
X586480Y8075D01*
X586490Y8035D01*
X586505Y7990D01*
X586510Y7950D01*
X586520Y7910D01*
X586525Y7865D01*
Y7825D01*
X586530Y7780D01*
X586525Y7735D01*
Y7695D01*
X586520Y7650D01*
X586510Y7610D01*
X586505Y7570D01*
X586490Y7525D01*
X586480Y7485D01*
X586465Y7445D01*
X586445Y7405D01*
X586430Y7370D01*
X586410Y7330D01*
X586310Y7190D01*
X586280Y7160D01*
Y3730D01*
X586270Y3605D01*
X586230Y3480D01*
X586170Y3370D01*
X586090Y3270D01*
X585990Y3190D01*
X585880Y3130D01*
X585755Y3090D01*
X585630Y3080D01*
G37*
G36*
G01X580905D02*
X580780Y3090D01*
X580655Y3130D01*
X580545Y3190D01*
X580445Y3270D01*
X580365Y3370D01*
X580305Y3480D01*
X580265Y3605D01*
X580255Y3730D01*
Y7160D01*
X580225Y7190D01*
X580125Y7330D01*
X580105Y7370D01*
X580090Y7405D01*
X580070Y7445D01*
X580055Y7485D01*
X580045Y7525D01*
X580030Y7570D01*
X580025Y7610D01*
X580015Y7650D01*
X580010Y7695D01*
Y7735D01*
X580005Y7780D01*
X580010Y7825D01*
Y7865D01*
X580015Y7910D01*
X580025Y7950D01*
X580030Y7990D01*
X580045Y8035D01*
X580055Y8075D01*
X580070Y8115D01*
X580090Y8155D01*
X580105Y8190D01*
X580125Y8230D01*
X580225Y8370D01*
X580255Y8400D01*
Y9530D01*
X580265Y9655D01*
X580305Y9780D01*
X580365Y9890D01*
X580445Y9990D01*
X580545Y10070D01*
X580655Y10130D01*
X580780Y10170D01*
X580905Y10180D01*
X581030Y10170D01*
X581155Y10130D01*
X581265Y10070D01*
X581365Y9990D01*
X581445Y9890D01*
X581505Y9780D01*
X581545Y9655D01*
X581555Y9530D01*
Y8400D01*
X581585Y8370D01*
X581685Y8230D01*
X581705Y8190D01*
X581720Y8155D01*
X581740Y8115D01*
X581755Y8075D01*
X581765Y8035D01*
X581780Y7990D01*
X581785Y7950D01*
X581795Y7910D01*
X581800Y7865D01*
Y7825D01*
X581805Y7780D01*
X581800Y7735D01*
Y7695D01*
X581795Y7650D01*
X581785Y7610D01*
X581780Y7570D01*
X581765Y7525D01*
X581755Y7485D01*
X581740Y7445D01*
X581720Y7405D01*
X581705Y7370D01*
X581685Y7330D01*
X581585Y7190D01*
X581555Y7160D01*
Y3730D01*
X581545Y3605D01*
X581505Y3480D01*
X581445Y3370D01*
X581365Y3270D01*
X581265Y3190D01*
X581155Y3130D01*
X581030Y3090D01*
X580905Y3080D01*
G37*
G36*
G01X576181D02*
X576056Y3090D01*
X575931Y3130D01*
X575821Y3190D01*
X575721Y3270D01*
X575641Y3370D01*
X575581Y3480D01*
X575541Y3605D01*
X575531Y3730D01*
Y7160D01*
X575501Y7190D01*
X575401Y7330D01*
X575381Y7370D01*
X575366Y7405D01*
X575346Y7445D01*
X575331Y7485D01*
X575321Y7525D01*
X575306Y7570D01*
X575301Y7610D01*
X575291Y7650D01*
X575286Y7695D01*
Y7735D01*
X575281Y7780D01*
X575286Y7825D01*
Y7865D01*
X575291Y7910D01*
X575301Y7950D01*
X575306Y7990D01*
X575321Y8035D01*
X575331Y8075D01*
X575346Y8115D01*
X575366Y8155D01*
X575381Y8190D01*
X575401Y8230D01*
X575501Y8370D01*
X575531Y8400D01*
Y9530D01*
X575541Y9655D01*
X575581Y9780D01*
X575641Y9890D01*
X575721Y9990D01*
X575821Y10070D01*
X575931Y10130D01*
X576056Y10170D01*
X576181Y10180D01*
X576306Y10170D01*
X576431Y10130D01*
X576541Y10070D01*
X576641Y9990D01*
X576721Y9890D01*
X576781Y9780D01*
X576821Y9655D01*
X576831Y9530D01*
Y8400D01*
X576861Y8370D01*
X576961Y8230D01*
X576981Y8190D01*
X576996Y8155D01*
X577016Y8115D01*
X577031Y8075D01*
X577041Y8035D01*
X577056Y7990D01*
X577061Y7950D01*
X577071Y7910D01*
X577076Y7865D01*
Y7825D01*
X577081Y7780D01*
X577076Y7735D01*
Y7695D01*
X577071Y7650D01*
X577061Y7610D01*
X577056Y7570D01*
X577041Y7525D01*
X577031Y7485D01*
X577016Y7445D01*
X576996Y7405D01*
X576981Y7370D01*
X576961Y7330D01*
X576861Y7190D01*
X576831Y7160D01*
Y3730D01*
X576821Y3605D01*
X576781Y3480D01*
X576721Y3370D01*
X576641Y3270D01*
X576541Y3190D01*
X576431Y3130D01*
X576306Y3090D01*
X576181Y3080D01*
G37*
G36*
G01X599803D02*
X599678Y3090D01*
X599553Y3130D01*
X599443Y3190D01*
X599343Y3270D01*
X599263Y3370D01*
X599203Y3480D01*
X599163Y3605D01*
X599153Y3730D01*
Y7160D01*
X599123Y7190D01*
X599023Y7330D01*
X599003Y7370D01*
X598988Y7405D01*
X598968Y7445D01*
X598953Y7485D01*
X598943Y7525D01*
X598928Y7570D01*
X598923Y7610D01*
X598913Y7650D01*
X598908Y7695D01*
Y7735D01*
X598903Y7780D01*
X598908Y7825D01*
Y7865D01*
X598913Y7910D01*
X598923Y7950D01*
X598928Y7990D01*
X598943Y8035D01*
X598953Y8075D01*
X598968Y8115D01*
X598988Y8155D01*
X599003Y8190D01*
X599023Y8230D01*
X599123Y8370D01*
X599153Y8400D01*
Y9530D01*
X599163Y9655D01*
X599203Y9780D01*
X599263Y9890D01*
X599343Y9990D01*
X599443Y10070D01*
X599553Y10130D01*
X599678Y10170D01*
X599803Y10180D01*
X599928Y10170D01*
X600053Y10130D01*
X600163Y10070D01*
X600263Y9990D01*
X600343Y9890D01*
X600403Y9780D01*
X600443Y9655D01*
X600453Y9530D01*
Y8400D01*
X600483Y8370D01*
X600583Y8230D01*
X600603Y8190D01*
X600618Y8155D01*
X600638Y8115D01*
X600653Y8075D01*
X600663Y8035D01*
X600678Y7990D01*
X600683Y7950D01*
X600693Y7910D01*
X600698Y7865D01*
Y7825D01*
X600703Y7780D01*
X600698Y7735D01*
Y7695D01*
X600693Y7650D01*
X600683Y7610D01*
X600678Y7570D01*
X600663Y7525D01*
X600653Y7485D01*
X600638Y7445D01*
X600618Y7405D01*
X600603Y7370D01*
X600583Y7330D01*
X600483Y7190D01*
X600453Y7160D01*
Y3730D01*
X600443Y3605D01*
X600403Y3480D01*
X600343Y3370D01*
X600263Y3270D01*
X600163Y3190D01*
X600053Y3130D01*
X599928Y3090D01*
X599803Y3080D01*
G37*
G36*
G01X618701D02*
X618576Y3090D01*
X618451Y3130D01*
X618341Y3190D01*
X618241Y3270D01*
X618161Y3370D01*
X618101Y3480D01*
X618061Y3605D01*
X618051Y3730D01*
Y7160D01*
X618021Y7190D01*
X617921Y7330D01*
X617901Y7370D01*
X617886Y7405D01*
X617866Y7445D01*
X617851Y7485D01*
X617841Y7525D01*
X617826Y7570D01*
X617821Y7610D01*
X617811Y7650D01*
X617806Y7695D01*
Y7735D01*
X617801Y7780D01*
X617806Y7825D01*
Y7865D01*
X617811Y7910D01*
X617821Y7950D01*
X617826Y7990D01*
X617841Y8035D01*
X617851Y8075D01*
X617866Y8115D01*
X617886Y8155D01*
X617901Y8190D01*
X617921Y8230D01*
X618021Y8370D01*
X618051Y8400D01*
Y9530D01*
X618061Y9655D01*
X618101Y9780D01*
X618161Y9890D01*
X618241Y9990D01*
X618341Y10070D01*
X618451Y10130D01*
X618576Y10170D01*
X618701Y10180D01*
X618826Y10170D01*
X618951Y10130D01*
X619061Y10070D01*
X619161Y9990D01*
X619241Y9890D01*
X619301Y9780D01*
X619341Y9655D01*
X619351Y9530D01*
Y8400D01*
X619381Y8370D01*
X619481Y8230D01*
X619501Y8190D01*
X619516Y8155D01*
X619536Y8115D01*
X619551Y8075D01*
X619561Y8035D01*
X619576Y7990D01*
X619581Y7950D01*
X619591Y7910D01*
X619596Y7865D01*
Y7825D01*
X619601Y7780D01*
X619596Y7735D01*
Y7695D01*
X619591Y7650D01*
X619581Y7610D01*
X619576Y7570D01*
X619561Y7525D01*
X619551Y7485D01*
X619536Y7445D01*
X619516Y7405D01*
X619501Y7370D01*
X619481Y7330D01*
X619381Y7190D01*
X619351Y7160D01*
Y3730D01*
X619341Y3605D01*
X619301Y3480D01*
X619241Y3370D01*
X619161Y3270D01*
X619061Y3190D01*
X618951Y3130D01*
X618826Y3090D01*
X618701Y3080D01*
G37*
G36*
G01X613976D02*
X613851Y3090D01*
X613726Y3130D01*
X613616Y3190D01*
X613516Y3270D01*
X613436Y3370D01*
X613376Y3480D01*
X613336Y3605D01*
X613326Y3730D01*
Y7160D01*
X613296Y7190D01*
X613196Y7330D01*
X613176Y7370D01*
X613161Y7405D01*
X613141Y7445D01*
X613126Y7485D01*
X613116Y7525D01*
X613101Y7570D01*
X613096Y7610D01*
X613086Y7650D01*
X613081Y7695D01*
Y7735D01*
X613076Y7780D01*
X613081Y7825D01*
Y7865D01*
X613086Y7910D01*
X613096Y7950D01*
X613101Y7990D01*
X613116Y8035D01*
X613126Y8075D01*
X613141Y8115D01*
X613161Y8155D01*
X613176Y8190D01*
X613196Y8230D01*
X613296Y8370D01*
X613326Y8400D01*
Y9530D01*
X613336Y9655D01*
X613376Y9780D01*
X613436Y9890D01*
X613516Y9990D01*
X613616Y10070D01*
X613726Y10130D01*
X613851Y10170D01*
X613976Y10180D01*
X614101Y10170D01*
X614226Y10130D01*
X614336Y10070D01*
X614436Y9990D01*
X614516Y9890D01*
X614576Y9780D01*
X614616Y9655D01*
X614626Y9530D01*
Y8400D01*
X614656Y8370D01*
X614756Y8230D01*
X614776Y8190D01*
X614791Y8155D01*
X614811Y8115D01*
X614826Y8075D01*
X614836Y8035D01*
X614851Y7990D01*
X614856Y7950D01*
X614866Y7910D01*
X614871Y7865D01*
Y7825D01*
X614876Y7780D01*
X614871Y7735D01*
Y7695D01*
X614866Y7650D01*
X614856Y7610D01*
X614851Y7570D01*
X614836Y7525D01*
X614826Y7485D01*
X614811Y7445D01*
X614791Y7405D01*
X614776Y7370D01*
X614756Y7330D01*
X614656Y7190D01*
X614626Y7160D01*
Y3730D01*
X614616Y3605D01*
X614576Y3480D01*
X614516Y3370D01*
X614436Y3270D01*
X614336Y3190D01*
X614226Y3130D01*
X614101Y3090D01*
X613976Y3080D01*
G37*
G36*
G01X609252D02*
X609127Y3090D01*
X609002Y3130D01*
X608892Y3190D01*
X608792Y3270D01*
X608712Y3370D01*
X608652Y3480D01*
X608612Y3605D01*
X608602Y3730D01*
Y7160D01*
X608572Y7190D01*
X608472Y7330D01*
X608452Y7370D01*
X608437Y7405D01*
X608417Y7445D01*
X608402Y7485D01*
X608392Y7525D01*
X608377Y7570D01*
X608372Y7610D01*
X608362Y7650D01*
X608357Y7695D01*
Y7735D01*
X608352Y7780D01*
X608357Y7825D01*
Y7865D01*
X608362Y7910D01*
X608372Y7950D01*
X608377Y7990D01*
X608392Y8035D01*
X608402Y8075D01*
X608417Y8115D01*
X608437Y8155D01*
X608452Y8190D01*
X608472Y8230D01*
X608572Y8370D01*
X608602Y8400D01*
Y9530D01*
X608612Y9655D01*
X608652Y9780D01*
X608712Y9890D01*
X608792Y9990D01*
X608892Y10070D01*
X609002Y10130D01*
X609127Y10170D01*
X609252Y10180D01*
X609377Y10170D01*
X609502Y10130D01*
X609612Y10070D01*
X609712Y9990D01*
X609792Y9890D01*
X609852Y9780D01*
X609892Y9655D01*
X609902Y9530D01*
Y8400D01*
X609932Y8370D01*
X610032Y8230D01*
X610052Y8190D01*
X610067Y8155D01*
X610087Y8115D01*
X610102Y8075D01*
X610112Y8035D01*
X610127Y7990D01*
X610132Y7950D01*
X610142Y7910D01*
X610147Y7865D01*
Y7825D01*
X610152Y7780D01*
X610147Y7735D01*
Y7695D01*
X610142Y7650D01*
X610132Y7610D01*
X610127Y7570D01*
X610112Y7525D01*
X610102Y7485D01*
X610087Y7445D01*
X610067Y7405D01*
X610052Y7370D01*
X610032Y7330D01*
X609932Y7190D01*
X609902Y7160D01*
Y3730D01*
X609892Y3605D01*
X609852Y3480D01*
X609792Y3370D01*
X609712Y3270D01*
X609612Y3190D01*
X609502Y3130D01*
X609377Y3090D01*
X609252Y3080D01*
G37*
G36*
G01X604527D02*
X604402Y3090D01*
X604277Y3130D01*
X604167Y3190D01*
X604067Y3270D01*
X603987Y3370D01*
X603927Y3480D01*
X603887Y3605D01*
X603877Y3730D01*
Y7160D01*
X603847Y7190D01*
X603747Y7330D01*
X603727Y7370D01*
X603712Y7405D01*
X603692Y7445D01*
X603677Y7485D01*
X603667Y7525D01*
X603652Y7570D01*
X603647Y7610D01*
X603637Y7650D01*
X603632Y7695D01*
Y7735D01*
X603627Y7780D01*
X603632Y7825D01*
Y7865D01*
X603637Y7910D01*
X603647Y7950D01*
X603652Y7990D01*
X603667Y8035D01*
X603677Y8075D01*
X603692Y8115D01*
X603712Y8155D01*
X603727Y8190D01*
X603747Y8230D01*
X603847Y8370D01*
X603877Y8400D01*
Y9530D01*
X603887Y9655D01*
X603927Y9780D01*
X603987Y9890D01*
X604067Y9990D01*
X604167Y10070D01*
X604277Y10130D01*
X604402Y10170D01*
X604527Y10180D01*
X604652Y10170D01*
X604777Y10130D01*
X604887Y10070D01*
X604987Y9990D01*
X605067Y9890D01*
X605127Y9780D01*
X605167Y9655D01*
X605177Y9530D01*
Y8400D01*
X605207Y8370D01*
X605307Y8230D01*
X605327Y8190D01*
X605342Y8155D01*
X605362Y8115D01*
X605377Y8075D01*
X605387Y8035D01*
X605402Y7990D01*
X605407Y7950D01*
X605417Y7910D01*
X605422Y7865D01*
Y7825D01*
X605427Y7780D01*
X605422Y7735D01*
Y7695D01*
X605417Y7650D01*
X605407Y7610D01*
X605402Y7570D01*
X605387Y7525D01*
X605377Y7485D01*
X605362Y7445D01*
X605342Y7405D01*
X605327Y7370D01*
X605307Y7330D01*
X605207Y7190D01*
X605177Y7160D01*
Y3730D01*
X605167Y3605D01*
X605127Y3480D01*
X605067Y3370D01*
X604987Y3270D01*
X604887Y3190D01*
X604777Y3130D01*
X604652Y3090D01*
X604527Y3080D01*
G37*
G36*
G01X632874D02*
X632749Y3090D01*
X632624Y3130D01*
X632514Y3190D01*
X632414Y3270D01*
X632334Y3370D01*
X632274Y3480D01*
X632234Y3605D01*
X632224Y3730D01*
Y7160D01*
X632194Y7190D01*
X632094Y7330D01*
X632074Y7370D01*
X632059Y7405D01*
X632039Y7445D01*
X632024Y7485D01*
X632014Y7525D01*
X631999Y7570D01*
X631994Y7610D01*
X631984Y7650D01*
X631979Y7695D01*
Y7735D01*
X631974Y7780D01*
X631979Y7825D01*
Y7865D01*
X631984Y7910D01*
X631994Y7950D01*
X631999Y7990D01*
X632014Y8035D01*
X632024Y8075D01*
X632039Y8115D01*
X632059Y8155D01*
X632074Y8190D01*
X632094Y8230D01*
X632194Y8370D01*
X632224Y8400D01*
Y9530D01*
X632234Y9655D01*
X632274Y9780D01*
X632334Y9890D01*
X632414Y9990D01*
X632514Y10070D01*
X632624Y10130D01*
X632749Y10170D01*
X632874Y10180D01*
X632999Y10170D01*
X633124Y10130D01*
X633234Y10070D01*
X633334Y9990D01*
X633414Y9890D01*
X633474Y9780D01*
X633514Y9655D01*
X633524Y9530D01*
Y8400D01*
X633554Y8370D01*
X633654Y8230D01*
X633674Y8190D01*
X633689Y8155D01*
X633709Y8115D01*
X633724Y8075D01*
X633734Y8035D01*
X633749Y7990D01*
X633754Y7950D01*
X633764Y7910D01*
X633769Y7865D01*
Y7825D01*
X633774Y7780D01*
X633769Y7735D01*
Y7695D01*
X633764Y7650D01*
X633754Y7610D01*
X633749Y7570D01*
X633734Y7525D01*
X633724Y7485D01*
X633709Y7445D01*
X633689Y7405D01*
X633674Y7370D01*
X633654Y7330D01*
X633554Y7190D01*
X633524Y7160D01*
Y3730D01*
X633514Y3605D01*
X633474Y3480D01*
X633414Y3370D01*
X633334Y3270D01*
X633234Y3190D01*
X633124Y3130D01*
X632999Y3090D01*
X632874Y3080D01*
G37*
G36*
G01X628149D02*
X628024Y3090D01*
X627899Y3130D01*
X627789Y3190D01*
X627689Y3270D01*
X627609Y3370D01*
X627549Y3480D01*
X627509Y3605D01*
X627499Y3730D01*
Y7160D01*
X627469Y7190D01*
X627369Y7330D01*
X627349Y7370D01*
X627334Y7405D01*
X627314Y7445D01*
X627299Y7485D01*
X627289Y7525D01*
X627274Y7570D01*
X627269Y7610D01*
X627259Y7650D01*
X627254Y7695D01*
Y7735D01*
X627249Y7780D01*
X627254Y7825D01*
Y7865D01*
X627259Y7910D01*
X627269Y7950D01*
X627274Y7990D01*
X627289Y8035D01*
X627299Y8075D01*
X627314Y8115D01*
X627334Y8155D01*
X627349Y8190D01*
X627369Y8230D01*
X627469Y8370D01*
X627499Y8400D01*
Y9530D01*
X627509Y9655D01*
X627549Y9780D01*
X627609Y9890D01*
X627689Y9990D01*
X627789Y10070D01*
X627899Y10130D01*
X628024Y10170D01*
X628149Y10180D01*
X628274Y10170D01*
X628399Y10130D01*
X628509Y10070D01*
X628609Y9990D01*
X628689Y9890D01*
X628749Y9780D01*
X628789Y9655D01*
X628799Y9530D01*
Y8400D01*
X628829Y8370D01*
X628929Y8230D01*
X628949Y8190D01*
X628964Y8155D01*
X628984Y8115D01*
X628999Y8075D01*
X629009Y8035D01*
X629024Y7990D01*
X629029Y7950D01*
X629039Y7910D01*
X629044Y7865D01*
Y7825D01*
X629049Y7780D01*
X629044Y7735D01*
Y7695D01*
X629039Y7650D01*
X629029Y7610D01*
X629024Y7570D01*
X629009Y7525D01*
X628999Y7485D01*
X628984Y7445D01*
X628964Y7405D01*
X628949Y7370D01*
X628929Y7330D01*
X628829Y7190D01*
X628799Y7160D01*
Y3730D01*
X628789Y3605D01*
X628749Y3480D01*
X628689Y3370D01*
X628609Y3270D01*
X628509Y3190D01*
X628399Y3130D01*
X628274Y3090D01*
X628149Y3080D01*
G37*
G36*
G01X623425D02*
X623300Y3090D01*
X623175Y3130D01*
X623065Y3190D01*
X622965Y3270D01*
X622885Y3370D01*
X622825Y3480D01*
X622785Y3605D01*
X622775Y3730D01*
Y7160D01*
X622745Y7190D01*
X622645Y7330D01*
X622625Y7370D01*
X622610Y7405D01*
X622590Y7445D01*
X622575Y7485D01*
X622565Y7525D01*
X622550Y7570D01*
X622545Y7610D01*
X622535Y7650D01*
X622530Y7695D01*
Y7735D01*
X622525Y7780D01*
X622530Y7825D01*
Y7865D01*
X622535Y7910D01*
X622545Y7950D01*
X622550Y7990D01*
X622565Y8035D01*
X622575Y8075D01*
X622590Y8115D01*
X622610Y8155D01*
X622625Y8190D01*
X622645Y8230D01*
X622745Y8370D01*
X622775Y8400D01*
Y9530D01*
X622785Y9655D01*
X622825Y9780D01*
X622885Y9890D01*
X622965Y9990D01*
X623065Y10070D01*
X623175Y10130D01*
X623300Y10170D01*
X623425Y10180D01*
X623550Y10170D01*
X623675Y10130D01*
X623785Y10070D01*
X623885Y9990D01*
X623965Y9890D01*
X624025Y9780D01*
X624065Y9655D01*
X624075Y9530D01*
Y8400D01*
X624105Y8370D01*
X624205Y8230D01*
X624225Y8190D01*
X624240Y8155D01*
X624260Y8115D01*
X624275Y8075D01*
X624285Y8035D01*
X624300Y7990D01*
X624305Y7950D01*
X624315Y7910D01*
X624320Y7865D01*
Y7825D01*
X624325Y7780D01*
X624320Y7735D01*
Y7695D01*
X624315Y7650D01*
X624305Y7610D01*
X624300Y7570D01*
X624285Y7525D01*
X624275Y7485D01*
X624260Y7445D01*
X624240Y7405D01*
X624225Y7370D01*
X624205Y7330D01*
X624105Y7190D01*
X624075Y7160D01*
Y3730D01*
X624065Y3605D01*
X624025Y3480D01*
X623965Y3370D01*
X623885Y3270D01*
X623785Y3190D01*
X623675Y3130D01*
X623550Y3090D01*
X623425Y3080D01*
G37*
G36*
G01X647047D02*
X646922Y3090D01*
X646797Y3130D01*
X646687Y3190D01*
X646587Y3270D01*
X646507Y3370D01*
X646447Y3480D01*
X646407Y3605D01*
X646397Y3730D01*
Y7160D01*
X646367Y7190D01*
X646267Y7330D01*
X646247Y7370D01*
X646232Y7405D01*
X646212Y7445D01*
X646197Y7485D01*
X646187Y7525D01*
X646172Y7570D01*
X646167Y7610D01*
X646157Y7650D01*
X646152Y7695D01*
Y7735D01*
X646147Y7780D01*
X646152Y7825D01*
Y7865D01*
X646157Y7910D01*
X646167Y7950D01*
X646172Y7990D01*
X646187Y8035D01*
X646197Y8075D01*
X646212Y8115D01*
X646232Y8155D01*
X646247Y8190D01*
X646267Y8230D01*
X646367Y8370D01*
X646397Y8400D01*
Y9530D01*
X646407Y9655D01*
X646447Y9780D01*
X646507Y9890D01*
X646587Y9990D01*
X646687Y10070D01*
X646797Y10130D01*
X646922Y10170D01*
X647047Y10180D01*
X647172Y10170D01*
X647297Y10130D01*
X647407Y10070D01*
X647507Y9990D01*
X647587Y9890D01*
X647647Y9780D01*
X647687Y9655D01*
X647697Y9530D01*
Y8400D01*
X647727Y8370D01*
X647827Y8230D01*
X647847Y8190D01*
X647862Y8155D01*
X647882Y8115D01*
X647897Y8075D01*
X647907Y8035D01*
X647922Y7990D01*
X647927Y7950D01*
X647937Y7910D01*
X647942Y7865D01*
Y7825D01*
X647947Y7780D01*
X647942Y7735D01*
Y7695D01*
X647937Y7650D01*
X647927Y7610D01*
X647922Y7570D01*
X647907Y7525D01*
X647897Y7485D01*
X647882Y7445D01*
X647862Y7405D01*
X647847Y7370D01*
X647827Y7330D01*
X647727Y7190D01*
X647697Y7160D01*
Y3730D01*
X647687Y3605D01*
X647647Y3480D01*
X647587Y3370D01*
X647507Y3270D01*
X647407Y3190D01*
X647297Y3130D01*
X647172Y3090D01*
X647047Y3080D01*
G37*
G36*
G01X642323D02*
X642198Y3090D01*
X642073Y3130D01*
X641963Y3190D01*
X641863Y3270D01*
X641783Y3370D01*
X641723Y3480D01*
X641683Y3605D01*
X641673Y3730D01*
Y7160D01*
X641643Y7190D01*
X641543Y7330D01*
X641523Y7370D01*
X641508Y7405D01*
X641488Y7445D01*
X641473Y7485D01*
X641463Y7525D01*
X641448Y7570D01*
X641443Y7610D01*
X641433Y7650D01*
X641428Y7695D01*
Y7735D01*
X641423Y7780D01*
X641428Y7825D01*
Y7865D01*
X641433Y7910D01*
X641443Y7950D01*
X641448Y7990D01*
X641463Y8035D01*
X641473Y8075D01*
X641488Y8115D01*
X641508Y8155D01*
X641523Y8190D01*
X641543Y8230D01*
X641643Y8370D01*
X641673Y8400D01*
Y9530D01*
X641683Y9655D01*
X641723Y9780D01*
X641783Y9890D01*
X641863Y9990D01*
X641963Y10070D01*
X642073Y10130D01*
X642198Y10170D01*
X642323Y10180D01*
X642448Y10170D01*
X642573Y10130D01*
X642683Y10070D01*
X642783Y9990D01*
X642863Y9890D01*
X642923Y9780D01*
X642963Y9655D01*
X642973Y9530D01*
Y8400D01*
X643003Y8370D01*
X643103Y8230D01*
X643123Y8190D01*
X643138Y8155D01*
X643158Y8115D01*
X643173Y8075D01*
X643183Y8035D01*
X643198Y7990D01*
X643203Y7950D01*
X643213Y7910D01*
X643218Y7865D01*
Y7825D01*
X643223Y7780D01*
X643218Y7735D01*
Y7695D01*
X643213Y7650D01*
X643203Y7610D01*
X643198Y7570D01*
X643183Y7525D01*
X643173Y7485D01*
X643158Y7445D01*
X643138Y7405D01*
X643123Y7370D01*
X643103Y7330D01*
X643003Y7190D01*
X642973Y7160D01*
Y3730D01*
X642963Y3605D01*
X642923Y3480D01*
X642863Y3370D01*
X642783Y3270D01*
X642683Y3190D01*
X642573Y3130D01*
X642448Y3090D01*
X642323Y3080D01*
G37*
G36*
G01X637598D02*
X637473Y3090D01*
X637348Y3130D01*
X637238Y3190D01*
X637138Y3270D01*
X637058Y3370D01*
X636998Y3480D01*
X636958Y3605D01*
X636948Y3730D01*
Y7160D01*
X636918Y7190D01*
X636818Y7330D01*
X636798Y7370D01*
X636783Y7405D01*
X636763Y7445D01*
X636748Y7485D01*
X636738Y7525D01*
X636723Y7570D01*
X636718Y7610D01*
X636708Y7650D01*
X636703Y7695D01*
Y7735D01*
X636698Y7780D01*
X636703Y7825D01*
Y7865D01*
X636708Y7910D01*
X636718Y7950D01*
X636723Y7990D01*
X636738Y8035D01*
X636748Y8075D01*
X636763Y8115D01*
X636783Y8155D01*
X636798Y8190D01*
X636818Y8230D01*
X636918Y8370D01*
X636948Y8400D01*
Y9530D01*
X636958Y9655D01*
X636998Y9780D01*
X637058Y9890D01*
X637138Y9990D01*
X637238Y10070D01*
X637348Y10130D01*
X637473Y10170D01*
X637598Y10180D01*
X637723Y10170D01*
X637848Y10130D01*
X637958Y10070D01*
X638058Y9990D01*
X638138Y9890D01*
X638198Y9780D01*
X638238Y9655D01*
X638248Y9530D01*
Y8400D01*
X638278Y8370D01*
X638378Y8230D01*
X638398Y8190D01*
X638413Y8155D01*
X638433Y8115D01*
X638448Y8075D01*
X638458Y8035D01*
X638473Y7990D01*
X638478Y7950D01*
X638488Y7910D01*
X638493Y7865D01*
Y7825D01*
X638498Y7780D01*
X638493Y7735D01*
Y7695D01*
X638488Y7650D01*
X638478Y7610D01*
X638473Y7570D01*
X638458Y7525D01*
X638448Y7485D01*
X638433Y7445D01*
X638413Y7405D01*
X638398Y7370D01*
X638378Y7330D01*
X638278Y7190D01*
X638248Y7160D01*
Y3730D01*
X638238Y3605D01*
X638198Y3480D01*
X638138Y3370D01*
X638058Y3270D01*
X637958Y3190D01*
X637848Y3130D01*
X637723Y3090D01*
X637598Y3080D01*
G37*
G36*
G01X661220D02*
X661095Y3090D01*
X660970Y3130D01*
X660860Y3190D01*
X660760Y3270D01*
X660680Y3370D01*
X660620Y3480D01*
X660580Y3605D01*
X660570Y3730D01*
Y7160D01*
X660540Y7190D01*
X660440Y7330D01*
X660420Y7370D01*
X660405Y7405D01*
X660385Y7445D01*
X660370Y7485D01*
X660360Y7525D01*
X660345Y7570D01*
X660340Y7610D01*
X660330Y7650D01*
X660325Y7695D01*
Y7735D01*
X660320Y7780D01*
X660325Y7825D01*
Y7865D01*
X660330Y7910D01*
X660340Y7950D01*
X660345Y7990D01*
X660360Y8035D01*
X660370Y8075D01*
X660385Y8115D01*
X660405Y8155D01*
X660420Y8190D01*
X660440Y8230D01*
X660540Y8370D01*
X660570Y8400D01*
Y9530D01*
X660580Y9655D01*
X660620Y9780D01*
X660680Y9890D01*
X660760Y9990D01*
X660860Y10070D01*
X660970Y10130D01*
X661095Y10170D01*
X661220Y10180D01*
X661345Y10170D01*
X661470Y10130D01*
X661580Y10070D01*
X661680Y9990D01*
X661760Y9890D01*
X661820Y9780D01*
X661860Y9655D01*
X661870Y9530D01*
Y8400D01*
X661900Y8370D01*
X662000Y8230D01*
X662020Y8190D01*
X662035Y8155D01*
X662055Y8115D01*
X662070Y8075D01*
X662080Y8035D01*
X662095Y7990D01*
X662100Y7950D01*
X662110Y7910D01*
X662115Y7865D01*
Y7825D01*
X662120Y7780D01*
X662115Y7735D01*
Y7695D01*
X662110Y7650D01*
X662100Y7610D01*
X662095Y7570D01*
X662080Y7525D01*
X662070Y7485D01*
X662055Y7445D01*
X662035Y7405D01*
X662020Y7370D01*
X662000Y7330D01*
X661900Y7190D01*
X661870Y7160D01*
Y3730D01*
X661860Y3605D01*
X661820Y3480D01*
X661760Y3370D01*
X661680Y3270D01*
X661580Y3190D01*
X661470Y3130D01*
X661345Y3090D01*
X661220Y3080D01*
G37*
G36*
G01X656496D02*
X656371Y3090D01*
X656246Y3130D01*
X656136Y3190D01*
X656036Y3270D01*
X655956Y3370D01*
X655896Y3480D01*
X655856Y3605D01*
X655846Y3730D01*
Y7160D01*
X655816Y7190D01*
X655716Y7330D01*
X655696Y7370D01*
X655681Y7405D01*
X655661Y7445D01*
X655646Y7485D01*
X655636Y7525D01*
X655621Y7570D01*
X655616Y7610D01*
X655606Y7650D01*
X655601Y7695D01*
Y7735D01*
X655596Y7780D01*
X655601Y7825D01*
Y7865D01*
X655606Y7910D01*
X655616Y7950D01*
X655621Y7990D01*
X655636Y8035D01*
X655646Y8075D01*
X655661Y8115D01*
X655681Y8155D01*
X655696Y8190D01*
X655716Y8230D01*
X655816Y8370D01*
X655846Y8400D01*
Y9530D01*
X655856Y9655D01*
X655896Y9780D01*
X655956Y9890D01*
X656036Y9990D01*
X656136Y10070D01*
X656246Y10130D01*
X656371Y10170D01*
X656496Y10180D01*
X656621Y10170D01*
X656746Y10130D01*
X656856Y10070D01*
X656956Y9990D01*
X657036Y9890D01*
X657096Y9780D01*
X657136Y9655D01*
X657146Y9530D01*
Y8400D01*
X657176Y8370D01*
X657276Y8230D01*
X657296Y8190D01*
X657311Y8155D01*
X657331Y8115D01*
X657346Y8075D01*
X657356Y8035D01*
X657371Y7990D01*
X657376Y7950D01*
X657386Y7910D01*
X657391Y7865D01*
Y7825D01*
X657396Y7780D01*
X657391Y7735D01*
Y7695D01*
X657386Y7650D01*
X657376Y7610D01*
X657371Y7570D01*
X657356Y7525D01*
X657346Y7485D01*
X657331Y7445D01*
X657311Y7405D01*
X657296Y7370D01*
X657276Y7330D01*
X657176Y7190D01*
X657146Y7160D01*
Y3730D01*
X657136Y3605D01*
X657096Y3480D01*
X657036Y3370D01*
X656956Y3270D01*
X656856Y3190D01*
X656746Y3130D01*
X656621Y3090D01*
X656496Y3080D01*
G37*
G36*
G01X651771D02*
X651646Y3090D01*
X651521Y3130D01*
X651411Y3190D01*
X651311Y3270D01*
X651231Y3370D01*
X651171Y3480D01*
X651131Y3605D01*
X651121Y3730D01*
Y7160D01*
X651091Y7190D01*
X650991Y7330D01*
X650971Y7370D01*
X650956Y7405D01*
X650936Y7445D01*
X650921Y7485D01*
X650911Y7525D01*
X650896Y7570D01*
X650891Y7610D01*
X650881Y7650D01*
X650876Y7695D01*
Y7735D01*
X650871Y7780D01*
X650876Y7825D01*
Y7865D01*
X650881Y7910D01*
X650891Y7950D01*
X650896Y7990D01*
X650911Y8035D01*
X650921Y8075D01*
X650936Y8115D01*
X650956Y8155D01*
X650971Y8190D01*
X650991Y8230D01*
X651091Y8370D01*
X651121Y8400D01*
Y9530D01*
X651131Y9655D01*
X651171Y9780D01*
X651231Y9890D01*
X651311Y9990D01*
X651411Y10070D01*
X651521Y10130D01*
X651646Y10170D01*
X651771Y10180D01*
X651896Y10170D01*
X652021Y10130D01*
X652131Y10070D01*
X652231Y9990D01*
X652311Y9890D01*
X652371Y9780D01*
X652411Y9655D01*
X652421Y9530D01*
Y8400D01*
X652451Y8370D01*
X652551Y8230D01*
X652571Y8190D01*
X652586Y8155D01*
X652606Y8115D01*
X652621Y8075D01*
X652631Y8035D01*
X652646Y7990D01*
X652651Y7950D01*
X652661Y7910D01*
X652666Y7865D01*
Y7825D01*
X652671Y7780D01*
X652666Y7735D01*
Y7695D01*
X652661Y7650D01*
X652651Y7610D01*
X652646Y7570D01*
X652631Y7525D01*
X652621Y7485D01*
X652606Y7445D01*
X652586Y7405D01*
X652571Y7370D01*
X652551Y7330D01*
X652451Y7190D01*
X652421Y7160D01*
Y3730D01*
X652411Y3605D01*
X652371Y3480D01*
X652311Y3370D01*
X652231Y3270D01*
X652131Y3190D01*
X652021Y3130D01*
X651896Y3090D01*
X651771Y3080D01*
G37*
G36*
G01X680118D02*
X679993Y3090D01*
X679868Y3130D01*
X679758Y3190D01*
X679658Y3270D01*
X679578Y3370D01*
X679518Y3480D01*
X679478Y3605D01*
X679468Y3730D01*
Y7160D01*
X679438Y7190D01*
X679338Y7330D01*
X679318Y7370D01*
X679303Y7405D01*
X679283Y7445D01*
X679268Y7485D01*
X679258Y7525D01*
X679243Y7570D01*
X679238Y7610D01*
X679228Y7650D01*
X679223Y7695D01*
Y7735D01*
X679218Y7780D01*
X679223Y7825D01*
Y7865D01*
X679228Y7910D01*
X679238Y7950D01*
X679243Y7990D01*
X679258Y8035D01*
X679268Y8075D01*
X679283Y8115D01*
X679303Y8155D01*
X679318Y8190D01*
X679338Y8230D01*
X679438Y8370D01*
X679468Y8400D01*
Y9530D01*
X679478Y9655D01*
X679518Y9780D01*
X679578Y9890D01*
X679658Y9990D01*
X679758Y10070D01*
X679868Y10130D01*
X679993Y10170D01*
X680118Y10180D01*
X680243Y10170D01*
X680368Y10130D01*
X680478Y10070D01*
X680578Y9990D01*
X680658Y9890D01*
X680718Y9780D01*
X680758Y9655D01*
X680768Y9530D01*
Y8400D01*
X680798Y8370D01*
X680898Y8230D01*
X680918Y8190D01*
X680933Y8155D01*
X680953Y8115D01*
X680968Y8075D01*
X680978Y8035D01*
X680993Y7990D01*
X680998Y7950D01*
X681008Y7910D01*
X681013Y7865D01*
Y7825D01*
X681018Y7780D01*
X681013Y7735D01*
Y7695D01*
X681008Y7650D01*
X680998Y7610D01*
X680993Y7570D01*
X680978Y7525D01*
X680968Y7485D01*
X680953Y7445D01*
X680933Y7405D01*
X680918Y7370D01*
X680898Y7330D01*
X680798Y7190D01*
X680768Y7160D01*
Y3730D01*
X680758Y3605D01*
X680718Y3480D01*
X680658Y3370D01*
X680578Y3270D01*
X680478Y3190D01*
X680368Y3130D01*
X680243Y3090D01*
X680118Y3080D01*
G37*
G36*
G01X675393D02*
X675268Y3090D01*
X675143Y3130D01*
X675033Y3190D01*
X674933Y3270D01*
X674853Y3370D01*
X674793Y3480D01*
X674753Y3605D01*
X674743Y3730D01*
Y7160D01*
X674713Y7190D01*
X674613Y7330D01*
X674593Y7370D01*
X674578Y7405D01*
X674558Y7445D01*
X674543Y7485D01*
X674533Y7525D01*
X674518Y7570D01*
X674513Y7610D01*
X674503Y7650D01*
X674498Y7695D01*
Y7735D01*
X674493Y7780D01*
X674498Y7825D01*
Y7865D01*
X674503Y7910D01*
X674513Y7950D01*
X674518Y7990D01*
X674533Y8035D01*
X674543Y8075D01*
X674558Y8115D01*
X674578Y8155D01*
X674593Y8190D01*
X674613Y8230D01*
X674713Y8370D01*
X674743Y8400D01*
Y9530D01*
X674753Y9655D01*
X674793Y9780D01*
X674853Y9890D01*
X674933Y9990D01*
X675033Y10070D01*
X675143Y10130D01*
X675268Y10170D01*
X675393Y10180D01*
X675518Y10170D01*
X675643Y10130D01*
X675753Y10070D01*
X675853Y9990D01*
X675933Y9890D01*
X675993Y9780D01*
X676033Y9655D01*
X676043Y9530D01*
Y8400D01*
X676073Y8370D01*
X676173Y8230D01*
X676193Y8190D01*
X676208Y8155D01*
X676228Y8115D01*
X676243Y8075D01*
X676253Y8035D01*
X676268Y7990D01*
X676273Y7950D01*
X676283Y7910D01*
X676288Y7865D01*
Y7825D01*
X676293Y7780D01*
X676288Y7735D01*
Y7695D01*
X676283Y7650D01*
X676273Y7610D01*
X676268Y7570D01*
X676253Y7525D01*
X676243Y7485D01*
X676228Y7445D01*
X676208Y7405D01*
X676193Y7370D01*
X676173Y7330D01*
X676073Y7190D01*
X676043Y7160D01*
Y3730D01*
X676033Y3605D01*
X675993Y3480D01*
X675933Y3370D01*
X675853Y3270D01*
X675753Y3190D01*
X675643Y3130D01*
X675518Y3090D01*
X675393Y3080D01*
G37*
G36*
G01X670669D02*
X670544Y3090D01*
X670419Y3130D01*
X670309Y3190D01*
X670209Y3270D01*
X670129Y3370D01*
X670069Y3480D01*
X670029Y3605D01*
X670019Y3730D01*
Y7160D01*
X669989Y7190D01*
X669889Y7330D01*
X669869Y7370D01*
X669854Y7405D01*
X669834Y7445D01*
X669819Y7485D01*
X669809Y7525D01*
X669794Y7570D01*
X669789Y7610D01*
X669779Y7650D01*
X669774Y7695D01*
Y7735D01*
X669769Y7780D01*
X669774Y7825D01*
Y7865D01*
X669779Y7910D01*
X669789Y7950D01*
X669794Y7990D01*
X669809Y8035D01*
X669819Y8075D01*
X669834Y8115D01*
X669854Y8155D01*
X669869Y8190D01*
X669889Y8230D01*
X669989Y8370D01*
X670019Y8400D01*
Y9530D01*
X670029Y9655D01*
X670069Y9780D01*
X670129Y9890D01*
X670209Y9990D01*
X670309Y10070D01*
X670419Y10130D01*
X670544Y10170D01*
X670669Y10180D01*
X670794Y10170D01*
X670919Y10130D01*
X671029Y10070D01*
X671129Y9990D01*
X671209Y9890D01*
X671269Y9780D01*
X671309Y9655D01*
X671319Y9530D01*
Y8400D01*
X671349Y8370D01*
X671449Y8230D01*
X671469Y8190D01*
X671484Y8155D01*
X671504Y8115D01*
X671519Y8075D01*
X671529Y8035D01*
X671544Y7990D01*
X671549Y7950D01*
X671559Y7910D01*
X671564Y7865D01*
Y7825D01*
X671569Y7780D01*
X671564Y7735D01*
Y7695D01*
X671559Y7650D01*
X671549Y7610D01*
X671544Y7570D01*
X671529Y7525D01*
X671519Y7485D01*
X671504Y7445D01*
X671484Y7405D01*
X671469Y7370D01*
X671449Y7330D01*
X671349Y7190D01*
X671319Y7160D01*
Y3730D01*
X671309Y3605D01*
X671269Y3480D01*
X671209Y3370D01*
X671129Y3270D01*
X671029Y3190D01*
X670919Y3130D01*
X670794Y3090D01*
X670669Y3080D01*
G37*
G36*
G01X665945D02*
X665820Y3090D01*
X665695Y3130D01*
X665585Y3190D01*
X665485Y3270D01*
X665405Y3370D01*
X665345Y3480D01*
X665305Y3605D01*
X665295Y3730D01*
Y7160D01*
X665265Y7190D01*
X665165Y7330D01*
X665145Y7370D01*
X665130Y7405D01*
X665110Y7445D01*
X665095Y7485D01*
X665085Y7525D01*
X665070Y7570D01*
X665065Y7610D01*
X665055Y7650D01*
X665050Y7695D01*
Y7735D01*
X665045Y7780D01*
X665050Y7825D01*
Y7865D01*
X665055Y7910D01*
X665065Y7950D01*
X665070Y7990D01*
X665085Y8035D01*
X665095Y8075D01*
X665110Y8115D01*
X665130Y8155D01*
X665145Y8190D01*
X665165Y8230D01*
X665265Y8370D01*
X665295Y8400D01*
Y9530D01*
X665305Y9655D01*
X665345Y9780D01*
X665405Y9890D01*
X665485Y9990D01*
X665585Y10070D01*
X665695Y10130D01*
X665820Y10170D01*
X665945Y10180D01*
X666070Y10170D01*
X666195Y10130D01*
X666305Y10070D01*
X666405Y9990D01*
X666485Y9890D01*
X666545Y9780D01*
X666585Y9655D01*
X666595Y9530D01*
Y8400D01*
X666625Y8370D01*
X666725Y8230D01*
X666745Y8190D01*
X666760Y8155D01*
X666780Y8115D01*
X666795Y8075D01*
X666805Y8035D01*
X666820Y7990D01*
X666825Y7950D01*
X666835Y7910D01*
X666840Y7865D01*
Y7825D01*
X666845Y7780D01*
X666840Y7735D01*
Y7695D01*
X666835Y7650D01*
X666825Y7610D01*
X666820Y7570D01*
X666805Y7525D01*
X666795Y7485D01*
X666780Y7445D01*
X666760Y7405D01*
X666745Y7370D01*
X666725Y7330D01*
X666625Y7190D01*
X666595Y7160D01*
Y3730D01*
X666585Y3605D01*
X666545Y3480D01*
X666485Y3370D01*
X666405Y3270D01*
X666305Y3190D01*
X666195Y3130D01*
X666070Y3090D01*
X665945Y3080D01*
G37*
G36*
G01X694291D02*
X694166Y3090D01*
X694041Y3130D01*
X693931Y3190D01*
X693831Y3270D01*
X693751Y3370D01*
X693691Y3480D01*
X693651Y3605D01*
X693641Y3730D01*
Y7160D01*
X693611Y7190D01*
X693511Y7330D01*
X693491Y7370D01*
X693476Y7405D01*
X693456Y7445D01*
X693441Y7485D01*
X693431Y7525D01*
X693416Y7570D01*
X693411Y7610D01*
X693401Y7650D01*
X693396Y7695D01*
Y7735D01*
X693391Y7780D01*
X693396Y7825D01*
Y7865D01*
X693401Y7910D01*
X693411Y7950D01*
X693416Y7990D01*
X693431Y8035D01*
X693441Y8075D01*
X693456Y8115D01*
X693476Y8155D01*
X693491Y8190D01*
X693511Y8230D01*
X693611Y8370D01*
X693641Y8400D01*
Y9530D01*
X693651Y9655D01*
X693691Y9780D01*
X693751Y9890D01*
X693831Y9990D01*
X693931Y10070D01*
X694041Y10130D01*
X694166Y10170D01*
X694291Y10180D01*
X694416Y10170D01*
X694541Y10130D01*
X694651Y10070D01*
X694751Y9990D01*
X694831Y9890D01*
X694891Y9780D01*
X694931Y9655D01*
X694941Y9530D01*
Y8400D01*
X694971Y8370D01*
X695071Y8230D01*
X695091Y8190D01*
X695106Y8155D01*
X695126Y8115D01*
X695141Y8075D01*
X695151Y8035D01*
X695166Y7990D01*
X695171Y7950D01*
X695181Y7910D01*
X695186Y7865D01*
Y7825D01*
X695191Y7780D01*
X695186Y7735D01*
Y7695D01*
X695181Y7650D01*
X695171Y7610D01*
X695166Y7570D01*
X695151Y7525D01*
X695141Y7485D01*
X695126Y7445D01*
X695106Y7405D01*
X695091Y7370D01*
X695071Y7330D01*
X694971Y7190D01*
X694941Y7160D01*
Y3730D01*
X694931Y3605D01*
X694891Y3480D01*
X694831Y3370D01*
X694751Y3270D01*
X694651Y3190D01*
X694541Y3130D01*
X694416Y3090D01*
X694291Y3080D01*
G37*
G36*
G01X689567D02*
X689442Y3090D01*
X689317Y3130D01*
X689207Y3190D01*
X689107Y3270D01*
X689027Y3370D01*
X688967Y3480D01*
X688927Y3605D01*
X688917Y3730D01*
Y7160D01*
X688887Y7190D01*
X688787Y7330D01*
X688767Y7370D01*
X688752Y7405D01*
X688732Y7445D01*
X688717Y7485D01*
X688707Y7525D01*
X688692Y7570D01*
X688687Y7610D01*
X688677Y7650D01*
X688672Y7695D01*
Y7735D01*
X688667Y7780D01*
X688672Y7825D01*
Y7865D01*
X688677Y7910D01*
X688687Y7950D01*
X688692Y7990D01*
X688707Y8035D01*
X688717Y8075D01*
X688732Y8115D01*
X688752Y8155D01*
X688767Y8190D01*
X688787Y8230D01*
X688887Y8370D01*
X688917Y8400D01*
Y9530D01*
X688927Y9655D01*
X688967Y9780D01*
X689027Y9890D01*
X689107Y9990D01*
X689207Y10070D01*
X689317Y10130D01*
X689442Y10170D01*
X689567Y10180D01*
X689692Y10170D01*
X689817Y10130D01*
X689927Y10070D01*
X690027Y9990D01*
X690107Y9890D01*
X690167Y9780D01*
X690207Y9655D01*
X690217Y9530D01*
Y8400D01*
X690247Y8370D01*
X690347Y8230D01*
X690367Y8190D01*
X690382Y8155D01*
X690402Y8115D01*
X690417Y8075D01*
X690427Y8035D01*
X690442Y7990D01*
X690447Y7950D01*
X690457Y7910D01*
X690462Y7865D01*
Y7825D01*
X690467Y7780D01*
X690462Y7735D01*
Y7695D01*
X690457Y7650D01*
X690447Y7610D01*
X690442Y7570D01*
X690427Y7525D01*
X690417Y7485D01*
X690402Y7445D01*
X690382Y7405D01*
X690367Y7370D01*
X690347Y7330D01*
X690247Y7190D01*
X690217Y7160D01*
Y3730D01*
X690207Y3605D01*
X690167Y3480D01*
X690107Y3370D01*
X690027Y3270D01*
X689927Y3190D01*
X689817Y3130D01*
X689692Y3090D01*
X689567Y3080D01*
G37*
G36*
G01X684842D02*
X684717Y3090D01*
X684592Y3130D01*
X684482Y3190D01*
X684382Y3270D01*
X684302Y3370D01*
X684242Y3480D01*
X684202Y3605D01*
X684192Y3730D01*
Y7160D01*
X684162Y7190D01*
X684062Y7330D01*
X684042Y7370D01*
X684027Y7405D01*
X684007Y7445D01*
X683992Y7485D01*
X683982Y7525D01*
X683967Y7570D01*
X683962Y7610D01*
X683952Y7650D01*
X683947Y7695D01*
Y7735D01*
X683942Y7780D01*
X683947Y7825D01*
Y7865D01*
X683952Y7910D01*
X683962Y7950D01*
X683967Y7990D01*
X683982Y8035D01*
X683992Y8075D01*
X684007Y8115D01*
X684027Y8155D01*
X684042Y8190D01*
X684062Y8230D01*
X684162Y8370D01*
X684192Y8400D01*
Y9530D01*
X684202Y9655D01*
X684242Y9780D01*
X684302Y9890D01*
X684382Y9990D01*
X684482Y10070D01*
X684592Y10130D01*
X684717Y10170D01*
X684842Y10180D01*
X684967Y10170D01*
X685092Y10130D01*
X685202Y10070D01*
X685302Y9990D01*
X685382Y9890D01*
X685442Y9780D01*
X685482Y9655D01*
X685492Y9530D01*
Y8400D01*
X685522Y8370D01*
X685622Y8230D01*
X685642Y8190D01*
X685657Y8155D01*
X685677Y8115D01*
X685692Y8075D01*
X685702Y8035D01*
X685717Y7990D01*
X685722Y7950D01*
X685732Y7910D01*
X685737Y7865D01*
Y7825D01*
X685742Y7780D01*
X685737Y7735D01*
Y7695D01*
X685732Y7650D01*
X685722Y7610D01*
X685717Y7570D01*
X685702Y7525D01*
X685692Y7485D01*
X685677Y7445D01*
X685657Y7405D01*
X685642Y7370D01*
X685622Y7330D01*
X685522Y7190D01*
X685492Y7160D01*
Y3730D01*
X685482Y3605D01*
X685442Y3480D01*
X685382Y3370D01*
X685302Y3270D01*
X685202Y3190D01*
X685092Y3130D01*
X684967Y3090D01*
X684842Y3080D01*
G37*
G36*
G01X708464D02*
X708339Y3090D01*
X708214Y3130D01*
X708104Y3190D01*
X708004Y3270D01*
X707924Y3370D01*
X707864Y3480D01*
X707824Y3605D01*
X707814Y3730D01*
Y7160D01*
X707784Y7190D01*
X707684Y7330D01*
X707664Y7370D01*
X707649Y7405D01*
X707629Y7445D01*
X707614Y7485D01*
X707604Y7525D01*
X707589Y7570D01*
X707584Y7610D01*
X707574Y7650D01*
X707569Y7695D01*
Y7735D01*
X707564Y7780D01*
X707569Y7825D01*
Y7865D01*
X707574Y7910D01*
X707584Y7950D01*
X707589Y7990D01*
X707604Y8035D01*
X707614Y8075D01*
X707629Y8115D01*
X707649Y8155D01*
X707664Y8190D01*
X707684Y8230D01*
X707784Y8370D01*
X707814Y8400D01*
Y9530D01*
X707824Y9655D01*
X707864Y9780D01*
X707924Y9890D01*
X708004Y9990D01*
X708104Y10070D01*
X708214Y10130D01*
X708339Y10170D01*
X708464Y10180D01*
X708589Y10170D01*
X708714Y10130D01*
X708824Y10070D01*
X708924Y9990D01*
X709004Y9890D01*
X709064Y9780D01*
X709104Y9655D01*
X709114Y9530D01*
Y8400D01*
X709144Y8370D01*
X709244Y8230D01*
X709264Y8190D01*
X709279Y8155D01*
X709299Y8115D01*
X709314Y8075D01*
X709324Y8035D01*
X709339Y7990D01*
X709344Y7950D01*
X709354Y7910D01*
X709359Y7865D01*
Y7825D01*
X709364Y7780D01*
X709359Y7735D01*
Y7695D01*
X709354Y7650D01*
X709344Y7610D01*
X709339Y7570D01*
X709324Y7525D01*
X709314Y7485D01*
X709299Y7445D01*
X709279Y7405D01*
X709264Y7370D01*
X709244Y7330D01*
X709144Y7190D01*
X709114Y7160D01*
Y3730D01*
X709104Y3605D01*
X709064Y3480D01*
X709004Y3370D01*
X708924Y3270D01*
X708824Y3190D01*
X708714Y3130D01*
X708589Y3090D01*
X708464Y3080D01*
G37*
G36*
G01X703740D02*
X703615Y3090D01*
X703490Y3130D01*
X703380Y3190D01*
X703280Y3270D01*
X703200Y3370D01*
X703140Y3480D01*
X703100Y3605D01*
X703090Y3730D01*
Y7160D01*
X703060Y7190D01*
X702960Y7330D01*
X702940Y7370D01*
X702925Y7405D01*
X702905Y7445D01*
X702890Y7485D01*
X702880Y7525D01*
X702865Y7570D01*
X702860Y7610D01*
X702850Y7650D01*
X702845Y7695D01*
Y7735D01*
X702840Y7780D01*
X702845Y7825D01*
Y7865D01*
X702850Y7910D01*
X702860Y7950D01*
X702865Y7990D01*
X702880Y8035D01*
X702890Y8075D01*
X702905Y8115D01*
X702925Y8155D01*
X702940Y8190D01*
X702960Y8230D01*
X703060Y8370D01*
X703090Y8400D01*
Y9530D01*
X703100Y9655D01*
X703140Y9780D01*
X703200Y9890D01*
X703280Y9990D01*
X703380Y10070D01*
X703490Y10130D01*
X703615Y10170D01*
X703740Y10180D01*
X703865Y10170D01*
X703990Y10130D01*
X704100Y10070D01*
X704200Y9990D01*
X704280Y9890D01*
X704340Y9780D01*
X704380Y9655D01*
X704390Y9530D01*
Y8400D01*
X704420Y8370D01*
X704520Y8230D01*
X704540Y8190D01*
X704555Y8155D01*
X704575Y8115D01*
X704590Y8075D01*
X704600Y8035D01*
X704615Y7990D01*
X704620Y7950D01*
X704630Y7910D01*
X704635Y7865D01*
Y7825D01*
X704640Y7780D01*
X704635Y7735D01*
Y7695D01*
X704630Y7650D01*
X704620Y7610D01*
X704615Y7570D01*
X704600Y7525D01*
X704590Y7485D01*
X704575Y7445D01*
X704555Y7405D01*
X704540Y7370D01*
X704520Y7330D01*
X704420Y7190D01*
X704390Y7160D01*
Y3730D01*
X704380Y3605D01*
X704340Y3480D01*
X704280Y3370D01*
X704200Y3270D01*
X704100Y3190D01*
X703990Y3130D01*
X703865Y3090D01*
X703740Y3080D01*
G37*
G36*
G01X699015D02*
X698890Y3090D01*
X698765Y3130D01*
X698655Y3190D01*
X698555Y3270D01*
X698475Y3370D01*
X698415Y3480D01*
X698375Y3605D01*
X698365Y3730D01*
Y7160D01*
X698335Y7190D01*
X698235Y7330D01*
X698215Y7370D01*
X698200Y7405D01*
X698180Y7445D01*
X698165Y7485D01*
X698155Y7525D01*
X698140Y7570D01*
X698135Y7610D01*
X698125Y7650D01*
X698120Y7695D01*
Y7735D01*
X698115Y7780D01*
X698120Y7825D01*
Y7865D01*
X698125Y7910D01*
X698135Y7950D01*
X698140Y7990D01*
X698155Y8035D01*
X698165Y8075D01*
X698180Y8115D01*
X698200Y8155D01*
X698215Y8190D01*
X698235Y8230D01*
X698335Y8370D01*
X698365Y8400D01*
Y9530D01*
X698375Y9655D01*
X698415Y9780D01*
X698475Y9890D01*
X698555Y9990D01*
X698655Y10070D01*
X698765Y10130D01*
X698890Y10170D01*
X699015Y10180D01*
X699140Y10170D01*
X699265Y10130D01*
X699375Y10070D01*
X699475Y9990D01*
X699555Y9890D01*
X699615Y9780D01*
X699655Y9655D01*
X699665Y9530D01*
Y8400D01*
X699695Y8370D01*
X699795Y8230D01*
X699815Y8190D01*
X699830Y8155D01*
X699850Y8115D01*
X699865Y8075D01*
X699875Y8035D01*
X699890Y7990D01*
X699895Y7950D01*
X699905Y7910D01*
X699910Y7865D01*
Y7825D01*
X699915Y7780D01*
X699910Y7735D01*
Y7695D01*
X699905Y7650D01*
X699895Y7610D01*
X699890Y7570D01*
X699875Y7525D01*
X699865Y7485D01*
X699850Y7445D01*
X699830Y7405D01*
X699815Y7370D01*
X699795Y7330D01*
X699695Y7190D01*
X699665Y7160D01*
Y3730D01*
X699655Y3605D01*
X699615Y3480D01*
X699555Y3370D01*
X699475Y3270D01*
X699375Y3190D01*
X699265Y3130D01*
X699140Y3090D01*
X699015Y3080D01*
G37*
G36*
G01X722638D02*
X722513Y3090D01*
X722388Y3130D01*
X722278Y3190D01*
X722178Y3270D01*
X722098Y3370D01*
X722038Y3480D01*
X721998Y3605D01*
X721988Y3730D01*
Y7160D01*
X721958Y7190D01*
X721858Y7330D01*
X721838Y7370D01*
X721823Y7405D01*
X721803Y7445D01*
X721788Y7485D01*
X721778Y7525D01*
X721763Y7570D01*
X721758Y7610D01*
X721748Y7650D01*
X721743Y7695D01*
Y7735D01*
X721738Y7780D01*
X721743Y7825D01*
Y7865D01*
X721748Y7910D01*
X721758Y7950D01*
X721763Y7990D01*
X721778Y8035D01*
X721788Y8075D01*
X721803Y8115D01*
X721823Y8155D01*
X721838Y8190D01*
X721858Y8230D01*
X721958Y8370D01*
X721988Y8400D01*
Y9530D01*
X721998Y9655D01*
X722038Y9780D01*
X722098Y9890D01*
X722178Y9990D01*
X722278Y10070D01*
X722388Y10130D01*
X722513Y10170D01*
X722638Y10180D01*
X722763Y10170D01*
X722888Y10130D01*
X722998Y10070D01*
X723098Y9990D01*
X723178Y9890D01*
X723238Y9780D01*
X723278Y9655D01*
X723288Y9530D01*
Y8400D01*
X723318Y8370D01*
X723418Y8230D01*
X723438Y8190D01*
X723453Y8155D01*
X723473Y8115D01*
X723488Y8075D01*
X723498Y8035D01*
X723513Y7990D01*
X723518Y7950D01*
X723528Y7910D01*
X723533Y7865D01*
Y7825D01*
X723538Y7780D01*
X723533Y7735D01*
Y7695D01*
X723528Y7650D01*
X723518Y7610D01*
X723513Y7570D01*
X723498Y7525D01*
X723488Y7485D01*
X723473Y7445D01*
X723453Y7405D01*
X723438Y7370D01*
X723418Y7330D01*
X723318Y7190D01*
X723288Y7160D01*
Y3730D01*
X723278Y3605D01*
X723238Y3480D01*
X723178Y3370D01*
X723098Y3270D01*
X722998Y3190D01*
X722888Y3130D01*
X722763Y3090D01*
X722638Y3080D01*
G37*
G36*
G01X717913D02*
X717788Y3090D01*
X717663Y3130D01*
X717553Y3190D01*
X717453Y3270D01*
X717373Y3370D01*
X717313Y3480D01*
X717273Y3605D01*
X717263Y3730D01*
Y7160D01*
X717233Y7190D01*
X717133Y7330D01*
X717113Y7370D01*
X717098Y7405D01*
X717078Y7445D01*
X717063Y7485D01*
X717053Y7525D01*
X717038Y7570D01*
X717033Y7610D01*
X717023Y7650D01*
X717018Y7695D01*
Y7735D01*
X717013Y7780D01*
X717018Y7825D01*
Y7865D01*
X717023Y7910D01*
X717033Y7950D01*
X717038Y7990D01*
X717053Y8035D01*
X717063Y8075D01*
X717078Y8115D01*
X717098Y8155D01*
X717113Y8190D01*
X717133Y8230D01*
X717233Y8370D01*
X717263Y8400D01*
Y9530D01*
X717273Y9655D01*
X717313Y9780D01*
X717373Y9890D01*
X717453Y9990D01*
X717553Y10070D01*
X717663Y10130D01*
X717788Y10170D01*
X717913Y10180D01*
X718038Y10170D01*
X718163Y10130D01*
X718273Y10070D01*
X718373Y9990D01*
X718453Y9890D01*
X718513Y9780D01*
X718553Y9655D01*
X718563Y9530D01*
Y8400D01*
X718593Y8370D01*
X718693Y8230D01*
X718713Y8190D01*
X718728Y8155D01*
X718748Y8115D01*
X718763Y8075D01*
X718773Y8035D01*
X718788Y7990D01*
X718793Y7950D01*
X718803Y7910D01*
X718808Y7865D01*
Y7825D01*
X718813Y7780D01*
X718808Y7735D01*
Y7695D01*
X718803Y7650D01*
X718793Y7610D01*
X718788Y7570D01*
X718773Y7525D01*
X718763Y7485D01*
X718748Y7445D01*
X718728Y7405D01*
X718713Y7370D01*
X718693Y7330D01*
X718593Y7190D01*
X718563Y7160D01*
Y3730D01*
X718553Y3605D01*
X718513Y3480D01*
X718453Y3370D01*
X718373Y3270D01*
X718273Y3190D01*
X718163Y3130D01*
X718038Y3090D01*
X717913Y3080D01*
G37*
G36*
G01X713189D02*
X713064Y3090D01*
X712939Y3130D01*
X712829Y3190D01*
X712729Y3270D01*
X712649Y3370D01*
X712589Y3480D01*
X712549Y3605D01*
X712539Y3730D01*
Y7160D01*
X712509Y7190D01*
X712409Y7330D01*
X712389Y7370D01*
X712374Y7405D01*
X712354Y7445D01*
X712339Y7485D01*
X712329Y7525D01*
X712314Y7570D01*
X712309Y7610D01*
X712299Y7650D01*
X712294Y7695D01*
Y7735D01*
X712289Y7780D01*
X712294Y7825D01*
Y7865D01*
X712299Y7910D01*
X712309Y7950D01*
X712314Y7990D01*
X712329Y8035D01*
X712339Y8075D01*
X712354Y8115D01*
X712374Y8155D01*
X712389Y8190D01*
X712409Y8230D01*
X712509Y8370D01*
X712539Y8400D01*
Y9530D01*
X712549Y9655D01*
X712589Y9780D01*
X712649Y9890D01*
X712729Y9990D01*
X712829Y10070D01*
X712939Y10130D01*
X713064Y10170D01*
X713189Y10180D01*
X713314Y10170D01*
X713439Y10130D01*
X713549Y10070D01*
X713649Y9990D01*
X713729Y9890D01*
X713789Y9780D01*
X713829Y9655D01*
X713839Y9530D01*
Y8400D01*
X713869Y8370D01*
X713969Y8230D01*
X713989Y8190D01*
X714004Y8155D01*
X714024Y8115D01*
X714039Y8075D01*
X714049Y8035D01*
X714064Y7990D01*
X714069Y7950D01*
X714079Y7910D01*
X714084Y7865D01*
Y7825D01*
X714089Y7780D01*
X714084Y7735D01*
Y7695D01*
X714079Y7650D01*
X714069Y7610D01*
X714064Y7570D01*
X714049Y7525D01*
X714039Y7485D01*
X714024Y7445D01*
X714004Y7405D01*
X713989Y7370D01*
X713969Y7330D01*
X713869Y7190D01*
X713839Y7160D01*
Y3730D01*
X713829Y3605D01*
X713789Y3480D01*
X713729Y3370D01*
X713649Y3270D01*
X713549Y3190D01*
X713439Y3130D01*
X713314Y3090D01*
X713189Y3080D01*
G37*
G36*
G01X741535D02*
X741410Y3090D01*
X741285Y3130D01*
X741175Y3190D01*
X741075Y3270D01*
X740995Y3370D01*
X740935Y3480D01*
X740895Y3605D01*
X740885Y3730D01*
Y7160D01*
X740855Y7190D01*
X740755Y7330D01*
X740735Y7370D01*
X740720Y7405D01*
X740700Y7445D01*
X740685Y7485D01*
X740675Y7525D01*
X740660Y7570D01*
X740655Y7610D01*
X740645Y7650D01*
X740640Y7695D01*
Y7735D01*
X740635Y7780D01*
X740640Y7825D01*
Y7865D01*
X740645Y7910D01*
X740655Y7950D01*
X740660Y7990D01*
X740675Y8035D01*
X740685Y8075D01*
X740700Y8115D01*
X740720Y8155D01*
X740735Y8190D01*
X740755Y8230D01*
X740855Y8370D01*
X740885Y8400D01*
Y9530D01*
X740895Y9655D01*
X740935Y9780D01*
X740995Y9890D01*
X741075Y9990D01*
X741175Y10070D01*
X741285Y10130D01*
X741410Y10170D01*
X741535Y10180D01*
X741660Y10170D01*
X741785Y10130D01*
X741895Y10070D01*
X741995Y9990D01*
X742075Y9890D01*
X742135Y9780D01*
X742175Y9655D01*
X742185Y9530D01*
Y8400D01*
X742215Y8370D01*
X742315Y8230D01*
X742335Y8190D01*
X742350Y8155D01*
X742370Y8115D01*
X742385Y8075D01*
X742395Y8035D01*
X742410Y7990D01*
X742415Y7950D01*
X742425Y7910D01*
X742430Y7865D01*
Y7825D01*
X742435Y7780D01*
X742430Y7735D01*
Y7695D01*
X742425Y7650D01*
X742415Y7610D01*
X742410Y7570D01*
X742395Y7525D01*
X742385Y7485D01*
X742370Y7445D01*
X742350Y7405D01*
X742335Y7370D01*
X742315Y7330D01*
X742215Y7190D01*
X742185Y7160D01*
Y3730D01*
X742175Y3605D01*
X742135Y3480D01*
X742075Y3370D01*
X741995Y3270D01*
X741895Y3190D01*
X741785Y3130D01*
X741660Y3090D01*
X741535Y3080D01*
G37*
G36*
G01X736811D02*
X736686Y3090D01*
X736561Y3130D01*
X736451Y3190D01*
X736351Y3270D01*
X736271Y3370D01*
X736211Y3480D01*
X736171Y3605D01*
X736161Y3730D01*
Y7160D01*
X736131Y7190D01*
X736031Y7330D01*
X736011Y7370D01*
X735996Y7405D01*
X735976Y7445D01*
X735961Y7485D01*
X735951Y7525D01*
X735936Y7570D01*
X735931Y7610D01*
X735921Y7650D01*
X735916Y7695D01*
Y7735D01*
X735911Y7780D01*
X735916Y7825D01*
Y7865D01*
X735921Y7910D01*
X735931Y7950D01*
X735936Y7990D01*
X735951Y8035D01*
X735961Y8075D01*
X735976Y8115D01*
X735996Y8155D01*
X736011Y8190D01*
X736031Y8230D01*
X736131Y8370D01*
X736161Y8400D01*
Y9530D01*
X736171Y9655D01*
X736211Y9780D01*
X736271Y9890D01*
X736351Y9990D01*
X736451Y10070D01*
X736561Y10130D01*
X736686Y10170D01*
X736811Y10180D01*
X736936Y10170D01*
X737061Y10130D01*
X737171Y10070D01*
X737271Y9990D01*
X737351Y9890D01*
X737411Y9780D01*
X737451Y9655D01*
X737461Y9530D01*
Y8400D01*
X737491Y8370D01*
X737591Y8230D01*
X737611Y8190D01*
X737626Y8155D01*
X737646Y8115D01*
X737661Y8075D01*
X737671Y8035D01*
X737686Y7990D01*
X737691Y7950D01*
X737701Y7910D01*
X737706Y7865D01*
Y7825D01*
X737711Y7780D01*
X737706Y7735D01*
Y7695D01*
X737701Y7650D01*
X737691Y7610D01*
X737686Y7570D01*
X737671Y7525D01*
X737661Y7485D01*
X737646Y7445D01*
X737626Y7405D01*
X737611Y7370D01*
X737591Y7330D01*
X737491Y7190D01*
X737461Y7160D01*
Y3730D01*
X737451Y3605D01*
X737411Y3480D01*
X737351Y3370D01*
X737271Y3270D01*
X737171Y3190D01*
X737061Y3130D01*
X736936Y3090D01*
X736811Y3080D01*
G37*
G36*
G01X732086D02*
X731961Y3090D01*
X731836Y3130D01*
X731726Y3190D01*
X731626Y3270D01*
X731546Y3370D01*
X731486Y3480D01*
X731446Y3605D01*
X731436Y3730D01*
Y7160D01*
X731406Y7190D01*
X731306Y7330D01*
X731286Y7370D01*
X731271Y7405D01*
X731251Y7445D01*
X731236Y7485D01*
X731226Y7525D01*
X731211Y7570D01*
X731206Y7610D01*
X731196Y7650D01*
X731191Y7695D01*
Y7735D01*
X731186Y7780D01*
X731191Y7825D01*
Y7865D01*
X731196Y7910D01*
X731206Y7950D01*
X731211Y7990D01*
X731226Y8035D01*
X731236Y8075D01*
X731251Y8115D01*
X731271Y8155D01*
X731286Y8190D01*
X731306Y8230D01*
X731406Y8370D01*
X731436Y8400D01*
Y9530D01*
X731446Y9655D01*
X731486Y9780D01*
X731546Y9890D01*
X731626Y9990D01*
X731726Y10070D01*
X731836Y10130D01*
X731961Y10170D01*
X732086Y10180D01*
X732211Y10170D01*
X732336Y10130D01*
X732446Y10070D01*
X732546Y9990D01*
X732626Y9890D01*
X732686Y9780D01*
X732726Y9655D01*
X732736Y9530D01*
Y8400D01*
X732766Y8370D01*
X732866Y8230D01*
X732886Y8190D01*
X732901Y8155D01*
X732921Y8115D01*
X732936Y8075D01*
X732946Y8035D01*
X732961Y7990D01*
X732966Y7950D01*
X732976Y7910D01*
X732981Y7865D01*
Y7825D01*
X732986Y7780D01*
X732981Y7735D01*
Y7695D01*
X732976Y7650D01*
X732966Y7610D01*
X732961Y7570D01*
X732946Y7525D01*
X732936Y7485D01*
X732921Y7445D01*
X732901Y7405D01*
X732886Y7370D01*
X732866Y7330D01*
X732766Y7190D01*
X732736Y7160D01*
Y3730D01*
X732726Y3605D01*
X732686Y3480D01*
X732626Y3370D01*
X732546Y3270D01*
X732446Y3190D01*
X732336Y3130D01*
X732211Y3090D01*
X732086Y3080D01*
G37*
G36*
G01X727362D02*
X727237Y3090D01*
X727112Y3130D01*
X727002Y3190D01*
X726902Y3270D01*
X726822Y3370D01*
X726762Y3480D01*
X726722Y3605D01*
X726712Y3730D01*
Y7160D01*
X726682Y7190D01*
X726582Y7330D01*
X726562Y7370D01*
X726547Y7405D01*
X726527Y7445D01*
X726512Y7485D01*
X726502Y7525D01*
X726487Y7570D01*
X726482Y7610D01*
X726472Y7650D01*
X726467Y7695D01*
Y7735D01*
X726462Y7780D01*
X726467Y7825D01*
Y7865D01*
X726472Y7910D01*
X726482Y7950D01*
X726487Y7990D01*
X726502Y8035D01*
X726512Y8075D01*
X726527Y8115D01*
X726547Y8155D01*
X726562Y8190D01*
X726582Y8230D01*
X726682Y8370D01*
X726712Y8400D01*
Y9530D01*
X726722Y9655D01*
X726762Y9780D01*
X726822Y9890D01*
X726902Y9990D01*
X727002Y10070D01*
X727112Y10130D01*
X727237Y10170D01*
X727362Y10180D01*
X727487Y10170D01*
X727612Y10130D01*
X727722Y10070D01*
X727822Y9990D01*
X727902Y9890D01*
X727962Y9780D01*
X728002Y9655D01*
X728012Y9530D01*
Y8400D01*
X728042Y8370D01*
X728142Y8230D01*
X728162Y8190D01*
X728177Y8155D01*
X728197Y8115D01*
X728212Y8075D01*
X728222Y8035D01*
X728237Y7990D01*
X728242Y7950D01*
X728252Y7910D01*
X728257Y7865D01*
Y7825D01*
X728262Y7780D01*
X728257Y7735D01*
Y7695D01*
X728252Y7650D01*
X728242Y7610D01*
X728237Y7570D01*
X728222Y7525D01*
X728212Y7485D01*
X728197Y7445D01*
X728177Y7405D01*
X728162Y7370D01*
X728142Y7330D01*
X728042Y7190D01*
X728012Y7160D01*
Y3730D01*
X728002Y3605D01*
X727962Y3480D01*
X727902Y3370D01*
X727822Y3270D01*
X727722Y3190D01*
X727612Y3130D01*
X727487Y3090D01*
X727362Y3080D01*
G37*
G36*
G01X750984D02*
X750859Y3090D01*
X750734Y3130D01*
X750624Y3190D01*
X750524Y3270D01*
X750444Y3370D01*
X750384Y3480D01*
X750344Y3605D01*
X750334Y3730D01*
Y7160D01*
X750304Y7190D01*
X750204Y7330D01*
X750184Y7370D01*
X750169Y7405D01*
X750149Y7445D01*
X750134Y7485D01*
X750124Y7525D01*
X750109Y7570D01*
X750104Y7610D01*
X750094Y7650D01*
X750089Y7695D01*
Y7735D01*
X750084Y7780D01*
X750089Y7825D01*
Y7865D01*
X750094Y7910D01*
X750104Y7950D01*
X750109Y7990D01*
X750124Y8035D01*
X750134Y8075D01*
X750149Y8115D01*
X750169Y8155D01*
X750184Y8190D01*
X750204Y8230D01*
X750304Y8370D01*
X750334Y8400D01*
Y9530D01*
X750344Y9655D01*
X750384Y9780D01*
X750444Y9890D01*
X750524Y9990D01*
X750624Y10070D01*
X750734Y10130D01*
X750859Y10170D01*
X750984Y10180D01*
X751109Y10170D01*
X751234Y10130D01*
X751344Y10070D01*
X751444Y9990D01*
X751524Y9890D01*
X751584Y9780D01*
X751624Y9655D01*
X751634Y9530D01*
Y8400D01*
X751664Y8370D01*
X751764Y8230D01*
X751784Y8190D01*
X751799Y8155D01*
X751819Y8115D01*
X751834Y8075D01*
X751844Y8035D01*
X751859Y7990D01*
X751864Y7950D01*
X751874Y7910D01*
X751879Y7865D01*
Y7825D01*
X751884Y7780D01*
X751879Y7735D01*
Y7695D01*
X751874Y7650D01*
X751864Y7610D01*
X751859Y7570D01*
X751844Y7525D01*
X751834Y7485D01*
X751819Y7445D01*
X751799Y7405D01*
X751784Y7370D01*
X751764Y7330D01*
X751664Y7190D01*
X751634Y7160D01*
Y3730D01*
X751624Y3605D01*
X751584Y3480D01*
X751524Y3370D01*
X751444Y3270D01*
X751344Y3190D01*
X751234Y3130D01*
X751109Y3090D01*
X750984Y3080D01*
G37*
G36*
G01X746260D02*
X746135Y3090D01*
X746010Y3130D01*
X745900Y3190D01*
X745800Y3270D01*
X745720Y3370D01*
X745660Y3480D01*
X745620Y3605D01*
X745610Y3730D01*
Y7160D01*
X745580Y7190D01*
X745480Y7330D01*
X745460Y7370D01*
X745445Y7405D01*
X745425Y7445D01*
X745410Y7485D01*
X745400Y7525D01*
X745385Y7570D01*
X745380Y7610D01*
X745370Y7650D01*
X745365Y7695D01*
Y7735D01*
X745360Y7780D01*
X745365Y7825D01*
Y7865D01*
X745370Y7910D01*
X745380Y7950D01*
X745385Y7990D01*
X745400Y8035D01*
X745410Y8075D01*
X745425Y8115D01*
X745445Y8155D01*
X745460Y8190D01*
X745480Y8230D01*
X745580Y8370D01*
X745610Y8400D01*
Y9530D01*
X745620Y9655D01*
X745660Y9780D01*
X745720Y9890D01*
X745800Y9990D01*
X745900Y10070D01*
X746010Y10130D01*
X746135Y10170D01*
X746260Y10180D01*
X746385Y10170D01*
X746510Y10130D01*
X746620Y10070D01*
X746720Y9990D01*
X746800Y9890D01*
X746860Y9780D01*
X746900Y9655D01*
X746910Y9530D01*
Y8400D01*
X746940Y8370D01*
X747040Y8230D01*
X747060Y8190D01*
X747075Y8155D01*
X747095Y8115D01*
X747110Y8075D01*
X747120Y8035D01*
X747135Y7990D01*
X747140Y7950D01*
X747150Y7910D01*
X747155Y7865D01*
Y7825D01*
X747160Y7780D01*
X747155Y7735D01*
Y7695D01*
X747150Y7650D01*
X747140Y7610D01*
X747135Y7570D01*
X747120Y7525D01*
X747110Y7485D01*
X747095Y7445D01*
X747075Y7405D01*
X747060Y7370D01*
X747040Y7330D01*
X746940Y7190D01*
X746910Y7160D01*
Y3730D01*
X746900Y3605D01*
X746860Y3480D01*
X746800Y3370D01*
X746720Y3270D01*
X746620Y3190D01*
X746510Y3130D01*
X746385Y3090D01*
X746260Y3080D01*
G37*
G54D98*
X535210Y218348D03*
Y220316D03*
Y222285D03*
Y224254D03*
Y226222D03*
X546710D03*
Y224254D03*
Y222285D03*
Y220316D03*
Y218348D03*
G36*
G01X508858Y35416D02*
X508733Y35426D01*
X508608Y35466D01*
X508498Y35526D01*
X508398Y35606D01*
X508318Y35706D01*
X508258Y35816D01*
X508218Y35941D01*
X508208Y36066D01*
Y38191D01*
X508178Y38221D01*
X508153Y38256D01*
X508123Y38291D01*
X508103Y38326D01*
X508078Y38361D01*
X508038Y38441D01*
X507993Y38561D01*
X507983Y38601D01*
X507973Y38646D01*
X507968Y38686D01*
X507958Y38731D01*
Y38901D01*
X507968Y38946D01*
X507973Y38986D01*
X507983Y39031D01*
X507993Y39071D01*
X508038Y39191D01*
X508078Y39271D01*
X508103Y39306D01*
X508123Y39341D01*
X508153Y39376D01*
X508178Y39411D01*
X508208Y39441D01*
Y41866D01*
X508218Y41991D01*
X508258Y42116D01*
X508318Y42226D01*
X508398Y42326D01*
X508498Y42406D01*
X508608Y42466D01*
X508733Y42506D01*
X508858Y42516D01*
X508983Y42506D01*
X509108Y42466D01*
X509218Y42406D01*
X509318Y42326D01*
X509398Y42226D01*
X509458Y42116D01*
X509498Y41991D01*
X509508Y41866D01*
Y39436D01*
X509538Y39406D01*
X509638Y39266D01*
X509658Y39226D01*
X509673Y39191D01*
X509693Y39151D01*
X509708Y39111D01*
X509718Y39071D01*
X509733Y39026D01*
X509738Y38986D01*
X509748Y38946D01*
X509753Y38901D01*
Y38861D01*
X509758Y38816D01*
X509753Y38771D01*
Y38731D01*
X509748Y38686D01*
X509738Y38646D01*
X509733Y38606D01*
X509718Y38561D01*
X509708Y38521D01*
X509693Y38481D01*
X509673Y38441D01*
X509658Y38406D01*
X509638Y38366D01*
X509538Y38226D01*
X509508Y38196D01*
Y36066D01*
X509498Y35941D01*
X509458Y35816D01*
X509398Y35706D01*
X509318Y35606D01*
X509218Y35526D01*
X509108Y35466D01*
X508983Y35426D01*
X508858Y35416D01*
G37*
G36*
G01X523031D02*
X522906Y35426D01*
X522781Y35466D01*
X522671Y35526D01*
X522571Y35606D01*
X522491Y35706D01*
X522431Y35816D01*
X522391Y35941D01*
X522381Y36066D01*
Y38191D01*
X522351Y38221D01*
X522326Y38256D01*
X522296Y38291D01*
X522276Y38326D01*
X522251Y38361D01*
X522211Y38441D01*
X522166Y38561D01*
X522156Y38601D01*
X522146Y38646D01*
X522141Y38686D01*
X522131Y38731D01*
Y38901D01*
X522141Y38946D01*
X522146Y38986D01*
X522156Y39031D01*
X522166Y39071D01*
X522211Y39191D01*
X522251Y39271D01*
X522276Y39306D01*
X522296Y39341D01*
X522326Y39376D01*
X522351Y39411D01*
X522381Y39441D01*
Y41866D01*
X522391Y41991D01*
X522431Y42116D01*
X522491Y42226D01*
X522571Y42326D01*
X522671Y42406D01*
X522781Y42466D01*
X522906Y42506D01*
X523031Y42516D01*
X523156Y42506D01*
X523281Y42466D01*
X523391Y42406D01*
X523491Y42326D01*
X523571Y42226D01*
X523631Y42116D01*
X523671Y41991D01*
X523681Y41866D01*
Y39436D01*
X523711Y39406D01*
X523811Y39266D01*
X523831Y39226D01*
X523846Y39191D01*
X523866Y39151D01*
X523881Y39111D01*
X523891Y39071D01*
X523906Y39026D01*
X523911Y38986D01*
X523921Y38946D01*
X523926Y38901D01*
Y38861D01*
X523931Y38816D01*
X523926Y38771D01*
Y38731D01*
X523921Y38686D01*
X523911Y38646D01*
X523906Y38606D01*
X523891Y38561D01*
X523881Y38521D01*
X523866Y38481D01*
X523846Y38441D01*
X523831Y38406D01*
X523811Y38366D01*
X523711Y38226D01*
X523681Y38196D01*
Y36066D01*
X523671Y35941D01*
X523631Y35816D01*
X523571Y35706D01*
X523491Y35606D01*
X523391Y35526D01*
X523281Y35466D01*
X523156Y35426D01*
X523031Y35416D01*
G37*
G36*
G01X518307D02*
X518182Y35426D01*
X518057Y35466D01*
X517947Y35526D01*
X517847Y35606D01*
X517767Y35706D01*
X517707Y35816D01*
X517667Y35941D01*
X517657Y36066D01*
Y38191D01*
X517627Y38221D01*
X517602Y38256D01*
X517572Y38291D01*
X517552Y38326D01*
X517527Y38361D01*
X517487Y38441D01*
X517442Y38561D01*
X517432Y38601D01*
X517422Y38646D01*
X517417Y38686D01*
X517407Y38731D01*
Y38901D01*
X517417Y38946D01*
X517422Y38986D01*
X517432Y39031D01*
X517442Y39071D01*
X517487Y39191D01*
X517527Y39271D01*
X517552Y39306D01*
X517572Y39341D01*
X517602Y39376D01*
X517627Y39411D01*
X517657Y39441D01*
Y41866D01*
X517667Y41991D01*
X517707Y42116D01*
X517767Y42226D01*
X517847Y42326D01*
X517947Y42406D01*
X518057Y42466D01*
X518182Y42506D01*
X518307Y42516D01*
X518432Y42506D01*
X518557Y42466D01*
X518667Y42406D01*
X518767Y42326D01*
X518847Y42226D01*
X518907Y42116D01*
X518947Y41991D01*
X518957Y41866D01*
Y39436D01*
X518987Y39406D01*
X519087Y39266D01*
X519107Y39226D01*
X519122Y39191D01*
X519142Y39151D01*
X519157Y39111D01*
X519167Y39071D01*
X519182Y39026D01*
X519187Y38986D01*
X519197Y38946D01*
X519202Y38901D01*
Y38861D01*
X519207Y38816D01*
X519202Y38771D01*
Y38731D01*
X519197Y38686D01*
X519187Y38646D01*
X519182Y38606D01*
X519167Y38561D01*
X519157Y38521D01*
X519142Y38481D01*
X519122Y38441D01*
X519107Y38406D01*
X519087Y38366D01*
X518987Y38226D01*
X518957Y38196D01*
Y36066D01*
X518947Y35941D01*
X518907Y35816D01*
X518847Y35706D01*
X518767Y35606D01*
X518667Y35526D01*
X518557Y35466D01*
X518432Y35426D01*
X518307Y35416D01*
G37*
G36*
G01X513582D02*
X513457Y35426D01*
X513332Y35466D01*
X513222Y35526D01*
X513122Y35606D01*
X513042Y35706D01*
X512982Y35816D01*
X512942Y35941D01*
X512932Y36066D01*
Y38191D01*
X512902Y38221D01*
X512877Y38256D01*
X512847Y38291D01*
X512827Y38326D01*
X512802Y38361D01*
X512762Y38441D01*
X512717Y38561D01*
X512707Y38601D01*
X512697Y38646D01*
X512692Y38686D01*
X512682Y38731D01*
Y38901D01*
X512692Y38946D01*
X512697Y38986D01*
X512707Y39031D01*
X512717Y39071D01*
X512762Y39191D01*
X512802Y39271D01*
X512827Y39306D01*
X512847Y39341D01*
X512877Y39376D01*
X512902Y39411D01*
X512932Y39441D01*
Y41866D01*
X512942Y41991D01*
X512982Y42116D01*
X513042Y42226D01*
X513122Y42326D01*
X513222Y42406D01*
X513332Y42466D01*
X513457Y42506D01*
X513582Y42516D01*
X513707Y42506D01*
X513832Y42466D01*
X513942Y42406D01*
X514042Y42326D01*
X514122Y42226D01*
X514182Y42116D01*
X514222Y41991D01*
X514232Y41866D01*
Y39436D01*
X514262Y39406D01*
X514362Y39266D01*
X514382Y39226D01*
X514397Y39191D01*
X514417Y39151D01*
X514432Y39111D01*
X514442Y39071D01*
X514457Y39026D01*
X514462Y38986D01*
X514472Y38946D01*
X514477Y38901D01*
Y38861D01*
X514482Y38816D01*
X514477Y38771D01*
Y38731D01*
X514472Y38686D01*
X514462Y38646D01*
X514457Y38606D01*
X514442Y38561D01*
X514432Y38521D01*
X514417Y38481D01*
X514397Y38441D01*
X514382Y38406D01*
X514362Y38366D01*
X514262Y38226D01*
X514232Y38196D01*
Y36066D01*
X514222Y35941D01*
X514182Y35816D01*
X514122Y35706D01*
X514042Y35606D01*
X513942Y35526D01*
X513832Y35466D01*
X513707Y35426D01*
X513582Y35416D01*
G37*
G36*
G01X541929D02*
X541804Y35426D01*
X541679Y35466D01*
X541569Y35526D01*
X541469Y35606D01*
X541389Y35706D01*
X541329Y35816D01*
X541289Y35941D01*
X541279Y36066D01*
Y38191D01*
X541249Y38221D01*
X541224Y38256D01*
X541194Y38291D01*
X541174Y38326D01*
X541149Y38361D01*
X541109Y38441D01*
X541064Y38561D01*
X541054Y38601D01*
X541044Y38646D01*
X541039Y38686D01*
X541029Y38731D01*
Y38901D01*
X541039Y38946D01*
X541044Y38986D01*
X541054Y39031D01*
X541064Y39071D01*
X541109Y39191D01*
X541149Y39271D01*
X541174Y39306D01*
X541194Y39341D01*
X541224Y39376D01*
X541249Y39411D01*
X541279Y39441D01*
Y41866D01*
X541289Y41991D01*
X541329Y42116D01*
X541389Y42226D01*
X541469Y42326D01*
X541569Y42406D01*
X541679Y42466D01*
X541804Y42506D01*
X541929Y42516D01*
X542054Y42506D01*
X542179Y42466D01*
X542289Y42406D01*
X542389Y42326D01*
X542469Y42226D01*
X542529Y42116D01*
X542569Y41991D01*
X542579Y41866D01*
Y39436D01*
X542609Y39406D01*
X542709Y39266D01*
X542729Y39226D01*
X542744Y39191D01*
X542764Y39151D01*
X542779Y39111D01*
X542789Y39071D01*
X542804Y39026D01*
X542809Y38986D01*
X542819Y38946D01*
X542824Y38901D01*
Y38861D01*
X542829Y38816D01*
X542824Y38771D01*
Y38731D01*
X542819Y38686D01*
X542809Y38646D01*
X542804Y38606D01*
X542789Y38561D01*
X542779Y38521D01*
X542764Y38481D01*
X542744Y38441D01*
X542729Y38406D01*
X542709Y38366D01*
X542609Y38226D01*
X542579Y38196D01*
Y36066D01*
X542569Y35941D01*
X542529Y35816D01*
X542469Y35706D01*
X542389Y35606D01*
X542289Y35526D01*
X542179Y35466D01*
X542054Y35426D01*
X541929Y35416D01*
G37*
G36*
G01X537204D02*
X537079Y35426D01*
X536954Y35466D01*
X536844Y35526D01*
X536744Y35606D01*
X536664Y35706D01*
X536604Y35816D01*
X536564Y35941D01*
X536554Y36066D01*
Y38191D01*
X536524Y38221D01*
X536499Y38256D01*
X536469Y38291D01*
X536449Y38326D01*
X536424Y38361D01*
X536384Y38441D01*
X536339Y38561D01*
X536329Y38601D01*
X536319Y38646D01*
X536314Y38686D01*
X536304Y38731D01*
Y38901D01*
X536314Y38946D01*
X536319Y38986D01*
X536329Y39031D01*
X536339Y39071D01*
X536384Y39191D01*
X536424Y39271D01*
X536449Y39306D01*
X536469Y39341D01*
X536499Y39376D01*
X536524Y39411D01*
X536554Y39441D01*
Y41866D01*
X536564Y41991D01*
X536604Y42116D01*
X536664Y42226D01*
X536744Y42326D01*
X536844Y42406D01*
X536954Y42466D01*
X537079Y42506D01*
X537204Y42516D01*
X537329Y42506D01*
X537454Y42466D01*
X537564Y42406D01*
X537664Y42326D01*
X537744Y42226D01*
X537804Y42116D01*
X537844Y41991D01*
X537854Y41866D01*
Y39436D01*
X537884Y39406D01*
X537984Y39266D01*
X538004Y39226D01*
X538019Y39191D01*
X538039Y39151D01*
X538054Y39111D01*
X538064Y39071D01*
X538079Y39026D01*
X538084Y38986D01*
X538094Y38946D01*
X538099Y38901D01*
Y38861D01*
X538104Y38816D01*
X538099Y38771D01*
Y38731D01*
X538094Y38686D01*
X538084Y38646D01*
X538079Y38606D01*
X538064Y38561D01*
X538054Y38521D01*
X538039Y38481D01*
X538019Y38441D01*
X538004Y38406D01*
X537984Y38366D01*
X537884Y38226D01*
X537854Y38196D01*
Y36066D01*
X537844Y35941D01*
X537804Y35816D01*
X537744Y35706D01*
X537664Y35606D01*
X537564Y35526D01*
X537454Y35466D01*
X537329Y35426D01*
X537204Y35416D01*
G37*
G36*
G01X532480D02*
X532355Y35426D01*
X532230Y35466D01*
X532120Y35526D01*
X532020Y35606D01*
X531940Y35706D01*
X531880Y35816D01*
X531840Y35941D01*
X531830Y36066D01*
Y38191D01*
X531800Y38221D01*
X531775Y38256D01*
X531745Y38291D01*
X531725Y38326D01*
X531700Y38361D01*
X531660Y38441D01*
X531615Y38561D01*
X531605Y38601D01*
X531595Y38646D01*
X531590Y38686D01*
X531580Y38731D01*
Y38901D01*
X531590Y38946D01*
X531595Y38986D01*
X531605Y39031D01*
X531615Y39071D01*
X531660Y39191D01*
X531700Y39271D01*
X531725Y39306D01*
X531745Y39341D01*
X531775Y39376D01*
X531800Y39411D01*
X531830Y39441D01*
Y41866D01*
X531840Y41991D01*
X531880Y42116D01*
X531940Y42226D01*
X532020Y42326D01*
X532120Y42406D01*
X532230Y42466D01*
X532355Y42506D01*
X532480Y42516D01*
X532605Y42506D01*
X532730Y42466D01*
X532840Y42406D01*
X532940Y42326D01*
X533020Y42226D01*
X533080Y42116D01*
X533120Y41991D01*
X533130Y41866D01*
Y39436D01*
X533160Y39406D01*
X533260Y39266D01*
X533280Y39226D01*
X533295Y39191D01*
X533315Y39151D01*
X533330Y39111D01*
X533340Y39071D01*
X533355Y39026D01*
X533360Y38986D01*
X533370Y38946D01*
X533375Y38901D01*
Y38861D01*
X533380Y38816D01*
X533375Y38771D01*
Y38731D01*
X533370Y38686D01*
X533360Y38646D01*
X533355Y38606D01*
X533340Y38561D01*
X533330Y38521D01*
X533315Y38481D01*
X533295Y38441D01*
X533280Y38406D01*
X533260Y38366D01*
X533160Y38226D01*
X533130Y38196D01*
Y36066D01*
X533120Y35941D01*
X533080Y35816D01*
X533020Y35706D01*
X532940Y35606D01*
X532840Y35526D01*
X532730Y35466D01*
X532605Y35426D01*
X532480Y35416D01*
G37*
G36*
G01X527756D02*
X527631Y35426D01*
X527506Y35466D01*
X527396Y35526D01*
X527296Y35606D01*
X527216Y35706D01*
X527156Y35816D01*
X527116Y35941D01*
X527106Y36066D01*
Y38191D01*
X527076Y38221D01*
X527051Y38256D01*
X527021Y38291D01*
X527001Y38326D01*
X526976Y38361D01*
X526936Y38441D01*
X526891Y38561D01*
X526881Y38601D01*
X526871Y38646D01*
X526866Y38686D01*
X526856Y38731D01*
Y38901D01*
X526866Y38946D01*
X526871Y38986D01*
X526881Y39031D01*
X526891Y39071D01*
X526936Y39191D01*
X526976Y39271D01*
X527001Y39306D01*
X527021Y39341D01*
X527051Y39376D01*
X527076Y39411D01*
X527106Y39441D01*
Y41866D01*
X527116Y41991D01*
X527156Y42116D01*
X527216Y42226D01*
X527296Y42326D01*
X527396Y42406D01*
X527506Y42466D01*
X527631Y42506D01*
X527756Y42516D01*
X527881Y42506D01*
X528006Y42466D01*
X528116Y42406D01*
X528216Y42326D01*
X528296Y42226D01*
X528356Y42116D01*
X528396Y41991D01*
X528406Y41866D01*
Y39436D01*
X528436Y39406D01*
X528536Y39266D01*
X528556Y39226D01*
X528571Y39191D01*
X528591Y39151D01*
X528606Y39111D01*
X528616Y39071D01*
X528631Y39026D01*
X528636Y38986D01*
X528646Y38946D01*
X528651Y38901D01*
Y38861D01*
X528656Y38816D01*
X528651Y38771D01*
Y38731D01*
X528646Y38686D01*
X528636Y38646D01*
X528631Y38606D01*
X528616Y38561D01*
X528606Y38521D01*
X528591Y38481D01*
X528571Y38441D01*
X528556Y38406D01*
X528536Y38366D01*
X528436Y38226D01*
X528406Y38196D01*
Y36066D01*
X528396Y35941D01*
X528356Y35816D01*
X528296Y35706D01*
X528216Y35606D01*
X528116Y35526D01*
X528006Y35466D01*
X527881Y35426D01*
X527756Y35416D01*
G37*
G36*
G01X556102D02*
X555977Y35426D01*
X555852Y35466D01*
X555742Y35526D01*
X555642Y35606D01*
X555562Y35706D01*
X555502Y35816D01*
X555462Y35941D01*
X555452Y36066D01*
Y38191D01*
X555422Y38221D01*
X555397Y38256D01*
X555367Y38291D01*
X555347Y38326D01*
X555322Y38361D01*
X555282Y38441D01*
X555237Y38561D01*
X555227Y38601D01*
X555217Y38646D01*
X555212Y38686D01*
X555202Y38731D01*
Y38901D01*
X555212Y38946D01*
X555217Y38986D01*
X555227Y39031D01*
X555237Y39071D01*
X555282Y39191D01*
X555322Y39271D01*
X555347Y39306D01*
X555367Y39341D01*
X555397Y39376D01*
X555422Y39411D01*
X555452Y39441D01*
Y41866D01*
X555462Y41991D01*
X555502Y42116D01*
X555562Y42226D01*
X555642Y42326D01*
X555742Y42406D01*
X555852Y42466D01*
X555977Y42506D01*
X556102Y42516D01*
X556227Y42506D01*
X556352Y42466D01*
X556462Y42406D01*
X556562Y42326D01*
X556642Y42226D01*
X556702Y42116D01*
X556742Y41991D01*
X556752Y41866D01*
Y39436D01*
X556782Y39406D01*
X556882Y39266D01*
X556902Y39226D01*
X556917Y39191D01*
X556937Y39151D01*
X556952Y39111D01*
X556962Y39071D01*
X556977Y39026D01*
X556982Y38986D01*
X556992Y38946D01*
X556997Y38901D01*
Y38861D01*
X557002Y38816D01*
X556997Y38771D01*
Y38731D01*
X556992Y38686D01*
X556982Y38646D01*
X556977Y38606D01*
X556962Y38561D01*
X556952Y38521D01*
X556937Y38481D01*
X556917Y38441D01*
X556902Y38406D01*
X556882Y38366D01*
X556782Y38226D01*
X556752Y38196D01*
Y36066D01*
X556742Y35941D01*
X556702Y35816D01*
X556642Y35706D01*
X556562Y35606D01*
X556462Y35526D01*
X556352Y35466D01*
X556227Y35426D01*
X556102Y35416D01*
G37*
G36*
G01X551378D02*
X551253Y35426D01*
X551128Y35466D01*
X551018Y35526D01*
X550918Y35606D01*
X550838Y35706D01*
X550778Y35816D01*
X550738Y35941D01*
X550728Y36066D01*
Y38191D01*
X550698Y38221D01*
X550673Y38256D01*
X550643Y38291D01*
X550623Y38326D01*
X550598Y38361D01*
X550558Y38441D01*
X550513Y38561D01*
X550503Y38601D01*
X550493Y38646D01*
X550488Y38686D01*
X550478Y38731D01*
Y38901D01*
X550488Y38946D01*
X550493Y38986D01*
X550503Y39031D01*
X550513Y39071D01*
X550558Y39191D01*
X550598Y39271D01*
X550623Y39306D01*
X550643Y39341D01*
X550673Y39376D01*
X550698Y39411D01*
X550728Y39441D01*
Y41866D01*
X550738Y41991D01*
X550778Y42116D01*
X550838Y42226D01*
X550918Y42326D01*
X551018Y42406D01*
X551128Y42466D01*
X551253Y42506D01*
X551378Y42516D01*
X551503Y42506D01*
X551628Y42466D01*
X551738Y42406D01*
X551838Y42326D01*
X551918Y42226D01*
X551978Y42116D01*
X552018Y41991D01*
X552028Y41866D01*
Y39436D01*
X552058Y39406D01*
X552158Y39266D01*
X552178Y39226D01*
X552193Y39191D01*
X552213Y39151D01*
X552228Y39111D01*
X552238Y39071D01*
X552253Y39026D01*
X552258Y38986D01*
X552268Y38946D01*
X552273Y38901D01*
Y38861D01*
X552278Y38816D01*
X552273Y38771D01*
Y38731D01*
X552268Y38686D01*
X552258Y38646D01*
X552253Y38606D01*
X552238Y38561D01*
X552228Y38521D01*
X552213Y38481D01*
X552193Y38441D01*
X552178Y38406D01*
X552158Y38366D01*
X552058Y38226D01*
X552028Y38196D01*
Y36066D01*
X552018Y35941D01*
X551978Y35816D01*
X551918Y35706D01*
X551838Y35606D01*
X551738Y35526D01*
X551628Y35466D01*
X551503Y35426D01*
X551378Y35416D01*
G37*
G36*
G01X546653D02*
X546528Y35426D01*
X546403Y35466D01*
X546293Y35526D01*
X546193Y35606D01*
X546113Y35706D01*
X546053Y35816D01*
X546013Y35941D01*
X546003Y36066D01*
Y38191D01*
X545973Y38221D01*
X545948Y38256D01*
X545918Y38291D01*
X545898Y38326D01*
X545873Y38361D01*
X545833Y38441D01*
X545788Y38561D01*
X545778Y38601D01*
X545768Y38646D01*
X545763Y38686D01*
X545753Y38731D01*
Y38901D01*
X545763Y38946D01*
X545768Y38986D01*
X545778Y39031D01*
X545788Y39071D01*
X545833Y39191D01*
X545873Y39271D01*
X545898Y39306D01*
X545918Y39341D01*
X545948Y39376D01*
X545973Y39411D01*
X546003Y39441D01*
Y41866D01*
X546013Y41991D01*
X546053Y42116D01*
X546113Y42226D01*
X546193Y42326D01*
X546293Y42406D01*
X546403Y42466D01*
X546528Y42506D01*
X546653Y42516D01*
X546778Y42506D01*
X546903Y42466D01*
X547013Y42406D01*
X547113Y42326D01*
X547193Y42226D01*
X547253Y42116D01*
X547293Y41991D01*
X547303Y41866D01*
Y39436D01*
X547333Y39406D01*
X547433Y39266D01*
X547453Y39226D01*
X547468Y39191D01*
X547488Y39151D01*
X547503Y39111D01*
X547513Y39071D01*
X547528Y39026D01*
X547533Y38986D01*
X547543Y38946D01*
X547548Y38901D01*
Y38861D01*
X547553Y38816D01*
X547548Y38771D01*
Y38731D01*
X547543Y38686D01*
X547533Y38646D01*
X547528Y38606D01*
X547513Y38561D01*
X547503Y38521D01*
X547488Y38481D01*
X547468Y38441D01*
X547453Y38406D01*
X547433Y38366D01*
X547333Y38226D01*
X547303Y38196D01*
Y36066D01*
X547293Y35941D01*
X547253Y35816D01*
X547193Y35706D01*
X547113Y35606D01*
X547013Y35526D01*
X546903Y35466D01*
X546778Y35426D01*
X546653Y35416D01*
G37*
G36*
G01X570275D02*
X570150Y35426D01*
X570025Y35466D01*
X569915Y35526D01*
X569815Y35606D01*
X569735Y35706D01*
X569675Y35816D01*
X569635Y35941D01*
X569625Y36066D01*
Y38191D01*
X569595Y38221D01*
X569570Y38256D01*
X569540Y38291D01*
X569520Y38326D01*
X569495Y38361D01*
X569455Y38441D01*
X569410Y38561D01*
X569400Y38601D01*
X569390Y38646D01*
X569385Y38686D01*
X569375Y38731D01*
Y38901D01*
X569385Y38946D01*
X569390Y38986D01*
X569400Y39031D01*
X569410Y39071D01*
X569455Y39191D01*
X569495Y39271D01*
X569520Y39306D01*
X569540Y39341D01*
X569570Y39376D01*
X569595Y39411D01*
X569625Y39441D01*
Y41866D01*
X569635Y41991D01*
X569675Y42116D01*
X569735Y42226D01*
X569815Y42326D01*
X569915Y42406D01*
X570025Y42466D01*
X570150Y42506D01*
X570275Y42516D01*
X570400Y42506D01*
X570525Y42466D01*
X570635Y42406D01*
X570735Y42326D01*
X570815Y42226D01*
X570875Y42116D01*
X570915Y41991D01*
X570925Y41866D01*
Y39436D01*
X570955Y39406D01*
X571055Y39266D01*
X571075Y39226D01*
X571090Y39191D01*
X571110Y39151D01*
X571125Y39111D01*
X571135Y39071D01*
X571150Y39026D01*
X571155Y38986D01*
X571165Y38946D01*
X571170Y38901D01*
Y38861D01*
X571175Y38816D01*
X571170Y38771D01*
Y38731D01*
X571165Y38686D01*
X571155Y38646D01*
X571150Y38606D01*
X571135Y38561D01*
X571125Y38521D01*
X571110Y38481D01*
X571090Y38441D01*
X571075Y38406D01*
X571055Y38366D01*
X570955Y38226D01*
X570925Y38196D01*
Y36066D01*
X570915Y35941D01*
X570875Y35816D01*
X570815Y35706D01*
X570735Y35606D01*
X570635Y35526D01*
X570525Y35466D01*
X570400Y35426D01*
X570275Y35416D01*
G37*
G36*
G01X565551D02*
X565426Y35426D01*
X565301Y35466D01*
X565191Y35526D01*
X565091Y35606D01*
X565011Y35706D01*
X564951Y35816D01*
X564911Y35941D01*
X564901Y36066D01*
Y38191D01*
X564871Y38221D01*
X564846Y38256D01*
X564816Y38291D01*
X564796Y38326D01*
X564771Y38361D01*
X564731Y38441D01*
X564686Y38561D01*
X564676Y38601D01*
X564666Y38646D01*
X564661Y38686D01*
X564651Y38731D01*
Y38901D01*
X564661Y38946D01*
X564666Y38986D01*
X564676Y39031D01*
X564686Y39071D01*
X564731Y39191D01*
X564771Y39271D01*
X564796Y39306D01*
X564816Y39341D01*
X564846Y39376D01*
X564871Y39411D01*
X564901Y39441D01*
Y41866D01*
X564911Y41991D01*
X564951Y42116D01*
X565011Y42226D01*
X565091Y42326D01*
X565191Y42406D01*
X565301Y42466D01*
X565426Y42506D01*
X565551Y42516D01*
X565676Y42506D01*
X565801Y42466D01*
X565911Y42406D01*
X566011Y42326D01*
X566091Y42226D01*
X566151Y42116D01*
X566191Y41991D01*
X566201Y41866D01*
Y39436D01*
X566231Y39406D01*
X566331Y39266D01*
X566351Y39226D01*
X566366Y39191D01*
X566386Y39151D01*
X566401Y39111D01*
X566411Y39071D01*
X566426Y39026D01*
X566431Y38986D01*
X566441Y38946D01*
X566446Y38901D01*
Y38861D01*
X566451Y38816D01*
X566446Y38771D01*
Y38731D01*
X566441Y38686D01*
X566431Y38646D01*
X566426Y38606D01*
X566411Y38561D01*
X566401Y38521D01*
X566386Y38481D01*
X566366Y38441D01*
X566351Y38406D01*
X566331Y38366D01*
X566231Y38226D01*
X566201Y38196D01*
Y36066D01*
X566191Y35941D01*
X566151Y35816D01*
X566091Y35706D01*
X566011Y35606D01*
X565911Y35526D01*
X565801Y35466D01*
X565676Y35426D01*
X565551Y35416D01*
G37*
G36*
G01X560827D02*
X560702Y35426D01*
X560577Y35466D01*
X560467Y35526D01*
X560367Y35606D01*
X560287Y35706D01*
X560227Y35816D01*
X560187Y35941D01*
X560177Y36066D01*
Y38191D01*
X560147Y38221D01*
X560122Y38256D01*
X560092Y38291D01*
X560072Y38326D01*
X560047Y38361D01*
X560007Y38441D01*
X559962Y38561D01*
X559952Y38601D01*
X559942Y38646D01*
X559937Y38686D01*
X559927Y38731D01*
Y38901D01*
X559937Y38946D01*
X559942Y38986D01*
X559952Y39031D01*
X559962Y39071D01*
X560007Y39191D01*
X560047Y39271D01*
X560072Y39306D01*
X560092Y39341D01*
X560122Y39376D01*
X560147Y39411D01*
X560177Y39441D01*
Y41866D01*
X560187Y41991D01*
X560227Y42116D01*
X560287Y42226D01*
X560367Y42326D01*
X560467Y42406D01*
X560577Y42466D01*
X560702Y42506D01*
X560827Y42516D01*
X560952Y42506D01*
X561077Y42466D01*
X561187Y42406D01*
X561287Y42326D01*
X561367Y42226D01*
X561427Y42116D01*
X561467Y41991D01*
X561477Y41866D01*
Y39436D01*
X561507Y39406D01*
X561607Y39266D01*
X561627Y39226D01*
X561642Y39191D01*
X561662Y39151D01*
X561677Y39111D01*
X561687Y39071D01*
X561702Y39026D01*
X561707Y38986D01*
X561717Y38946D01*
X561722Y38901D01*
Y38861D01*
X561727Y38816D01*
X561722Y38771D01*
Y38731D01*
X561717Y38686D01*
X561707Y38646D01*
X561702Y38606D01*
X561687Y38561D01*
X561677Y38521D01*
X561662Y38481D01*
X561642Y38441D01*
X561627Y38406D01*
X561607Y38366D01*
X561507Y38226D01*
X561477Y38196D01*
Y36066D01*
X561467Y35941D01*
X561427Y35816D01*
X561367Y35706D01*
X561287Y35606D01*
X561187Y35526D01*
X561077Y35466D01*
X560952Y35426D01*
X560827Y35416D01*
G37*
G36*
G01X584449D02*
X584324Y35426D01*
X584199Y35466D01*
X584089Y35526D01*
X583989Y35606D01*
X583909Y35706D01*
X583849Y35816D01*
X583809Y35941D01*
X583799Y36066D01*
Y38191D01*
X583769Y38221D01*
X583744Y38256D01*
X583714Y38291D01*
X583694Y38326D01*
X583669Y38361D01*
X583629Y38441D01*
X583584Y38561D01*
X583574Y38601D01*
X583564Y38646D01*
X583559Y38686D01*
X583549Y38731D01*
Y38901D01*
X583559Y38946D01*
X583564Y38986D01*
X583574Y39031D01*
X583584Y39071D01*
X583629Y39191D01*
X583669Y39271D01*
X583694Y39306D01*
X583714Y39341D01*
X583744Y39376D01*
X583769Y39411D01*
X583799Y39441D01*
Y41866D01*
X583809Y41991D01*
X583849Y42116D01*
X583909Y42226D01*
X583989Y42326D01*
X584089Y42406D01*
X584199Y42466D01*
X584324Y42506D01*
X584449Y42516D01*
X584574Y42506D01*
X584699Y42466D01*
X584809Y42406D01*
X584909Y42326D01*
X584989Y42226D01*
X585049Y42116D01*
X585089Y41991D01*
X585099Y41866D01*
Y39436D01*
X585129Y39406D01*
X585229Y39266D01*
X585249Y39226D01*
X585264Y39191D01*
X585284Y39151D01*
X585299Y39111D01*
X585309Y39071D01*
X585324Y39026D01*
X585329Y38986D01*
X585339Y38946D01*
X585344Y38901D01*
Y38861D01*
X585349Y38816D01*
X585344Y38771D01*
Y38731D01*
X585339Y38686D01*
X585329Y38646D01*
X585324Y38606D01*
X585309Y38561D01*
X585299Y38521D01*
X585284Y38481D01*
X585264Y38441D01*
X585249Y38406D01*
X585229Y38366D01*
X585129Y38226D01*
X585099Y38196D01*
Y36066D01*
X585089Y35941D01*
X585049Y35816D01*
X584989Y35706D01*
X584909Y35606D01*
X584809Y35526D01*
X584699Y35466D01*
X584574Y35426D01*
X584449Y35416D01*
G37*
G36*
G01X579724D02*
X579599Y35426D01*
X579474Y35466D01*
X579364Y35526D01*
X579264Y35606D01*
X579184Y35706D01*
X579124Y35816D01*
X579084Y35941D01*
X579074Y36066D01*
Y38191D01*
X579044Y38221D01*
X579019Y38256D01*
X578989Y38291D01*
X578969Y38326D01*
X578944Y38361D01*
X578904Y38441D01*
X578859Y38561D01*
X578849Y38601D01*
X578839Y38646D01*
X578834Y38686D01*
X578824Y38731D01*
Y38901D01*
X578834Y38946D01*
X578839Y38986D01*
X578849Y39031D01*
X578859Y39071D01*
X578904Y39191D01*
X578944Y39271D01*
X578969Y39306D01*
X578989Y39341D01*
X579019Y39376D01*
X579044Y39411D01*
X579074Y39441D01*
Y41866D01*
X579084Y41991D01*
X579124Y42116D01*
X579184Y42226D01*
X579264Y42326D01*
X579364Y42406D01*
X579474Y42466D01*
X579599Y42506D01*
X579724Y42516D01*
X579849Y42506D01*
X579974Y42466D01*
X580084Y42406D01*
X580184Y42326D01*
X580264Y42226D01*
X580324Y42116D01*
X580364Y41991D01*
X580374Y41866D01*
Y39436D01*
X580404Y39406D01*
X580504Y39266D01*
X580524Y39226D01*
X580539Y39191D01*
X580559Y39151D01*
X580574Y39111D01*
X580584Y39071D01*
X580599Y39026D01*
X580604Y38986D01*
X580614Y38946D01*
X580619Y38901D01*
Y38861D01*
X580624Y38816D01*
X580619Y38771D01*
Y38731D01*
X580614Y38686D01*
X580604Y38646D01*
X580599Y38606D01*
X580584Y38561D01*
X580574Y38521D01*
X580559Y38481D01*
X580539Y38441D01*
X580524Y38406D01*
X580504Y38366D01*
X580404Y38226D01*
X580374Y38196D01*
Y36066D01*
X580364Y35941D01*
X580324Y35816D01*
X580264Y35706D01*
X580184Y35606D01*
X580084Y35526D01*
X579974Y35466D01*
X579849Y35426D01*
X579724Y35416D01*
G37*
G36*
G01X575000D02*
X574875Y35426D01*
X574750Y35466D01*
X574640Y35526D01*
X574540Y35606D01*
X574460Y35706D01*
X574400Y35816D01*
X574360Y35941D01*
X574350Y36066D01*
Y38191D01*
X574320Y38221D01*
X574295Y38256D01*
X574265Y38291D01*
X574245Y38326D01*
X574220Y38361D01*
X574180Y38441D01*
X574135Y38561D01*
X574125Y38601D01*
X574115Y38646D01*
X574110Y38686D01*
X574100Y38731D01*
Y38901D01*
X574110Y38946D01*
X574115Y38986D01*
X574125Y39031D01*
X574135Y39071D01*
X574180Y39191D01*
X574220Y39271D01*
X574245Y39306D01*
X574265Y39341D01*
X574295Y39376D01*
X574320Y39411D01*
X574350Y39441D01*
Y41866D01*
X574360Y41991D01*
X574400Y42116D01*
X574460Y42226D01*
X574540Y42326D01*
X574640Y42406D01*
X574750Y42466D01*
X574875Y42506D01*
X575000Y42516D01*
X575125Y42506D01*
X575250Y42466D01*
X575360Y42406D01*
X575460Y42326D01*
X575540Y42226D01*
X575600Y42116D01*
X575640Y41991D01*
X575650Y41866D01*
Y39436D01*
X575680Y39406D01*
X575780Y39266D01*
X575800Y39226D01*
X575815Y39191D01*
X575835Y39151D01*
X575850Y39111D01*
X575860Y39071D01*
X575875Y39026D01*
X575880Y38986D01*
X575890Y38946D01*
X575895Y38901D01*
Y38861D01*
X575900Y38816D01*
X575895Y38771D01*
Y38731D01*
X575890Y38686D01*
X575880Y38646D01*
X575875Y38606D01*
X575860Y38561D01*
X575850Y38521D01*
X575835Y38481D01*
X575815Y38441D01*
X575800Y38406D01*
X575780Y38366D01*
X575680Y38226D01*
X575650Y38196D01*
Y36066D01*
X575640Y35941D01*
X575600Y35816D01*
X575540Y35706D01*
X575460Y35606D01*
X575360Y35526D01*
X575250Y35466D01*
X575125Y35426D01*
X575000Y35416D01*
G37*
G36*
G01X603346D02*
X603221Y35426D01*
X603096Y35466D01*
X602986Y35526D01*
X602886Y35606D01*
X602806Y35706D01*
X602746Y35816D01*
X602706Y35941D01*
X602696Y36066D01*
Y38191D01*
X602666Y38221D01*
X602641Y38256D01*
X602611Y38291D01*
X602591Y38326D01*
X602566Y38361D01*
X602526Y38441D01*
X602481Y38561D01*
X602471Y38601D01*
X602461Y38646D01*
X602456Y38686D01*
X602446Y38731D01*
Y38901D01*
X602456Y38946D01*
X602461Y38986D01*
X602471Y39031D01*
X602481Y39071D01*
X602526Y39191D01*
X602566Y39271D01*
X602591Y39306D01*
X602611Y39341D01*
X602641Y39376D01*
X602666Y39411D01*
X602696Y39441D01*
Y41866D01*
X602706Y41991D01*
X602746Y42116D01*
X602806Y42226D01*
X602886Y42326D01*
X602986Y42406D01*
X603096Y42466D01*
X603221Y42506D01*
X603346Y42516D01*
X603471Y42506D01*
X603596Y42466D01*
X603706Y42406D01*
X603806Y42326D01*
X603886Y42226D01*
X603946Y42116D01*
X603986Y41991D01*
X603996Y41866D01*
Y39436D01*
X604026Y39406D01*
X604126Y39266D01*
X604146Y39226D01*
X604161Y39191D01*
X604181Y39151D01*
X604196Y39111D01*
X604206Y39071D01*
X604221Y39026D01*
X604226Y38986D01*
X604236Y38946D01*
X604241Y38901D01*
Y38861D01*
X604246Y38816D01*
X604241Y38771D01*
Y38731D01*
X604236Y38686D01*
X604226Y38646D01*
X604221Y38606D01*
X604206Y38561D01*
X604196Y38521D01*
X604181Y38481D01*
X604161Y38441D01*
X604146Y38406D01*
X604126Y38366D01*
X604026Y38226D01*
X603996Y38196D01*
Y36066D01*
X603986Y35941D01*
X603946Y35816D01*
X603886Y35706D01*
X603806Y35606D01*
X603706Y35526D01*
X603596Y35466D01*
X603471Y35426D01*
X603346Y35416D01*
G37*
G36*
G01X589173D02*
X589048Y35426D01*
X588923Y35466D01*
X588813Y35526D01*
X588713Y35606D01*
X588633Y35706D01*
X588573Y35816D01*
X588533Y35941D01*
X588523Y36066D01*
Y38191D01*
X588493Y38221D01*
X588468Y38256D01*
X588438Y38291D01*
X588418Y38326D01*
X588393Y38361D01*
X588353Y38441D01*
X588308Y38561D01*
X588298Y38601D01*
X588288Y38646D01*
X588283Y38686D01*
X588273Y38731D01*
Y38901D01*
X588283Y38946D01*
X588288Y38986D01*
X588298Y39031D01*
X588308Y39071D01*
X588353Y39191D01*
X588393Y39271D01*
X588418Y39306D01*
X588438Y39341D01*
X588468Y39376D01*
X588493Y39411D01*
X588523Y39441D01*
Y41866D01*
X588533Y41991D01*
X588573Y42116D01*
X588633Y42226D01*
X588713Y42326D01*
X588813Y42406D01*
X588923Y42466D01*
X589048Y42506D01*
X589173Y42516D01*
X589298Y42506D01*
X589423Y42466D01*
X589533Y42406D01*
X589633Y42326D01*
X589713Y42226D01*
X589773Y42116D01*
X589813Y41991D01*
X589823Y41866D01*
Y39436D01*
X589853Y39406D01*
X589953Y39266D01*
X589973Y39226D01*
X589988Y39191D01*
X590008Y39151D01*
X590023Y39111D01*
X590033Y39071D01*
X590048Y39026D01*
X590053Y38986D01*
X590063Y38946D01*
X590068Y38901D01*
Y38861D01*
X590073Y38816D01*
X590068Y38771D01*
Y38731D01*
X590063Y38686D01*
X590053Y38646D01*
X590048Y38606D01*
X590033Y38561D01*
X590023Y38521D01*
X590008Y38481D01*
X589988Y38441D01*
X589973Y38406D01*
X589953Y38366D01*
X589853Y38226D01*
X589823Y38196D01*
Y36066D01*
X589813Y35941D01*
X589773Y35816D01*
X589713Y35706D01*
X589633Y35606D01*
X589533Y35526D01*
X589423Y35466D01*
X589298Y35426D01*
X589173Y35416D01*
G37*
G36*
G01X617519D02*
X617394Y35426D01*
X617269Y35466D01*
X617159Y35526D01*
X617059Y35606D01*
X616979Y35706D01*
X616919Y35816D01*
X616879Y35941D01*
X616869Y36066D01*
Y38191D01*
X616839Y38221D01*
X616814Y38256D01*
X616784Y38291D01*
X616764Y38326D01*
X616739Y38361D01*
X616699Y38441D01*
X616654Y38561D01*
X616644Y38601D01*
X616634Y38646D01*
X616629Y38686D01*
X616619Y38731D01*
Y38901D01*
X616629Y38946D01*
X616634Y38986D01*
X616644Y39031D01*
X616654Y39071D01*
X616699Y39191D01*
X616739Y39271D01*
X616764Y39306D01*
X616784Y39341D01*
X616814Y39376D01*
X616839Y39411D01*
X616869Y39441D01*
Y41866D01*
X616879Y41991D01*
X616919Y42116D01*
X616979Y42226D01*
X617059Y42326D01*
X617159Y42406D01*
X617269Y42466D01*
X617394Y42506D01*
X617519Y42516D01*
X617644Y42506D01*
X617769Y42466D01*
X617879Y42406D01*
X617979Y42326D01*
X618059Y42226D01*
X618119Y42116D01*
X618159Y41991D01*
X618169Y41866D01*
Y39436D01*
X618199Y39406D01*
X618299Y39266D01*
X618319Y39226D01*
X618334Y39191D01*
X618354Y39151D01*
X618369Y39111D01*
X618379Y39071D01*
X618394Y39026D01*
X618399Y38986D01*
X618409Y38946D01*
X618414Y38901D01*
Y38861D01*
X618419Y38816D01*
X618414Y38771D01*
Y38731D01*
X618409Y38686D01*
X618399Y38646D01*
X618394Y38606D01*
X618379Y38561D01*
X618369Y38521D01*
X618354Y38481D01*
X618334Y38441D01*
X618319Y38406D01*
X618299Y38366D01*
X618199Y38226D01*
X618169Y38196D01*
Y36066D01*
X618159Y35941D01*
X618119Y35816D01*
X618059Y35706D01*
X617979Y35606D01*
X617879Y35526D01*
X617769Y35466D01*
X617644Y35426D01*
X617519Y35416D01*
G37*
G36*
G01X612795D02*
X612670Y35426D01*
X612545Y35466D01*
X612435Y35526D01*
X612335Y35606D01*
X612255Y35706D01*
X612195Y35816D01*
X612155Y35941D01*
X612145Y36066D01*
Y38191D01*
X612115Y38221D01*
X612090Y38256D01*
X612060Y38291D01*
X612040Y38326D01*
X612015Y38361D01*
X611975Y38441D01*
X611930Y38561D01*
X611920Y38601D01*
X611910Y38646D01*
X611905Y38686D01*
X611895Y38731D01*
Y38901D01*
X611905Y38946D01*
X611910Y38986D01*
X611920Y39031D01*
X611930Y39071D01*
X611975Y39191D01*
X612015Y39271D01*
X612040Y39306D01*
X612060Y39341D01*
X612090Y39376D01*
X612115Y39411D01*
X612145Y39441D01*
Y41866D01*
X612155Y41991D01*
X612195Y42116D01*
X612255Y42226D01*
X612335Y42326D01*
X612435Y42406D01*
X612545Y42466D01*
X612670Y42506D01*
X612795Y42516D01*
X612920Y42506D01*
X613045Y42466D01*
X613155Y42406D01*
X613255Y42326D01*
X613335Y42226D01*
X613395Y42116D01*
X613435Y41991D01*
X613445Y41866D01*
Y39436D01*
X613475Y39406D01*
X613575Y39266D01*
X613595Y39226D01*
X613610Y39191D01*
X613630Y39151D01*
X613645Y39111D01*
X613655Y39071D01*
X613670Y39026D01*
X613675Y38986D01*
X613685Y38946D01*
X613690Y38901D01*
Y38861D01*
X613695Y38816D01*
X613690Y38771D01*
Y38731D01*
X613685Y38686D01*
X613675Y38646D01*
X613670Y38606D01*
X613655Y38561D01*
X613645Y38521D01*
X613630Y38481D01*
X613610Y38441D01*
X613595Y38406D01*
X613575Y38366D01*
X613475Y38226D01*
X613445Y38196D01*
Y36066D01*
X613435Y35941D01*
X613395Y35816D01*
X613335Y35706D01*
X613255Y35606D01*
X613155Y35526D01*
X613045Y35466D01*
X612920Y35426D01*
X612795Y35416D01*
G37*
G36*
G01X608071D02*
X607946Y35426D01*
X607821Y35466D01*
X607711Y35526D01*
X607611Y35606D01*
X607531Y35706D01*
X607471Y35816D01*
X607431Y35941D01*
X607421Y36066D01*
Y38191D01*
X607391Y38221D01*
X607366Y38256D01*
X607336Y38291D01*
X607316Y38326D01*
X607291Y38361D01*
X607251Y38441D01*
X607206Y38561D01*
X607196Y38601D01*
X607186Y38646D01*
X607181Y38686D01*
X607171Y38731D01*
Y38901D01*
X607181Y38946D01*
X607186Y38986D01*
X607196Y39031D01*
X607206Y39071D01*
X607251Y39191D01*
X607291Y39271D01*
X607316Y39306D01*
X607336Y39341D01*
X607366Y39376D01*
X607391Y39411D01*
X607421Y39441D01*
Y41866D01*
X607431Y41991D01*
X607471Y42116D01*
X607531Y42226D01*
X607611Y42326D01*
X607711Y42406D01*
X607821Y42466D01*
X607946Y42506D01*
X608071Y42516D01*
X608196Y42506D01*
X608321Y42466D01*
X608431Y42406D01*
X608531Y42326D01*
X608611Y42226D01*
X608671Y42116D01*
X608711Y41991D01*
X608721Y41866D01*
Y39436D01*
X608751Y39406D01*
X608851Y39266D01*
X608871Y39226D01*
X608886Y39191D01*
X608906Y39151D01*
X608921Y39111D01*
X608931Y39071D01*
X608946Y39026D01*
X608951Y38986D01*
X608961Y38946D01*
X608966Y38901D01*
Y38861D01*
X608971Y38816D01*
X608966Y38771D01*
Y38731D01*
X608961Y38686D01*
X608951Y38646D01*
X608946Y38606D01*
X608931Y38561D01*
X608921Y38521D01*
X608906Y38481D01*
X608886Y38441D01*
X608871Y38406D01*
X608851Y38366D01*
X608751Y38226D01*
X608721Y38196D01*
Y36066D01*
X608711Y35941D01*
X608671Y35816D01*
X608611Y35706D01*
X608531Y35606D01*
X608431Y35526D01*
X608321Y35466D01*
X608196Y35426D01*
X608071Y35416D01*
G37*
G36*
G01X631693D02*
X631568Y35426D01*
X631443Y35466D01*
X631333Y35526D01*
X631233Y35606D01*
X631153Y35706D01*
X631093Y35816D01*
X631053Y35941D01*
X631043Y36066D01*
Y38191D01*
X631013Y38221D01*
X630988Y38256D01*
X630958Y38291D01*
X630938Y38326D01*
X630913Y38361D01*
X630873Y38441D01*
X630828Y38561D01*
X630818Y38601D01*
X630808Y38646D01*
X630803Y38686D01*
X630793Y38731D01*
Y38901D01*
X630803Y38946D01*
X630808Y38986D01*
X630818Y39031D01*
X630828Y39071D01*
X630873Y39191D01*
X630913Y39271D01*
X630938Y39306D01*
X630958Y39341D01*
X630988Y39376D01*
X631013Y39411D01*
X631043Y39441D01*
Y41866D01*
X631053Y41991D01*
X631093Y42116D01*
X631153Y42226D01*
X631233Y42326D01*
X631333Y42406D01*
X631443Y42466D01*
X631568Y42506D01*
X631693Y42516D01*
X631818Y42506D01*
X631943Y42466D01*
X632053Y42406D01*
X632153Y42326D01*
X632233Y42226D01*
X632293Y42116D01*
X632333Y41991D01*
X632343Y41866D01*
Y39436D01*
X632373Y39406D01*
X632473Y39266D01*
X632493Y39226D01*
X632508Y39191D01*
X632528Y39151D01*
X632543Y39111D01*
X632553Y39071D01*
X632568Y39026D01*
X632573Y38986D01*
X632583Y38946D01*
X632588Y38901D01*
Y38861D01*
X632593Y38816D01*
X632588Y38771D01*
Y38731D01*
X632583Y38686D01*
X632573Y38646D01*
X632568Y38606D01*
X632553Y38561D01*
X632543Y38521D01*
X632528Y38481D01*
X632508Y38441D01*
X632493Y38406D01*
X632473Y38366D01*
X632373Y38226D01*
X632343Y38196D01*
Y36066D01*
X632333Y35941D01*
X632293Y35816D01*
X632233Y35706D01*
X632153Y35606D01*
X632053Y35526D01*
X631943Y35466D01*
X631818Y35426D01*
X631693Y35416D01*
G37*
G36*
G01X626968D02*
X626843Y35426D01*
X626718Y35466D01*
X626608Y35526D01*
X626508Y35606D01*
X626428Y35706D01*
X626368Y35816D01*
X626328Y35941D01*
X626318Y36066D01*
Y38191D01*
X626288Y38221D01*
X626263Y38256D01*
X626233Y38291D01*
X626213Y38326D01*
X626188Y38361D01*
X626148Y38441D01*
X626103Y38561D01*
X626093Y38601D01*
X626083Y38646D01*
X626078Y38686D01*
X626068Y38731D01*
Y38901D01*
X626078Y38946D01*
X626083Y38986D01*
X626093Y39031D01*
X626103Y39071D01*
X626148Y39191D01*
X626188Y39271D01*
X626213Y39306D01*
X626233Y39341D01*
X626263Y39376D01*
X626288Y39411D01*
X626318Y39441D01*
Y41866D01*
X626328Y41991D01*
X626368Y42116D01*
X626428Y42226D01*
X626508Y42326D01*
X626608Y42406D01*
X626718Y42466D01*
X626843Y42506D01*
X626968Y42516D01*
X627093Y42506D01*
X627218Y42466D01*
X627328Y42406D01*
X627428Y42326D01*
X627508Y42226D01*
X627568Y42116D01*
X627608Y41991D01*
X627618Y41866D01*
Y39436D01*
X627648Y39406D01*
X627748Y39266D01*
X627768Y39226D01*
X627783Y39191D01*
X627803Y39151D01*
X627818Y39111D01*
X627828Y39071D01*
X627843Y39026D01*
X627848Y38986D01*
X627858Y38946D01*
X627863Y38901D01*
Y38861D01*
X627868Y38816D01*
X627863Y38771D01*
Y38731D01*
X627858Y38686D01*
X627848Y38646D01*
X627843Y38606D01*
X627828Y38561D01*
X627818Y38521D01*
X627803Y38481D01*
X627783Y38441D01*
X627768Y38406D01*
X627748Y38366D01*
X627648Y38226D01*
X627618Y38196D01*
Y36066D01*
X627608Y35941D01*
X627568Y35816D01*
X627508Y35706D01*
X627428Y35606D01*
X627328Y35526D01*
X627218Y35466D01*
X627093Y35426D01*
X626968Y35416D01*
G37*
G36*
G01X622244D02*
X622119Y35426D01*
X621994Y35466D01*
X621884Y35526D01*
X621784Y35606D01*
X621704Y35706D01*
X621644Y35816D01*
X621604Y35941D01*
X621594Y36066D01*
Y38191D01*
X621564Y38221D01*
X621539Y38256D01*
X621509Y38291D01*
X621489Y38326D01*
X621464Y38361D01*
X621424Y38441D01*
X621379Y38561D01*
X621369Y38601D01*
X621359Y38646D01*
X621354Y38686D01*
X621344Y38731D01*
Y38901D01*
X621354Y38946D01*
X621359Y38986D01*
X621369Y39031D01*
X621379Y39071D01*
X621424Y39191D01*
X621464Y39271D01*
X621489Y39306D01*
X621509Y39341D01*
X621539Y39376D01*
X621564Y39411D01*
X621594Y39441D01*
Y41866D01*
X621604Y41991D01*
X621644Y42116D01*
X621704Y42226D01*
X621784Y42326D01*
X621884Y42406D01*
X621994Y42466D01*
X622119Y42506D01*
X622244Y42516D01*
X622369Y42506D01*
X622494Y42466D01*
X622604Y42406D01*
X622704Y42326D01*
X622784Y42226D01*
X622844Y42116D01*
X622884Y41991D01*
X622894Y41866D01*
Y39436D01*
X622924Y39406D01*
X623024Y39266D01*
X623044Y39226D01*
X623059Y39191D01*
X623079Y39151D01*
X623094Y39111D01*
X623104Y39071D01*
X623119Y39026D01*
X623124Y38986D01*
X623134Y38946D01*
X623139Y38901D01*
Y38861D01*
X623144Y38816D01*
X623139Y38771D01*
Y38731D01*
X623134Y38686D01*
X623124Y38646D01*
X623119Y38606D01*
X623104Y38561D01*
X623094Y38521D01*
X623079Y38481D01*
X623059Y38441D01*
X623044Y38406D01*
X623024Y38366D01*
X622924Y38226D01*
X622894Y38196D01*
Y36066D01*
X622884Y35941D01*
X622844Y35816D01*
X622784Y35706D01*
X622704Y35606D01*
X622604Y35526D01*
X622494Y35466D01*
X622369Y35426D01*
X622244Y35416D01*
G37*
G36*
G01X645866D02*
X645741Y35426D01*
X645616Y35466D01*
X645506Y35526D01*
X645406Y35606D01*
X645326Y35706D01*
X645266Y35816D01*
X645226Y35941D01*
X645216Y36066D01*
Y38191D01*
X645186Y38221D01*
X645161Y38256D01*
X645131Y38291D01*
X645111Y38326D01*
X645086Y38361D01*
X645046Y38441D01*
X645001Y38561D01*
X644991Y38601D01*
X644981Y38646D01*
X644976Y38686D01*
X644966Y38731D01*
Y38901D01*
X644976Y38946D01*
X644981Y38986D01*
X644991Y39031D01*
X645001Y39071D01*
X645046Y39191D01*
X645086Y39271D01*
X645111Y39306D01*
X645131Y39341D01*
X645161Y39376D01*
X645186Y39411D01*
X645216Y39441D01*
Y41866D01*
X645226Y41991D01*
X645266Y42116D01*
X645326Y42226D01*
X645406Y42326D01*
X645506Y42406D01*
X645616Y42466D01*
X645741Y42506D01*
X645866Y42516D01*
X645991Y42506D01*
X646116Y42466D01*
X646226Y42406D01*
X646326Y42326D01*
X646406Y42226D01*
X646466Y42116D01*
X646506Y41991D01*
X646516Y41866D01*
Y39436D01*
X646546Y39406D01*
X646646Y39266D01*
X646666Y39226D01*
X646681Y39191D01*
X646701Y39151D01*
X646716Y39111D01*
X646726Y39071D01*
X646741Y39026D01*
X646746Y38986D01*
X646756Y38946D01*
X646761Y38901D01*
Y38861D01*
X646766Y38816D01*
X646761Y38771D01*
Y38731D01*
X646756Y38686D01*
X646746Y38646D01*
X646741Y38606D01*
X646726Y38561D01*
X646716Y38521D01*
X646701Y38481D01*
X646681Y38441D01*
X646666Y38406D01*
X646646Y38366D01*
X646546Y38226D01*
X646516Y38196D01*
Y36066D01*
X646506Y35941D01*
X646466Y35816D01*
X646406Y35706D01*
X646326Y35606D01*
X646226Y35526D01*
X646116Y35466D01*
X645991Y35426D01*
X645866Y35416D01*
G37*
G36*
G01X641141D02*
X641016Y35426D01*
X640891Y35466D01*
X640781Y35526D01*
X640681Y35606D01*
X640601Y35706D01*
X640541Y35816D01*
X640501Y35941D01*
X640491Y36066D01*
Y38191D01*
X640461Y38221D01*
X640436Y38256D01*
X640406Y38291D01*
X640386Y38326D01*
X640361Y38361D01*
X640321Y38441D01*
X640276Y38561D01*
X640266Y38601D01*
X640256Y38646D01*
X640251Y38686D01*
X640241Y38731D01*
Y38901D01*
X640251Y38946D01*
X640256Y38986D01*
X640266Y39031D01*
X640276Y39071D01*
X640321Y39191D01*
X640361Y39271D01*
X640386Y39306D01*
X640406Y39341D01*
X640436Y39376D01*
X640461Y39411D01*
X640491Y39441D01*
Y41866D01*
X640501Y41991D01*
X640541Y42116D01*
X640601Y42226D01*
X640681Y42326D01*
X640781Y42406D01*
X640891Y42466D01*
X641016Y42506D01*
X641141Y42516D01*
X641266Y42506D01*
X641391Y42466D01*
X641501Y42406D01*
X641601Y42326D01*
X641681Y42226D01*
X641741Y42116D01*
X641781Y41991D01*
X641791Y41866D01*
Y39436D01*
X641821Y39406D01*
X641921Y39266D01*
X641941Y39226D01*
X641956Y39191D01*
X641976Y39151D01*
X641991Y39111D01*
X642001Y39071D01*
X642016Y39026D01*
X642021Y38986D01*
X642031Y38946D01*
X642036Y38901D01*
Y38861D01*
X642041Y38816D01*
X642036Y38771D01*
Y38731D01*
X642031Y38686D01*
X642021Y38646D01*
X642016Y38606D01*
X642001Y38561D01*
X641991Y38521D01*
X641976Y38481D01*
X641956Y38441D01*
X641941Y38406D01*
X641921Y38366D01*
X641821Y38226D01*
X641791Y38196D01*
Y36066D01*
X641781Y35941D01*
X641741Y35816D01*
X641681Y35706D01*
X641601Y35606D01*
X641501Y35526D01*
X641391Y35466D01*
X641266Y35426D01*
X641141Y35416D01*
G37*
G36*
G01X636417D02*
X636292Y35426D01*
X636167Y35466D01*
X636057Y35526D01*
X635957Y35606D01*
X635877Y35706D01*
X635817Y35816D01*
X635777Y35941D01*
X635767Y36066D01*
Y38191D01*
X635737Y38221D01*
X635712Y38256D01*
X635682Y38291D01*
X635662Y38326D01*
X635637Y38361D01*
X635597Y38441D01*
X635552Y38561D01*
X635542Y38601D01*
X635532Y38646D01*
X635527Y38686D01*
X635517Y38731D01*
Y38901D01*
X635527Y38946D01*
X635532Y38986D01*
X635542Y39031D01*
X635552Y39071D01*
X635597Y39191D01*
X635637Y39271D01*
X635662Y39306D01*
X635682Y39341D01*
X635712Y39376D01*
X635737Y39411D01*
X635767Y39441D01*
Y41866D01*
X635777Y41991D01*
X635817Y42116D01*
X635877Y42226D01*
X635957Y42326D01*
X636057Y42406D01*
X636167Y42466D01*
X636292Y42506D01*
X636417Y42516D01*
X636542Y42506D01*
X636667Y42466D01*
X636777Y42406D01*
X636877Y42326D01*
X636957Y42226D01*
X637017Y42116D01*
X637057Y41991D01*
X637067Y41866D01*
Y39436D01*
X637097Y39406D01*
X637197Y39266D01*
X637217Y39226D01*
X637232Y39191D01*
X637252Y39151D01*
X637267Y39111D01*
X637277Y39071D01*
X637292Y39026D01*
X637297Y38986D01*
X637307Y38946D01*
X637312Y38901D01*
Y38861D01*
X637317Y38816D01*
X637312Y38771D01*
Y38731D01*
X637307Y38686D01*
X637297Y38646D01*
X637292Y38606D01*
X637277Y38561D01*
X637267Y38521D01*
X637252Y38481D01*
X637232Y38441D01*
X637217Y38406D01*
X637197Y38366D01*
X637097Y38226D01*
X637067Y38196D01*
Y36066D01*
X637057Y35941D01*
X637017Y35816D01*
X636957Y35706D01*
X636877Y35606D01*
X636777Y35526D01*
X636667Y35466D01*
X636542Y35426D01*
X636417Y35416D01*
G37*
G36*
G01X664764D02*
X664639Y35426D01*
X664514Y35466D01*
X664404Y35526D01*
X664304Y35606D01*
X664224Y35706D01*
X664164Y35816D01*
X664124Y35941D01*
X664114Y36066D01*
Y38191D01*
X664084Y38221D01*
X664059Y38256D01*
X664029Y38291D01*
X664009Y38326D01*
X663984Y38361D01*
X663944Y38441D01*
X663899Y38561D01*
X663889Y38601D01*
X663879Y38646D01*
X663874Y38686D01*
X663864Y38731D01*
Y38901D01*
X663874Y38946D01*
X663879Y38986D01*
X663889Y39031D01*
X663899Y39071D01*
X663944Y39191D01*
X663984Y39271D01*
X664009Y39306D01*
X664029Y39341D01*
X664059Y39376D01*
X664084Y39411D01*
X664114Y39441D01*
Y41866D01*
X664124Y41991D01*
X664164Y42116D01*
X664224Y42226D01*
X664304Y42326D01*
X664404Y42406D01*
X664514Y42466D01*
X664639Y42506D01*
X664764Y42516D01*
X664889Y42506D01*
X665014Y42466D01*
X665124Y42406D01*
X665224Y42326D01*
X665304Y42226D01*
X665364Y42116D01*
X665404Y41991D01*
X665414Y41866D01*
Y39436D01*
X665444Y39406D01*
X665544Y39266D01*
X665564Y39226D01*
X665579Y39191D01*
X665599Y39151D01*
X665614Y39111D01*
X665624Y39071D01*
X665639Y39026D01*
X665644Y38986D01*
X665654Y38946D01*
X665659Y38901D01*
Y38861D01*
X665664Y38816D01*
X665659Y38771D01*
Y38731D01*
X665654Y38686D01*
X665644Y38646D01*
X665639Y38606D01*
X665624Y38561D01*
X665614Y38521D01*
X665599Y38481D01*
X665579Y38441D01*
X665564Y38406D01*
X665544Y38366D01*
X665444Y38226D01*
X665414Y38196D01*
Y36066D01*
X665404Y35941D01*
X665364Y35816D01*
X665304Y35706D01*
X665224Y35606D01*
X665124Y35526D01*
X665014Y35466D01*
X664889Y35426D01*
X664764Y35416D01*
G37*
G36*
G01X660039D02*
X659914Y35426D01*
X659789Y35466D01*
X659679Y35526D01*
X659579Y35606D01*
X659499Y35706D01*
X659439Y35816D01*
X659399Y35941D01*
X659389Y36066D01*
Y38191D01*
X659359Y38221D01*
X659334Y38256D01*
X659304Y38291D01*
X659284Y38326D01*
X659259Y38361D01*
X659219Y38441D01*
X659174Y38561D01*
X659164Y38601D01*
X659154Y38646D01*
X659149Y38686D01*
X659139Y38731D01*
Y38901D01*
X659149Y38946D01*
X659154Y38986D01*
X659164Y39031D01*
X659174Y39071D01*
X659219Y39191D01*
X659259Y39271D01*
X659284Y39306D01*
X659304Y39341D01*
X659334Y39376D01*
X659359Y39411D01*
X659389Y39441D01*
Y41866D01*
X659399Y41991D01*
X659439Y42116D01*
X659499Y42226D01*
X659579Y42326D01*
X659679Y42406D01*
X659789Y42466D01*
X659914Y42506D01*
X660039Y42516D01*
X660164Y42506D01*
X660289Y42466D01*
X660399Y42406D01*
X660499Y42326D01*
X660579Y42226D01*
X660639Y42116D01*
X660679Y41991D01*
X660689Y41866D01*
Y39436D01*
X660719Y39406D01*
X660819Y39266D01*
X660839Y39226D01*
X660854Y39191D01*
X660874Y39151D01*
X660889Y39111D01*
X660899Y39071D01*
X660914Y39026D01*
X660919Y38986D01*
X660929Y38946D01*
X660934Y38901D01*
Y38861D01*
X660939Y38816D01*
X660934Y38771D01*
Y38731D01*
X660929Y38686D01*
X660919Y38646D01*
X660914Y38606D01*
X660899Y38561D01*
X660889Y38521D01*
X660874Y38481D01*
X660854Y38441D01*
X660839Y38406D01*
X660819Y38366D01*
X660719Y38226D01*
X660689Y38196D01*
Y36066D01*
X660679Y35941D01*
X660639Y35816D01*
X660579Y35706D01*
X660499Y35606D01*
X660399Y35526D01*
X660289Y35466D01*
X660164Y35426D01*
X660039Y35416D01*
G37*
G36*
G01X655315D02*
X655190Y35426D01*
X655065Y35466D01*
X654955Y35526D01*
X654855Y35606D01*
X654775Y35706D01*
X654715Y35816D01*
X654675Y35941D01*
X654665Y36066D01*
Y38191D01*
X654635Y38221D01*
X654610Y38256D01*
X654580Y38291D01*
X654560Y38326D01*
X654535Y38361D01*
X654495Y38441D01*
X654450Y38561D01*
X654440Y38601D01*
X654430Y38646D01*
X654425Y38686D01*
X654415Y38731D01*
Y38901D01*
X654425Y38946D01*
X654430Y38986D01*
X654440Y39031D01*
X654450Y39071D01*
X654495Y39191D01*
X654535Y39271D01*
X654560Y39306D01*
X654580Y39341D01*
X654610Y39376D01*
X654635Y39411D01*
X654665Y39441D01*
Y41866D01*
X654675Y41991D01*
X654715Y42116D01*
X654775Y42226D01*
X654855Y42326D01*
X654955Y42406D01*
X655065Y42466D01*
X655190Y42506D01*
X655315Y42516D01*
X655440Y42506D01*
X655565Y42466D01*
X655675Y42406D01*
X655775Y42326D01*
X655855Y42226D01*
X655915Y42116D01*
X655955Y41991D01*
X655965Y41866D01*
Y39436D01*
X655995Y39406D01*
X656095Y39266D01*
X656115Y39226D01*
X656130Y39191D01*
X656150Y39151D01*
X656165Y39111D01*
X656175Y39071D01*
X656190Y39026D01*
X656195Y38986D01*
X656205Y38946D01*
X656210Y38901D01*
Y38861D01*
X656215Y38816D01*
X656210Y38771D01*
Y38731D01*
X656205Y38686D01*
X656195Y38646D01*
X656190Y38606D01*
X656175Y38561D01*
X656165Y38521D01*
X656150Y38481D01*
X656130Y38441D01*
X656115Y38406D01*
X656095Y38366D01*
X655995Y38226D01*
X655965Y38196D01*
Y36066D01*
X655955Y35941D01*
X655915Y35816D01*
X655855Y35706D01*
X655775Y35606D01*
X655675Y35526D01*
X655565Y35466D01*
X655440Y35426D01*
X655315Y35416D01*
G37*
G36*
G01X650590D02*
X650465Y35426D01*
X650340Y35466D01*
X650230Y35526D01*
X650130Y35606D01*
X650050Y35706D01*
X649990Y35816D01*
X649950Y35941D01*
X649940Y36066D01*
Y38191D01*
X649910Y38221D01*
X649885Y38256D01*
X649855Y38291D01*
X649835Y38326D01*
X649810Y38361D01*
X649770Y38441D01*
X649725Y38561D01*
X649715Y38601D01*
X649705Y38646D01*
X649700Y38686D01*
X649690Y38731D01*
Y38901D01*
X649700Y38946D01*
X649705Y38986D01*
X649715Y39031D01*
X649725Y39071D01*
X649770Y39191D01*
X649810Y39271D01*
X649835Y39306D01*
X649855Y39341D01*
X649885Y39376D01*
X649910Y39411D01*
X649940Y39441D01*
Y41866D01*
X649950Y41991D01*
X649990Y42116D01*
X650050Y42226D01*
X650130Y42326D01*
X650230Y42406D01*
X650340Y42466D01*
X650465Y42506D01*
X650590Y42516D01*
X650715Y42506D01*
X650840Y42466D01*
X650950Y42406D01*
X651050Y42326D01*
X651130Y42226D01*
X651190Y42116D01*
X651230Y41991D01*
X651240Y41866D01*
Y39436D01*
X651270Y39406D01*
X651370Y39266D01*
X651390Y39226D01*
X651405Y39191D01*
X651425Y39151D01*
X651440Y39111D01*
X651450Y39071D01*
X651465Y39026D01*
X651470Y38986D01*
X651480Y38946D01*
X651485Y38901D01*
Y38861D01*
X651490Y38816D01*
X651485Y38771D01*
Y38731D01*
X651480Y38686D01*
X651470Y38646D01*
X651465Y38606D01*
X651450Y38561D01*
X651440Y38521D01*
X651425Y38481D01*
X651405Y38441D01*
X651390Y38406D01*
X651370Y38366D01*
X651270Y38226D01*
X651240Y38196D01*
Y36066D01*
X651230Y35941D01*
X651190Y35816D01*
X651130Y35706D01*
X651050Y35606D01*
X650950Y35526D01*
X650840Y35466D01*
X650715Y35426D01*
X650590Y35416D01*
G37*
G36*
G01X678937D02*
X678812Y35426D01*
X678687Y35466D01*
X678577Y35526D01*
X678477Y35606D01*
X678397Y35706D01*
X678337Y35816D01*
X678297Y35941D01*
X678287Y36066D01*
Y38191D01*
X678257Y38221D01*
X678232Y38256D01*
X678202Y38291D01*
X678182Y38326D01*
X678157Y38361D01*
X678117Y38441D01*
X678072Y38561D01*
X678062Y38601D01*
X678052Y38646D01*
X678047Y38686D01*
X678037Y38731D01*
Y38901D01*
X678047Y38946D01*
X678052Y38986D01*
X678062Y39031D01*
X678072Y39071D01*
X678117Y39191D01*
X678157Y39271D01*
X678182Y39306D01*
X678202Y39341D01*
X678232Y39376D01*
X678257Y39411D01*
X678287Y39441D01*
Y41866D01*
X678297Y41991D01*
X678337Y42116D01*
X678397Y42226D01*
X678477Y42326D01*
X678577Y42406D01*
X678687Y42466D01*
X678812Y42506D01*
X678937Y42516D01*
X679062Y42506D01*
X679187Y42466D01*
X679297Y42406D01*
X679397Y42326D01*
X679477Y42226D01*
X679537Y42116D01*
X679577Y41991D01*
X679587Y41866D01*
Y39436D01*
X679617Y39406D01*
X679717Y39266D01*
X679737Y39226D01*
X679752Y39191D01*
X679772Y39151D01*
X679787Y39111D01*
X679797Y39071D01*
X679812Y39026D01*
X679817Y38986D01*
X679827Y38946D01*
X679832Y38901D01*
Y38861D01*
X679837Y38816D01*
X679832Y38771D01*
Y38731D01*
X679827Y38686D01*
X679817Y38646D01*
X679812Y38606D01*
X679797Y38561D01*
X679787Y38521D01*
X679772Y38481D01*
X679752Y38441D01*
X679737Y38406D01*
X679717Y38366D01*
X679617Y38226D01*
X679587Y38196D01*
Y36066D01*
X679577Y35941D01*
X679537Y35816D01*
X679477Y35706D01*
X679397Y35606D01*
X679297Y35526D01*
X679187Y35466D01*
X679062Y35426D01*
X678937Y35416D01*
G37*
G36*
G01X674212D02*
X674087Y35426D01*
X673962Y35466D01*
X673852Y35526D01*
X673752Y35606D01*
X673672Y35706D01*
X673612Y35816D01*
X673572Y35941D01*
X673562Y36066D01*
Y38191D01*
X673532Y38221D01*
X673507Y38256D01*
X673477Y38291D01*
X673457Y38326D01*
X673432Y38361D01*
X673392Y38441D01*
X673347Y38561D01*
X673337Y38601D01*
X673327Y38646D01*
X673322Y38686D01*
X673312Y38731D01*
Y38901D01*
X673322Y38946D01*
X673327Y38986D01*
X673337Y39031D01*
X673347Y39071D01*
X673392Y39191D01*
X673432Y39271D01*
X673457Y39306D01*
X673477Y39341D01*
X673507Y39376D01*
X673532Y39411D01*
X673562Y39441D01*
Y41866D01*
X673572Y41991D01*
X673612Y42116D01*
X673672Y42226D01*
X673752Y42326D01*
X673852Y42406D01*
X673962Y42466D01*
X674087Y42506D01*
X674212Y42516D01*
X674337Y42506D01*
X674462Y42466D01*
X674572Y42406D01*
X674672Y42326D01*
X674752Y42226D01*
X674812Y42116D01*
X674852Y41991D01*
X674862Y41866D01*
Y39436D01*
X674892Y39406D01*
X674992Y39266D01*
X675012Y39226D01*
X675027Y39191D01*
X675047Y39151D01*
X675062Y39111D01*
X675072Y39071D01*
X675087Y39026D01*
X675092Y38986D01*
X675102Y38946D01*
X675107Y38901D01*
Y38861D01*
X675112Y38816D01*
X675107Y38771D01*
Y38731D01*
X675102Y38686D01*
X675092Y38646D01*
X675087Y38606D01*
X675072Y38561D01*
X675062Y38521D01*
X675047Y38481D01*
X675027Y38441D01*
X675012Y38406D01*
X674992Y38366D01*
X674892Y38226D01*
X674862Y38196D01*
Y36066D01*
X674852Y35941D01*
X674812Y35816D01*
X674752Y35706D01*
X674672Y35606D01*
X674572Y35526D01*
X674462Y35466D01*
X674337Y35426D01*
X674212Y35416D01*
G37*
G36*
G01X669488D02*
X669363Y35426D01*
X669238Y35466D01*
X669128Y35526D01*
X669028Y35606D01*
X668948Y35706D01*
X668888Y35816D01*
X668848Y35941D01*
X668838Y36066D01*
Y38191D01*
X668808Y38221D01*
X668783Y38256D01*
X668753Y38291D01*
X668733Y38326D01*
X668708Y38361D01*
X668668Y38441D01*
X668623Y38561D01*
X668613Y38601D01*
X668603Y38646D01*
X668598Y38686D01*
X668588Y38731D01*
Y38901D01*
X668598Y38946D01*
X668603Y38986D01*
X668613Y39031D01*
X668623Y39071D01*
X668668Y39191D01*
X668708Y39271D01*
X668733Y39306D01*
X668753Y39341D01*
X668783Y39376D01*
X668808Y39411D01*
X668838Y39441D01*
Y41866D01*
X668848Y41991D01*
X668888Y42116D01*
X668948Y42226D01*
X669028Y42326D01*
X669128Y42406D01*
X669238Y42466D01*
X669363Y42506D01*
X669488Y42516D01*
X669613Y42506D01*
X669738Y42466D01*
X669848Y42406D01*
X669948Y42326D01*
X670028Y42226D01*
X670088Y42116D01*
X670128Y41991D01*
X670138Y41866D01*
Y39436D01*
X670168Y39406D01*
X670268Y39266D01*
X670288Y39226D01*
X670303Y39191D01*
X670323Y39151D01*
X670338Y39111D01*
X670348Y39071D01*
X670363Y39026D01*
X670368Y38986D01*
X670378Y38946D01*
X670383Y38901D01*
Y38861D01*
X670388Y38816D01*
X670383Y38771D01*
Y38731D01*
X670378Y38686D01*
X670368Y38646D01*
X670363Y38606D01*
X670348Y38561D01*
X670338Y38521D01*
X670323Y38481D01*
X670303Y38441D01*
X670288Y38406D01*
X670268Y38366D01*
X670168Y38226D01*
X670138Y38196D01*
Y36066D01*
X670128Y35941D01*
X670088Y35816D01*
X670028Y35706D01*
X669948Y35606D01*
X669848Y35526D01*
X669738Y35466D01*
X669613Y35426D01*
X669488Y35416D01*
G37*
G36*
G01X693110D02*
X692985Y35426D01*
X692860Y35466D01*
X692750Y35526D01*
X692650Y35606D01*
X692570Y35706D01*
X692510Y35816D01*
X692470Y35941D01*
X692460Y36066D01*
Y38191D01*
X692430Y38221D01*
X692405Y38256D01*
X692375Y38291D01*
X692355Y38326D01*
X692330Y38361D01*
X692290Y38441D01*
X692245Y38561D01*
X692235Y38601D01*
X692225Y38646D01*
X692220Y38686D01*
X692210Y38731D01*
Y38901D01*
X692220Y38946D01*
X692225Y38986D01*
X692235Y39031D01*
X692245Y39071D01*
X692290Y39191D01*
X692330Y39271D01*
X692355Y39306D01*
X692375Y39341D01*
X692405Y39376D01*
X692430Y39411D01*
X692460Y39441D01*
Y41866D01*
X692470Y41991D01*
X692510Y42116D01*
X692570Y42226D01*
X692650Y42326D01*
X692750Y42406D01*
X692860Y42466D01*
X692985Y42506D01*
X693110Y42516D01*
X693235Y42506D01*
X693360Y42466D01*
X693470Y42406D01*
X693570Y42326D01*
X693650Y42226D01*
X693710Y42116D01*
X693750Y41991D01*
X693760Y41866D01*
Y39436D01*
X693790Y39406D01*
X693890Y39266D01*
X693910Y39226D01*
X693925Y39191D01*
X693945Y39151D01*
X693960Y39111D01*
X693970Y39071D01*
X693985Y39026D01*
X693990Y38986D01*
X694000Y38946D01*
X694005Y38901D01*
Y38861D01*
X694010Y38816D01*
X694005Y38771D01*
Y38731D01*
X694000Y38686D01*
X693990Y38646D01*
X693985Y38606D01*
X693970Y38561D01*
X693960Y38521D01*
X693945Y38481D01*
X693925Y38441D01*
X693910Y38406D01*
X693890Y38366D01*
X693790Y38226D01*
X693760Y38196D01*
Y36066D01*
X693750Y35941D01*
X693710Y35816D01*
X693650Y35706D01*
X693570Y35606D01*
X693470Y35526D01*
X693360Y35466D01*
X693235Y35426D01*
X693110Y35416D01*
G37*
G36*
G01X688386D02*
X688261Y35426D01*
X688136Y35466D01*
X688026Y35526D01*
X687926Y35606D01*
X687846Y35706D01*
X687786Y35816D01*
X687746Y35941D01*
X687736Y36066D01*
Y38191D01*
X687706Y38221D01*
X687681Y38256D01*
X687651Y38291D01*
X687631Y38326D01*
X687606Y38361D01*
X687566Y38441D01*
X687521Y38561D01*
X687511Y38601D01*
X687501Y38646D01*
X687496Y38686D01*
X687486Y38731D01*
Y38901D01*
X687496Y38946D01*
X687501Y38986D01*
X687511Y39031D01*
X687521Y39071D01*
X687566Y39191D01*
X687606Y39271D01*
X687631Y39306D01*
X687651Y39341D01*
X687681Y39376D01*
X687706Y39411D01*
X687736Y39441D01*
Y41866D01*
X687746Y41991D01*
X687786Y42116D01*
X687846Y42226D01*
X687926Y42326D01*
X688026Y42406D01*
X688136Y42466D01*
X688261Y42506D01*
X688386Y42516D01*
X688511Y42506D01*
X688636Y42466D01*
X688746Y42406D01*
X688846Y42326D01*
X688926Y42226D01*
X688986Y42116D01*
X689026Y41991D01*
X689036Y41866D01*
Y39436D01*
X689066Y39406D01*
X689166Y39266D01*
X689186Y39226D01*
X689201Y39191D01*
X689221Y39151D01*
X689236Y39111D01*
X689246Y39071D01*
X689261Y39026D01*
X689266Y38986D01*
X689276Y38946D01*
X689281Y38901D01*
Y38861D01*
X689286Y38816D01*
X689281Y38771D01*
Y38731D01*
X689276Y38686D01*
X689266Y38646D01*
X689261Y38606D01*
X689246Y38561D01*
X689236Y38521D01*
X689221Y38481D01*
X689201Y38441D01*
X689186Y38406D01*
X689166Y38366D01*
X689066Y38226D01*
X689036Y38196D01*
Y36066D01*
X689026Y35941D01*
X688986Y35816D01*
X688926Y35706D01*
X688846Y35606D01*
X688746Y35526D01*
X688636Y35466D01*
X688511Y35426D01*
X688386Y35416D01*
G37*
G36*
G01X683661D02*
X683536Y35426D01*
X683411Y35466D01*
X683301Y35526D01*
X683201Y35606D01*
X683121Y35706D01*
X683061Y35816D01*
X683021Y35941D01*
X683011Y36066D01*
Y38191D01*
X682981Y38221D01*
X682956Y38256D01*
X682926Y38291D01*
X682906Y38326D01*
X682881Y38361D01*
X682841Y38441D01*
X682796Y38561D01*
X682786Y38601D01*
X682776Y38646D01*
X682771Y38686D01*
X682761Y38731D01*
Y38901D01*
X682771Y38946D01*
X682776Y38986D01*
X682786Y39031D01*
X682796Y39071D01*
X682841Y39191D01*
X682881Y39271D01*
X682906Y39306D01*
X682926Y39341D01*
X682956Y39376D01*
X682981Y39411D01*
X683011Y39441D01*
Y41866D01*
X683021Y41991D01*
X683061Y42116D01*
X683121Y42226D01*
X683201Y42326D01*
X683301Y42406D01*
X683411Y42466D01*
X683536Y42506D01*
X683661Y42516D01*
X683786Y42506D01*
X683911Y42466D01*
X684021Y42406D01*
X684121Y42326D01*
X684201Y42226D01*
X684261Y42116D01*
X684301Y41991D01*
X684311Y41866D01*
Y39436D01*
X684341Y39406D01*
X684441Y39266D01*
X684461Y39226D01*
X684476Y39191D01*
X684496Y39151D01*
X684511Y39111D01*
X684521Y39071D01*
X684536Y39026D01*
X684541Y38986D01*
X684551Y38946D01*
X684556Y38901D01*
Y38861D01*
X684561Y38816D01*
X684556Y38771D01*
Y38731D01*
X684551Y38686D01*
X684541Y38646D01*
X684536Y38606D01*
X684521Y38561D01*
X684511Y38521D01*
X684496Y38481D01*
X684476Y38441D01*
X684461Y38406D01*
X684441Y38366D01*
X684341Y38226D01*
X684311Y38196D01*
Y36066D01*
X684301Y35941D01*
X684261Y35816D01*
X684201Y35706D01*
X684121Y35606D01*
X684021Y35526D01*
X683911Y35466D01*
X683786Y35426D01*
X683661Y35416D01*
G37*
G36*
G01X707283D02*
X707158Y35426D01*
X707033Y35466D01*
X706923Y35526D01*
X706823Y35606D01*
X706743Y35706D01*
X706683Y35816D01*
X706643Y35941D01*
X706633Y36066D01*
Y38191D01*
X706603Y38221D01*
X706578Y38256D01*
X706548Y38291D01*
X706528Y38326D01*
X706503Y38361D01*
X706463Y38441D01*
X706418Y38561D01*
X706408Y38601D01*
X706398Y38646D01*
X706393Y38686D01*
X706383Y38731D01*
Y38901D01*
X706393Y38946D01*
X706398Y38986D01*
X706408Y39031D01*
X706418Y39071D01*
X706463Y39191D01*
X706503Y39271D01*
X706528Y39306D01*
X706548Y39341D01*
X706578Y39376D01*
X706603Y39411D01*
X706633Y39441D01*
Y41866D01*
X706643Y41991D01*
X706683Y42116D01*
X706743Y42226D01*
X706823Y42326D01*
X706923Y42406D01*
X707033Y42466D01*
X707158Y42506D01*
X707283Y42516D01*
X707408Y42506D01*
X707533Y42466D01*
X707643Y42406D01*
X707743Y42326D01*
X707823Y42226D01*
X707883Y42116D01*
X707923Y41991D01*
X707933Y41866D01*
Y39436D01*
X707963Y39406D01*
X708063Y39266D01*
X708083Y39226D01*
X708098Y39191D01*
X708118Y39151D01*
X708133Y39111D01*
X708143Y39071D01*
X708158Y39026D01*
X708163Y38986D01*
X708173Y38946D01*
X708178Y38901D01*
Y38861D01*
X708183Y38816D01*
X708178Y38771D01*
Y38731D01*
X708173Y38686D01*
X708163Y38646D01*
X708158Y38606D01*
X708143Y38561D01*
X708133Y38521D01*
X708118Y38481D01*
X708098Y38441D01*
X708083Y38406D01*
X708063Y38366D01*
X707963Y38226D01*
X707933Y38196D01*
Y36066D01*
X707923Y35941D01*
X707883Y35816D01*
X707823Y35706D01*
X707743Y35606D01*
X707643Y35526D01*
X707533Y35466D01*
X707408Y35426D01*
X707283Y35416D01*
G37*
G36*
G01X702559D02*
X702434Y35426D01*
X702309Y35466D01*
X702199Y35526D01*
X702099Y35606D01*
X702019Y35706D01*
X701959Y35816D01*
X701919Y35941D01*
X701909Y36066D01*
Y38191D01*
X701879Y38221D01*
X701854Y38256D01*
X701824Y38291D01*
X701804Y38326D01*
X701779Y38361D01*
X701739Y38441D01*
X701694Y38561D01*
X701684Y38601D01*
X701674Y38646D01*
X701669Y38686D01*
X701659Y38731D01*
Y38901D01*
X701669Y38946D01*
X701674Y38986D01*
X701684Y39031D01*
X701694Y39071D01*
X701739Y39191D01*
X701779Y39271D01*
X701804Y39306D01*
X701824Y39341D01*
X701854Y39376D01*
X701879Y39411D01*
X701909Y39441D01*
Y41866D01*
X701919Y41991D01*
X701959Y42116D01*
X702019Y42226D01*
X702099Y42326D01*
X702199Y42406D01*
X702309Y42466D01*
X702434Y42506D01*
X702559Y42516D01*
X702684Y42506D01*
X702809Y42466D01*
X702919Y42406D01*
X703019Y42326D01*
X703099Y42226D01*
X703159Y42116D01*
X703199Y41991D01*
X703209Y41866D01*
Y39436D01*
X703239Y39406D01*
X703339Y39266D01*
X703359Y39226D01*
X703374Y39191D01*
X703394Y39151D01*
X703409Y39111D01*
X703419Y39071D01*
X703434Y39026D01*
X703439Y38986D01*
X703449Y38946D01*
X703454Y38901D01*
Y38861D01*
X703459Y38816D01*
X703454Y38771D01*
Y38731D01*
X703449Y38686D01*
X703439Y38646D01*
X703434Y38606D01*
X703419Y38561D01*
X703409Y38521D01*
X703394Y38481D01*
X703374Y38441D01*
X703359Y38406D01*
X703339Y38366D01*
X703239Y38226D01*
X703209Y38196D01*
Y36066D01*
X703199Y35941D01*
X703159Y35816D01*
X703099Y35706D01*
X703019Y35606D01*
X702919Y35526D01*
X702809Y35466D01*
X702684Y35426D01*
X702559Y35416D01*
G37*
G36*
G01X697834D02*
X697709Y35426D01*
X697584Y35466D01*
X697474Y35526D01*
X697374Y35606D01*
X697294Y35706D01*
X697234Y35816D01*
X697194Y35941D01*
X697184Y36066D01*
Y38191D01*
X697154Y38221D01*
X697129Y38256D01*
X697099Y38291D01*
X697079Y38326D01*
X697054Y38361D01*
X697014Y38441D01*
X696969Y38561D01*
X696959Y38601D01*
X696949Y38646D01*
X696944Y38686D01*
X696934Y38731D01*
Y38901D01*
X696944Y38946D01*
X696949Y38986D01*
X696959Y39031D01*
X696969Y39071D01*
X697014Y39191D01*
X697054Y39271D01*
X697079Y39306D01*
X697099Y39341D01*
X697129Y39376D01*
X697154Y39411D01*
X697184Y39441D01*
Y41866D01*
X697194Y41991D01*
X697234Y42116D01*
X697294Y42226D01*
X697374Y42326D01*
X697474Y42406D01*
X697584Y42466D01*
X697709Y42506D01*
X697834Y42516D01*
X697959Y42506D01*
X698084Y42466D01*
X698194Y42406D01*
X698294Y42326D01*
X698374Y42226D01*
X698434Y42116D01*
X698474Y41991D01*
X698484Y41866D01*
Y39436D01*
X698514Y39406D01*
X698614Y39266D01*
X698634Y39226D01*
X698649Y39191D01*
X698669Y39151D01*
X698684Y39111D01*
X698694Y39071D01*
X698709Y39026D01*
X698714Y38986D01*
X698724Y38946D01*
X698729Y38901D01*
Y38861D01*
X698734Y38816D01*
X698729Y38771D01*
Y38731D01*
X698724Y38686D01*
X698714Y38646D01*
X698709Y38606D01*
X698694Y38561D01*
X698684Y38521D01*
X698669Y38481D01*
X698649Y38441D01*
X698634Y38406D01*
X698614Y38366D01*
X698514Y38226D01*
X698484Y38196D01*
Y36066D01*
X698474Y35941D01*
X698434Y35816D01*
X698374Y35706D01*
X698294Y35606D01*
X698194Y35526D01*
X698084Y35466D01*
X697959Y35426D01*
X697834Y35416D01*
G37*
G36*
G01X726181D02*
X726056Y35426D01*
X725931Y35466D01*
X725821Y35526D01*
X725721Y35606D01*
X725641Y35706D01*
X725581Y35816D01*
X725541Y35941D01*
X725531Y36066D01*
Y38191D01*
X725501Y38221D01*
X725476Y38256D01*
X725446Y38291D01*
X725426Y38326D01*
X725401Y38361D01*
X725361Y38441D01*
X725316Y38561D01*
X725306Y38601D01*
X725296Y38646D01*
X725291Y38686D01*
X725281Y38731D01*
Y38901D01*
X725291Y38946D01*
X725296Y38986D01*
X725306Y39031D01*
X725316Y39071D01*
X725361Y39191D01*
X725401Y39271D01*
X725426Y39306D01*
X725446Y39341D01*
X725476Y39376D01*
X725501Y39411D01*
X725531Y39441D01*
Y41866D01*
X725541Y41991D01*
X725581Y42116D01*
X725641Y42226D01*
X725721Y42326D01*
X725821Y42406D01*
X725931Y42466D01*
X726056Y42506D01*
X726181Y42516D01*
X726306Y42506D01*
X726431Y42466D01*
X726541Y42406D01*
X726641Y42326D01*
X726721Y42226D01*
X726781Y42116D01*
X726821Y41991D01*
X726831Y41866D01*
Y39436D01*
X726861Y39406D01*
X726961Y39266D01*
X726981Y39226D01*
X726996Y39191D01*
X727016Y39151D01*
X727031Y39111D01*
X727041Y39071D01*
X727056Y39026D01*
X727061Y38986D01*
X727071Y38946D01*
X727076Y38901D01*
Y38861D01*
X727081Y38816D01*
X727076Y38771D01*
Y38731D01*
X727071Y38686D01*
X727061Y38646D01*
X727056Y38606D01*
X727041Y38561D01*
X727031Y38521D01*
X727016Y38481D01*
X726996Y38441D01*
X726981Y38406D01*
X726961Y38366D01*
X726861Y38226D01*
X726831Y38196D01*
Y36066D01*
X726821Y35941D01*
X726781Y35816D01*
X726721Y35706D01*
X726641Y35606D01*
X726541Y35526D01*
X726431Y35466D01*
X726306Y35426D01*
X726181Y35416D01*
G37*
G36*
G01X721456D02*
X721331Y35426D01*
X721206Y35466D01*
X721096Y35526D01*
X720996Y35606D01*
X720916Y35706D01*
X720856Y35816D01*
X720816Y35941D01*
X720806Y36066D01*
Y38191D01*
X720776Y38221D01*
X720751Y38256D01*
X720721Y38291D01*
X720701Y38326D01*
X720676Y38361D01*
X720636Y38441D01*
X720591Y38561D01*
X720581Y38601D01*
X720571Y38646D01*
X720566Y38686D01*
X720556Y38731D01*
Y38901D01*
X720566Y38946D01*
X720571Y38986D01*
X720581Y39031D01*
X720591Y39071D01*
X720636Y39191D01*
X720676Y39271D01*
X720701Y39306D01*
X720721Y39341D01*
X720751Y39376D01*
X720776Y39411D01*
X720806Y39441D01*
Y41866D01*
X720816Y41991D01*
X720856Y42116D01*
X720916Y42226D01*
X720996Y42326D01*
X721096Y42406D01*
X721206Y42466D01*
X721331Y42506D01*
X721456Y42516D01*
X721581Y42506D01*
X721706Y42466D01*
X721816Y42406D01*
X721916Y42326D01*
X721996Y42226D01*
X722056Y42116D01*
X722096Y41991D01*
X722106Y41866D01*
Y39436D01*
X722136Y39406D01*
X722236Y39266D01*
X722256Y39226D01*
X722271Y39191D01*
X722291Y39151D01*
X722306Y39111D01*
X722316Y39071D01*
X722331Y39026D01*
X722336Y38986D01*
X722346Y38946D01*
X722351Y38901D01*
Y38861D01*
X722356Y38816D01*
X722351Y38771D01*
Y38731D01*
X722346Y38686D01*
X722336Y38646D01*
X722331Y38606D01*
X722316Y38561D01*
X722306Y38521D01*
X722291Y38481D01*
X722271Y38441D01*
X722256Y38406D01*
X722236Y38366D01*
X722136Y38226D01*
X722106Y38196D01*
Y36066D01*
X722096Y35941D01*
X722056Y35816D01*
X721996Y35706D01*
X721916Y35606D01*
X721816Y35526D01*
X721706Y35466D01*
X721581Y35426D01*
X721456Y35416D01*
G37*
G36*
G01X716732D02*
X716607Y35426D01*
X716482Y35466D01*
X716372Y35526D01*
X716272Y35606D01*
X716192Y35706D01*
X716132Y35816D01*
X716092Y35941D01*
X716082Y36066D01*
Y38191D01*
X716052Y38221D01*
X716027Y38256D01*
X715997Y38291D01*
X715977Y38326D01*
X715952Y38361D01*
X715912Y38441D01*
X715867Y38561D01*
X715857Y38601D01*
X715847Y38646D01*
X715842Y38686D01*
X715832Y38731D01*
Y38901D01*
X715842Y38946D01*
X715847Y38986D01*
X715857Y39031D01*
X715867Y39071D01*
X715912Y39191D01*
X715952Y39271D01*
X715977Y39306D01*
X715997Y39341D01*
X716027Y39376D01*
X716052Y39411D01*
X716082Y39441D01*
Y41866D01*
X716092Y41991D01*
X716132Y42116D01*
X716192Y42226D01*
X716272Y42326D01*
X716372Y42406D01*
X716482Y42466D01*
X716607Y42506D01*
X716732Y42516D01*
X716857Y42506D01*
X716982Y42466D01*
X717092Y42406D01*
X717192Y42326D01*
X717272Y42226D01*
X717332Y42116D01*
X717372Y41991D01*
X717382Y41866D01*
Y39436D01*
X717412Y39406D01*
X717512Y39266D01*
X717532Y39226D01*
X717547Y39191D01*
X717567Y39151D01*
X717582Y39111D01*
X717592Y39071D01*
X717607Y39026D01*
X717612Y38986D01*
X717622Y38946D01*
X717627Y38901D01*
Y38861D01*
X717632Y38816D01*
X717627Y38771D01*
Y38731D01*
X717622Y38686D01*
X717612Y38646D01*
X717607Y38606D01*
X717592Y38561D01*
X717582Y38521D01*
X717567Y38481D01*
X717547Y38441D01*
X717532Y38406D01*
X717512Y38366D01*
X717412Y38226D01*
X717382Y38196D01*
Y36066D01*
X717372Y35941D01*
X717332Y35816D01*
X717272Y35706D01*
X717192Y35606D01*
X717092Y35526D01*
X716982Y35466D01*
X716857Y35426D01*
X716732Y35416D01*
G37*
G36*
G01X712008D02*
X711883Y35426D01*
X711758Y35466D01*
X711648Y35526D01*
X711548Y35606D01*
X711468Y35706D01*
X711408Y35816D01*
X711368Y35941D01*
X711358Y36066D01*
Y38191D01*
X711328Y38221D01*
X711303Y38256D01*
X711273Y38291D01*
X711253Y38326D01*
X711228Y38361D01*
X711188Y38441D01*
X711143Y38561D01*
X711133Y38601D01*
X711123Y38646D01*
X711118Y38686D01*
X711108Y38731D01*
Y38901D01*
X711118Y38946D01*
X711123Y38986D01*
X711133Y39031D01*
X711143Y39071D01*
X711188Y39191D01*
X711228Y39271D01*
X711253Y39306D01*
X711273Y39341D01*
X711303Y39376D01*
X711328Y39411D01*
X711358Y39441D01*
Y41866D01*
X711368Y41991D01*
X711408Y42116D01*
X711468Y42226D01*
X711548Y42326D01*
X711648Y42406D01*
X711758Y42466D01*
X711883Y42506D01*
X712008Y42516D01*
X712133Y42506D01*
X712258Y42466D01*
X712368Y42406D01*
X712468Y42326D01*
X712548Y42226D01*
X712608Y42116D01*
X712648Y41991D01*
X712658Y41866D01*
Y39436D01*
X712688Y39406D01*
X712788Y39266D01*
X712808Y39226D01*
X712823Y39191D01*
X712843Y39151D01*
X712858Y39111D01*
X712868Y39071D01*
X712883Y39026D01*
X712888Y38986D01*
X712898Y38946D01*
X712903Y38901D01*
Y38861D01*
X712908Y38816D01*
X712903Y38771D01*
Y38731D01*
X712898Y38686D01*
X712888Y38646D01*
X712883Y38606D01*
X712868Y38561D01*
X712858Y38521D01*
X712843Y38481D01*
X712823Y38441D01*
X712808Y38406D01*
X712788Y38366D01*
X712688Y38226D01*
X712658Y38196D01*
Y36066D01*
X712648Y35941D01*
X712608Y35816D01*
X712548Y35706D01*
X712468Y35606D01*
X712368Y35526D01*
X712258Y35466D01*
X712133Y35426D01*
X712008Y35416D01*
G37*
G36*
G01X740354D02*
X740229Y35426D01*
X740104Y35466D01*
X739994Y35526D01*
X739894Y35606D01*
X739814Y35706D01*
X739754Y35816D01*
X739714Y35941D01*
X739704Y36066D01*
Y38191D01*
X739674Y38221D01*
X739649Y38256D01*
X739619Y38291D01*
X739599Y38326D01*
X739574Y38361D01*
X739534Y38441D01*
X739489Y38561D01*
X739479Y38601D01*
X739469Y38646D01*
X739464Y38686D01*
X739454Y38731D01*
Y38901D01*
X739464Y38946D01*
X739469Y38986D01*
X739479Y39031D01*
X739489Y39071D01*
X739534Y39191D01*
X739574Y39271D01*
X739599Y39306D01*
X739619Y39341D01*
X739649Y39376D01*
X739674Y39411D01*
X739704Y39441D01*
Y41866D01*
X739714Y41991D01*
X739754Y42116D01*
X739814Y42226D01*
X739894Y42326D01*
X739994Y42406D01*
X740104Y42466D01*
X740229Y42506D01*
X740354Y42516D01*
X740479Y42506D01*
X740604Y42466D01*
X740714Y42406D01*
X740814Y42326D01*
X740894Y42226D01*
X740954Y42116D01*
X740994Y41991D01*
X741004Y41866D01*
Y39436D01*
X741034Y39406D01*
X741134Y39266D01*
X741154Y39226D01*
X741169Y39191D01*
X741189Y39151D01*
X741204Y39111D01*
X741214Y39071D01*
X741229Y39026D01*
X741234Y38986D01*
X741244Y38946D01*
X741249Y38901D01*
Y38861D01*
X741254Y38816D01*
X741249Y38771D01*
Y38731D01*
X741244Y38686D01*
X741234Y38646D01*
X741229Y38606D01*
X741214Y38561D01*
X741204Y38521D01*
X741189Y38481D01*
X741169Y38441D01*
X741154Y38406D01*
X741134Y38366D01*
X741034Y38226D01*
X741004Y38196D01*
Y36066D01*
X740994Y35941D01*
X740954Y35816D01*
X740894Y35706D01*
X740814Y35606D01*
X740714Y35526D01*
X740604Y35466D01*
X740479Y35426D01*
X740354Y35416D01*
G37*
G36*
G01X735630D02*
X735505Y35426D01*
X735380Y35466D01*
X735270Y35526D01*
X735170Y35606D01*
X735090Y35706D01*
X735030Y35816D01*
X734990Y35941D01*
X734980Y36066D01*
Y38191D01*
X734950Y38221D01*
X734925Y38256D01*
X734895Y38291D01*
X734875Y38326D01*
X734850Y38361D01*
X734810Y38441D01*
X734765Y38561D01*
X734755Y38601D01*
X734745Y38646D01*
X734740Y38686D01*
X734730Y38731D01*
Y38901D01*
X734740Y38946D01*
X734745Y38986D01*
X734755Y39031D01*
X734765Y39071D01*
X734810Y39191D01*
X734850Y39271D01*
X734875Y39306D01*
X734895Y39341D01*
X734925Y39376D01*
X734950Y39411D01*
X734980Y39441D01*
Y41866D01*
X734990Y41991D01*
X735030Y42116D01*
X735090Y42226D01*
X735170Y42326D01*
X735270Y42406D01*
X735380Y42466D01*
X735505Y42506D01*
X735630Y42516D01*
X735755Y42506D01*
X735880Y42466D01*
X735990Y42406D01*
X736090Y42326D01*
X736170Y42226D01*
X736230Y42116D01*
X736270Y41991D01*
X736280Y41866D01*
Y39436D01*
X736310Y39406D01*
X736410Y39266D01*
X736430Y39226D01*
X736445Y39191D01*
X736465Y39151D01*
X736480Y39111D01*
X736490Y39071D01*
X736505Y39026D01*
X736510Y38986D01*
X736520Y38946D01*
X736525Y38901D01*
Y38861D01*
X736530Y38816D01*
X736525Y38771D01*
Y38731D01*
X736520Y38686D01*
X736510Y38646D01*
X736505Y38606D01*
X736490Y38561D01*
X736480Y38521D01*
X736465Y38481D01*
X736445Y38441D01*
X736430Y38406D01*
X736410Y38366D01*
X736310Y38226D01*
X736280Y38196D01*
Y36066D01*
X736270Y35941D01*
X736230Y35816D01*
X736170Y35706D01*
X736090Y35606D01*
X735990Y35526D01*
X735880Y35466D01*
X735755Y35426D01*
X735630Y35416D01*
G37*
G36*
G01X730905D02*
X730780Y35426D01*
X730655Y35466D01*
X730545Y35526D01*
X730445Y35606D01*
X730365Y35706D01*
X730305Y35816D01*
X730265Y35941D01*
X730255Y36066D01*
Y38191D01*
X730225Y38221D01*
X730200Y38256D01*
X730170Y38291D01*
X730150Y38326D01*
X730125Y38361D01*
X730085Y38441D01*
X730040Y38561D01*
X730030Y38601D01*
X730020Y38646D01*
X730015Y38686D01*
X730005Y38731D01*
Y38901D01*
X730015Y38946D01*
X730020Y38986D01*
X730030Y39031D01*
X730040Y39071D01*
X730085Y39191D01*
X730125Y39271D01*
X730150Y39306D01*
X730170Y39341D01*
X730200Y39376D01*
X730225Y39411D01*
X730255Y39441D01*
Y41866D01*
X730265Y41991D01*
X730305Y42116D01*
X730365Y42226D01*
X730445Y42326D01*
X730545Y42406D01*
X730655Y42466D01*
X730780Y42506D01*
X730905Y42516D01*
X731030Y42506D01*
X731155Y42466D01*
X731265Y42406D01*
X731365Y42326D01*
X731445Y42226D01*
X731505Y42116D01*
X731545Y41991D01*
X731555Y41866D01*
Y39436D01*
X731585Y39406D01*
X731685Y39266D01*
X731705Y39226D01*
X731720Y39191D01*
X731740Y39151D01*
X731755Y39111D01*
X731765Y39071D01*
X731780Y39026D01*
X731785Y38986D01*
X731795Y38946D01*
X731800Y38901D01*
Y38861D01*
X731805Y38816D01*
X731800Y38771D01*
Y38731D01*
X731795Y38686D01*
X731785Y38646D01*
X731780Y38606D01*
X731765Y38561D01*
X731755Y38521D01*
X731740Y38481D01*
X731720Y38441D01*
X731705Y38406D01*
X731685Y38366D01*
X731585Y38226D01*
X731555Y38196D01*
Y36066D01*
X731545Y35941D01*
X731505Y35816D01*
X731445Y35706D01*
X731365Y35606D01*
X731265Y35526D01*
X731155Y35466D01*
X731030Y35426D01*
X730905Y35416D01*
G37*
G36*
G01X754527D02*
X754402Y35426D01*
X754277Y35466D01*
X754167Y35526D01*
X754067Y35606D01*
X753987Y35706D01*
X753927Y35816D01*
X753887Y35941D01*
X753877Y36066D01*
Y38191D01*
X753847Y38221D01*
X753822Y38256D01*
X753792Y38291D01*
X753772Y38326D01*
X753747Y38361D01*
X753707Y38441D01*
X753662Y38561D01*
X753652Y38601D01*
X753642Y38646D01*
X753637Y38686D01*
X753627Y38731D01*
Y38901D01*
X753637Y38946D01*
X753642Y38986D01*
X753652Y39031D01*
X753662Y39071D01*
X753707Y39191D01*
X753747Y39271D01*
X753772Y39306D01*
X753792Y39341D01*
X753822Y39376D01*
X753847Y39411D01*
X753877Y39441D01*
Y41866D01*
X753887Y41991D01*
X753927Y42116D01*
X753987Y42226D01*
X754067Y42326D01*
X754167Y42406D01*
X754277Y42466D01*
X754402Y42506D01*
X754527Y42516D01*
X754652Y42506D01*
X754777Y42466D01*
X754887Y42406D01*
X754987Y42326D01*
X755067Y42226D01*
X755127Y42116D01*
X755167Y41991D01*
X755177Y41866D01*
Y39436D01*
X755207Y39406D01*
X755307Y39266D01*
X755327Y39226D01*
X755342Y39191D01*
X755362Y39151D01*
X755377Y39111D01*
X755387Y39071D01*
X755402Y39026D01*
X755407Y38986D01*
X755417Y38946D01*
X755422Y38901D01*
Y38861D01*
X755427Y38816D01*
X755422Y38771D01*
Y38731D01*
X755417Y38686D01*
X755407Y38646D01*
X755402Y38606D01*
X755387Y38561D01*
X755377Y38521D01*
X755362Y38481D01*
X755342Y38441D01*
X755327Y38406D01*
X755307Y38366D01*
X755207Y38226D01*
X755177Y38196D01*
Y36066D01*
X755167Y35941D01*
X755127Y35816D01*
X755067Y35706D01*
X754987Y35606D01*
X754887Y35526D01*
X754777Y35466D01*
X754652Y35426D01*
X754527Y35416D01*
G37*
G36*
G01X749803D02*
X749678Y35426D01*
X749553Y35466D01*
X749443Y35526D01*
X749343Y35606D01*
X749263Y35706D01*
X749203Y35816D01*
X749163Y35941D01*
X749153Y36066D01*
Y38191D01*
X749123Y38221D01*
X749098Y38256D01*
X749068Y38291D01*
X749048Y38326D01*
X749023Y38361D01*
X748983Y38441D01*
X748938Y38561D01*
X748928Y38601D01*
X748918Y38646D01*
X748913Y38686D01*
X748903Y38731D01*
Y38901D01*
X748913Y38946D01*
X748918Y38986D01*
X748928Y39031D01*
X748938Y39071D01*
X748983Y39191D01*
X749023Y39271D01*
X749048Y39306D01*
X749068Y39341D01*
X749098Y39376D01*
X749123Y39411D01*
X749153Y39441D01*
Y41866D01*
X749163Y41991D01*
X749203Y42116D01*
X749263Y42226D01*
X749343Y42326D01*
X749443Y42406D01*
X749553Y42466D01*
X749678Y42506D01*
X749803Y42516D01*
X749928Y42506D01*
X750053Y42466D01*
X750163Y42406D01*
X750263Y42326D01*
X750343Y42226D01*
X750403Y42116D01*
X750443Y41991D01*
X750453Y41866D01*
Y39436D01*
X750483Y39406D01*
X750583Y39266D01*
X750603Y39226D01*
X750618Y39191D01*
X750638Y39151D01*
X750653Y39111D01*
X750663Y39071D01*
X750678Y39026D01*
X750683Y38986D01*
X750693Y38946D01*
X750698Y38901D01*
Y38861D01*
X750703Y38816D01*
X750698Y38771D01*
Y38731D01*
X750693Y38686D01*
X750683Y38646D01*
X750678Y38606D01*
X750663Y38561D01*
X750653Y38521D01*
X750638Y38481D01*
X750618Y38441D01*
X750603Y38406D01*
X750583Y38366D01*
X750483Y38226D01*
X750453Y38196D01*
Y36066D01*
X750443Y35941D01*
X750403Y35816D01*
X750343Y35706D01*
X750263Y35606D01*
X750163Y35526D01*
X750053Y35466D01*
X749928Y35426D01*
X749803Y35416D01*
G37*
G36*
G01X745078D02*
X744953Y35426D01*
X744828Y35466D01*
X744718Y35526D01*
X744618Y35606D01*
X744538Y35706D01*
X744478Y35816D01*
X744438Y35941D01*
X744428Y36066D01*
Y38191D01*
X744398Y38221D01*
X744373Y38256D01*
X744343Y38291D01*
X744323Y38326D01*
X744298Y38361D01*
X744258Y38441D01*
X744213Y38561D01*
X744203Y38601D01*
X744193Y38646D01*
X744188Y38686D01*
X744178Y38731D01*
Y38901D01*
X744188Y38946D01*
X744193Y38986D01*
X744203Y39031D01*
X744213Y39071D01*
X744258Y39191D01*
X744298Y39271D01*
X744323Y39306D01*
X744343Y39341D01*
X744373Y39376D01*
X744398Y39411D01*
X744428Y39441D01*
Y41866D01*
X744438Y41991D01*
X744478Y42116D01*
X744538Y42226D01*
X744618Y42326D01*
X744718Y42406D01*
X744828Y42466D01*
X744953Y42506D01*
X745078Y42516D01*
X745203Y42506D01*
X745328Y42466D01*
X745438Y42406D01*
X745538Y42326D01*
X745618Y42226D01*
X745678Y42116D01*
X745718Y41991D01*
X745728Y41866D01*
Y39436D01*
X745758Y39406D01*
X745858Y39266D01*
X745878Y39226D01*
X745893Y39191D01*
X745913Y39151D01*
X745928Y39111D01*
X745938Y39071D01*
X745953Y39026D01*
X745958Y38986D01*
X745968Y38946D01*
X745973Y38901D01*
Y38861D01*
X745978Y38816D01*
X745973Y38771D01*
Y38731D01*
X745968Y38686D01*
X745958Y38646D01*
X745953Y38606D01*
X745938Y38561D01*
X745928Y38521D01*
X745913Y38481D01*
X745893Y38441D01*
X745878Y38406D01*
X745858Y38366D01*
X745758Y38226D01*
X745728Y38196D01*
Y36066D01*
X745718Y35941D01*
X745678Y35816D01*
X745618Y35706D01*
X745538Y35606D01*
X745438Y35526D01*
X745328Y35466D01*
X745203Y35426D01*
X745078Y35416D01*
G37*
G54D99*
X562000Y74931D03*
Y80069D03*
M02*
